(lib_symbols
	(symbol "Amphenol_RJE361882415_1"
			(exclude_from_sim no)
			(in_bom yes)
			(on_board yes)
			(property "Reference" "J"
				(at 39.37 -2.54 0)
				(effects
					(font
						(size 1.27 1.27)
						(thickness 0.15)
					)
					(justify left bottom)
				)
			)
			(property "Value" "Amphenol_RJE361882415"
				(at 39.37 -10.16 0)
				(effects
					(font
						(size 1.27 1.27)
						(thickness 0.15)
					)
					(justify left bottom)
					(hide yes)
				)
			)
			(property "Footprint" "antmicro-footprints:RJ45_RJE361882415"
				(at 39.37 -12.7 0)
				(effects
					(font
						(size 1.27 1.27)
						(thickness 0.15)
					)
					(justify left bottom)
					(hide yes)
				)
			)
			(property "Datasheet" "https://cdn.amphenol-cs.com/media/wysiwyg/files/drawing/p-rje36-188-2xx5.pdf"
				(at 39.37 -15.24 0)
				(effects
					(font
						(size 1.27 1.27)
						(thickness 0.15)
					)
					(justify left bottom)
					(hide yes)
				)
			)
			(property "Description" "Modular Connectors / Ethernet Connectors MODULAR JACK"
				(at 0 0 0)
				(effects
					(font
						(size 1.27 1.27)
					)
					(hide yes)
				)
			)
			(property "MPN" "RJE361882415"
				(at 39.37 -5.08 0)
				(effects
					(font
						(size 1.27 1.27)
						(thickness 0.15)
					)
					(justify left bottom)
				)
			)
			(property "Manufacturer" "Amphenol"
				(at 39.37 -17.78 0)
				(effects
					(font
						(size 1.27 1.27)
						(thickness 0.15)
					)
					(justify left bottom)
					(hide yes)
				)
			)
			(property "Author" "Antmicro"
				(at 39.37 -20.32 0)
				(effects
					(font
						(size 1.27 1.27)
						(thickness 0.15)
					)
					(justify left bottom)
					(hide yes)
				)
			)
			(property "License" "Apache-2.0"
				(at 39.37 -22.86 0)
				(effects
					(font
						(size 1.27 1.27)
						(thickness 0.15)
					)
					(justify left bottom)
					(hide yes)
				)
			)
			(property "ki_locked" ""
				(at 0 0 0)
				(effects
					(font
						(size 1.27 1.27)
					)
				)
			)
			(property "ki_keywords" "THT, CONNECTOR"
				(at 0 0 0)
				(effects
					(font
						(size 1.27 1.27)
					)
					(hide yes)
				)
			)
			(symbol "Amphenol_RJE361882415_1_1_1"
				(rectangle
					(start 3.81 2.54)
					(end 21.59 -25.4)
					(stroke
						(width 0.254)
						(type default)
					)
					(fill
						(type background)
					)
				)
				(rectangle
					(start 7.62 -4.445)
					(end 19.05 -18.415)
					(stroke
						(width 0.254)
						(type default)
					)
					(fill
						(type background)
					)
				)
				(polyline
					(pts
						(xy 8.89 -5.715) (xy 15.24 -5.715)
					)
					(stroke
						(width 0.254)
						(type default)
					)
					(fill
						(type background)
					)
				)
				(polyline
					(pts
						(xy 8.89 -17.145) (xy 8.89 -5.715)
					)
					(stroke
						(width 0.254)
						(type default)
					)
					(fill
						(type background)
					)
				)
				(polyline
					(pts
						(xy 15.24 -5.715) (xy 15.24 -6.985)
					)
					(stroke
						(width 0.254)
						(type default)
					)
					(fill
						(type background)
					)
				)
				(polyline
					(pts
						(xy 15.24 -6.985) (xy 16.51 -6.985)
					)
					(stroke
						(width 0.254)
						(type default)
					)
					(fill
						(type background)
					)
				)
				(polyline
					(pts
						(xy 15.24 -15.875) (xy 16.51 -15.875)
					)
					(stroke
						(width 0.254)
						(type default)
					)
					(fill
						(type background)
					)
				)
				(polyline
					(pts
						(xy 15.24 -17.145) (xy 8.89 -17.145)
					)
					(stroke
						(width 0.254)
						(type default)
					)
					(fill
						(type background)
					)
				)
				(polyline
					(pts
						(xy 15.24 -17.145) (xy 15.24 -15.875)
					)
					(stroke
						(width 0.254)
						(type default)
					)
					(fill
						(type background)
					)
				)
				(polyline
					(pts
						(xy 16.51 -6.985) (xy 16.51 -8.255)
					)
					(stroke
						(width 0.254)
						(type default)
					)
					(fill
						(type background)
					)
				)
				(polyline
					(pts
						(xy 16.51 -8.255) (xy 17.78 -8.255)
					)
					(stroke
						(width 0.254)
						(type default)
					)
					(fill
						(type background)
					)
				)
				(polyline
					(pts
						(xy 16.51 -14.605) (xy 17.78 -14.605)
					)
					(stroke
						(width 0.254)
						(type default)
					)
					(fill
						(type background)
					)
				)
				(polyline
					(pts
						(xy 16.51 -15.875) (xy 16.51 -14.605)
					)
					(stroke
						(width 0.254)
						(type default)
					)
					(fill
						(type background)
					)
				)
				(polyline
					(pts
						(xy 17.78 -8.255) (xy 17.78 -14.605)
					)
					(stroke
						(width 0.254)
						(type default)
					)
					(fill
						(type background)
					)
				)
				(pin bidirectional line
					(at 0 0 0)
					(length 3.81)
					(name "1"
						(effects
							(font
								(size 1.27 1.27)
							)
						)
					)
					(number "1"
						(effects
							(font
								(size 1.27 1.27)
							)
						)
					)
				)
				(pin bidirectional line
					(at 0 -2.54 0)
					(length 3.81)
					(name "2"
						(effects
							(font
								(size 1.27 1.27)
							)
						)
					)
					(number "2"
						(effects
							(font
								(size 1.27 1.27)
							)
						)
					)
				)
				(pin bidirectional line
					(at 0 -5.08 0)
					(length 3.81)
					(name "3"
						(effects
							(font
								(size 1.27 1.27)
							)
						)
					)
					(number "3"
						(effects
							(font
								(size 1.27 1.27)
							)
						)
					)
				)
				(pin bidirectional line
					(at 0 -7.62 0)
					(length 3.81)
					(name "4"
						(effects
							(font
								(size 1.27 1.27)
							)
						)
					)
					(number "4"
						(effects
							(font
								(size 1.27 1.27)
							)
						)
					)
				)
				(pin bidirectional line
					(at 0 -10.16 0)
					(length 3.81)
					(name "5"
						(effects
							(font
								(size 1.27 1.27)
							)
						)
					)
					(number "5"
						(effects
							(font
								(size 1.27 1.27)
							)
						)
					)
				)
				(pin bidirectional line
					(at 0 -12.7 0)
					(length 3.81)
					(name "6"
						(effects
							(font
								(size 1.27 1.27)
							)
						)
					)
					(number "6"
						(effects
							(font
								(size 1.27 1.27)
							)
						)
					)
				)
				(pin bidirectional line
					(at 0 -15.24 0)
					(length 3.81)
					(name "7"
						(effects
							(font
								(size 1.27 1.27)
							)
						)
					)
					(number "7"
						(effects
							(font
								(size 1.27 1.27)
							)
						)
					)
				)
				(pin bidirectional line
					(at 0 -17.78 0)
					(length 3.81)
					(name "8"
						(effects
							(font
								(size 1.27 1.27)
							)
						)
					)
					(number "8"
						(effects
							(font
								(size 1.27 1.27)
							)
						)
					)
				)
				(pin bidirectional line
					(at 0 -22.86 0)
					(length 3.81)
					(name "MP"
						(effects
							(font
								(size 1.27 1.27)
							)
						)
					)
					(number "MP"
						(effects
							(font
								(size 1.27 1.27)
							)
						)
					)
				)
				(pin passive line
					(at 25.4 0 180)
					(length 3.81)
					(name "LED_D1"
						(effects
							(font
								(size 1.27 1.27)
							)
						)
					)
					(number "D1"
						(effects
							(font
								(size 1.27 1.27)
							)
						)
					)
				)
				(pin passive line
					(at 25.4 -2.54 180)
					(length 3.81)
					(name "LED_D2"
						(effects
							(font
								(size 1.27 1.27)
							)
						)
					)
					(number "D2"
						(effects
							(font
								(size 1.27 1.27)
							)
						)
					)
				)
				(pin passive line
					(at 25.4 -20.32 180)
					(length 3.81)
					(name "LED_D3"
						(effects
							(font
								(size 1.27 1.27)
							)
						)
					)
					(number "D3"
						(effects
							(font
								(size 1.27 1.27)
							)
						)
					)
				)
				(pin passive line
					(at 25.4 -22.86 180)
					(length 3.81)
					(name "LED_D4"
						(effects
							(font
								(size 1.27 1.27)
							)
						)
					)
					(number "D4"
						(effects
							(font
								(size 1.27 1.27)
							)
						)
					)
				)
			)
			(symbol "Amphenol_RJE361882415_1_2_1"
				(rectangle
					(start 3.81 2.54)
					(end 20.32 -24.13)
					(stroke
						(width 0.254)
						(type default)
					)
					(fill
						(type background)
					)
				)
				(circle
					(center 12.065 -5.08)
					(radius 0.381)
					(stroke
						(width 0.254)
						(type default)
					)
					(fill
						(type outline)
					)
				)
				(polyline
					(pts
						(xy 12.7 -3.81) (xy 13.97 -3.81) (xy 13.335 -2.54) (xy 12.7 -3.81)
					)
					(stroke
						(width 0.254)
						(type default)
					)
					(fill
						(type outline)
					)
				)
				(polyline
					(pts
						(xy 13.335 -6.35) (xy 13.335 -3.81)
					)
					(stroke
						(width 0.254)
						(type default)
					)
					(fill
						(type background)
					)
				)
				(polyline
					(pts
						(xy 13.335 -6.985) (xy 13.335 -6.35) (xy 14.605 -5.715) (xy 14.605 -4.445)
					)
					(stroke
						(width 0.254)
						(type default)
					)
					(fill
						(type background)
					)
				)
				(polyline
					(pts
						(xy 13.335 -7.62) (xy 13.335 -6.985) (xy 12.065 -5.715) (xy 12.065 -5.08)
					)
					(stroke
						(width 0.254)
						(type default)
					)
					(fill
						(type background)
					)
				)
				(circle
					(center 13.335 -8.255)
					(radius 0.635)
					(stroke
						(width 0.254)
						(type default)
					)
					(fill
						(type outline)
					)
				)
				(rectangle
					(start 14.224 -4.191)
					(end 14.986 -4.953)
					(stroke
						(width 0.254)
						(type default)
					)
					(fill
						(type outline)
					)
				)
				(rectangle
					(start 16.256 -3.81)
					(end 18.034 -8.382)
					(stroke
						(width 0.254)
						(type default)
					)
					(fill
						(type background)
					)
				)
				(rectangle
					(start 17.018 -4.318)
					(end 17.653 -7.874)
					(stroke
						(width 0.254)
						(type default)
					)
					(fill
						(type outline)
					)
				)
				(text "PORT 1"
					(at 12.7 0 0)
					(effects
						(font
							(size 1.27 1.27)
							(thickness 0.15)
						)
						(justify left bottom)
					)
				)
				(pin passive line
					(at 0 0 0)
					(length 3.81)
					(name "VBUS"
						(effects
							(font
								(size 1.27 1.27)
							)
						)
					)
					(number "U1"
						(effects
							(font
								(size 1.27 1.27)
							)
						)
					)
				)
				(pin bidirectional line
					(at 0 -3.81 0)
					(length 3.81)
					(name "D+"
						(effects
							(font
								(size 1.27 1.27)
							)
						)
					)
					(number "U3"
						(effects
							(font
								(size 1.27 1.27)
							)
						)
					)
				)
				(pin bidirectional line
					(at 0 -6.35 0)
					(length 3.81)
					(name "D-"
						(effects
							(font
								(size 1.27 1.27)
							)
						)
					)
					(number "U2"
						(effects
							(font
								(size 1.27 1.27)
							)
						)
					)
				)
				(pin bidirectional line
					(at 0 -8.89 0)
					(length 3.81)
					(name "SSRX+"
						(effects
							(font
								(size 1.27 1.27)
							)
						)
					)
					(number "U8"
						(effects
							(font
								(size 1.27 1.27)
							)
						)
					)
				)
				(pin bidirectional line
					(at 0 -11.43 0)
					(length 3.81)
					(name "SSRX-"
						(effects
							(font
								(size 1.27 1.27)
							)
						)
					)
					(number "U9"
						(effects
							(font
								(size 1.27 1.27)
							)
						)
					)
				)
				(pin bidirectional line
					(at 0 -13.97 0)
					(length 3.81)
					(name "SSTX+"
						(effects
							(font
								(size 1.27 1.27)
							)
						)
					)
					(number "U5"
						(effects
							(font
								(size 1.27 1.27)
							)
						)
					)
				)
				(pin bidirectional line
					(at 0 -16.51 0)
					(length 3.81)
					(name "SSTX-"
						(effects
							(font
								(size 1.27 1.27)
							)
						)
					)
					(number "U6"
						(effects
							(font
								(size 1.27 1.27)
							)
						)
					)
				)
				(pin power_in line
					(at 0 -19.05 0)
					(length 3.81)
					(name "GND"
						(effects
							(font
								(size 1.27 1.27)
							)
						)
					)
					(number "U4"
						(effects
							(font
								(size 1.27 1.27)
							)
						)
					)
				)
				(pin power_in line
					(at 0 -21.59 0)
					(length 3.81)
					(name "GND_DRAIN"
						(effects
							(font
								(size 1.27 1.27)
							)
						)
					)
					(number "U7"
						(effects
							(font
								(size 1.27 1.27)
							)
						)
					)
				)
			)
			(symbol "Amphenol_RJE361882415_1_3_1"
				(rectangle
					(start 3.81 2.54)
					(end 20.32 -24.13)
					(stroke
						(width 0.254)
						(type default)
					)
					(fill
						(type background)
					)
				)
				(circle
					(center 12.065 -5.08)
					(radius 0.381)
					(stroke
						(width 0.254)
						(type default)
					)
					(fill
						(type outline)
					)
				)
				(polyline
					(pts
						(xy 12.7 -3.81) (xy 13.97 -3.81) (xy 13.335 -2.54) (xy 12.7 -3.81)
					)
					(stroke
						(width 0.254)
						(type default)
					)
					(fill
						(type outline)
					)
				)
				(polyline
					(pts
						(xy 13.335 -6.35) (xy 13.335 -3.81)
					)
					(stroke
						(width 0.254)
						(type default)
					)
					(fill
						(type background)
					)
				)
				(polyline
					(pts
						(xy 13.335 -6.985) (xy 13.335 -6.35) (xy 14.605 -5.715) (xy 14.605 -4.445)
					)
					(stroke
						(width 0.254)
						(type default)
					)
					(fill
						(type background)
					)
				)
				(polyline
					(pts
						(xy 13.335 -7.62) (xy 13.335 -6.985) (xy 12.065 -5.715) (xy 12.065 -5.08)
					)
					(stroke
						(width 0.254)
						(type default)
					)
					(fill
						(type background)
					)
				)
				(circle
					(center 13.335 -8.255)
					(radius 0.635)
					(stroke
						(width 0.254)
						(type default)
					)
					(fill
						(type outline)
					)
				)
				(rectangle
					(start 14.224 -4.191)
					(end 14.986 -4.953)
					(stroke
						(width 0.254)
						(type default)
					)
					(fill
						(type outline)
					)
				)
				(rectangle
					(start 16.256 -3.81)
					(end 18.034 -8.382)
					(stroke
						(width 0.254)
						(type default)
					)
					(fill
						(type background)
					)
				)
				(rectangle
					(start 17.018 -4.318)
					(end 17.653 -7.874)
					(stroke
						(width 0.254)
						(type default)
					)
					(fill
						(type outline)
					)
				)
				(text "PORT 2"
					(at 12.7 0 0)
					(effects
						(font
							(size 1.27 1.27)
							(thickness 0.15)
						)
						(justify left bottom)
					)
				)
				(pin passive line
					(at 0 0 0)
					(length 3.81)
					(name "VBUS"
						(effects
							(font
								(size 1.27 1.27)
							)
						)
					)
					(number "U10"
						(effects
							(font
								(size 1.27 1.27)
							)
						)
					)
				)
				(pin bidirectional line
					(at 0 -3.81 0)
					(length 3.81)
					(name "D+"
						(effects
							(font
								(size 1.27 1.27)
							)
						)
					)
					(number "U12"
						(effects
							(font
								(size 1.27 1.27)
							)
						)
					)
				)
				(pin bidirectional line
					(at 0 -6.35 0)
					(length 3.81)
					(name "D-"
						(effects
							(font
								(size 1.27 1.27)
							)
						)
					)
					(number "U11"
						(effects
							(font
								(size 1.27 1.27)
							)
						)
					)
				)
				(pin bidirectional line
					(at 0 -8.89 0)
					(length 3.81)
					(name "SSRX+"
						(effects
							(font
								(size 1.27 1.27)
							)
						)
					)
					(number "U17"
						(effects
							(font
								(size 1.27 1.27)
							)
						)
					)
				)
				(pin bidirectional line
					(at 0 -11.43 0)
					(length 3.81)
					(name "SSRX-"
						(effects
							(font
								(size 1.27 1.27)
							)
						)
					)
					(number "U18"
						(effects
							(font
								(size 1.27 1.27)
							)
						)
					)
				)
				(pin bidirectional line
					(at 0 -13.97 0)
					(length 3.81)
					(name "SSTX+"
						(effects
							(font
								(size 1.27 1.27)
							)
						)
					)
					(number "U14"
						(effects
							(font
								(size 1.27 1.27)
							)
						)
					)
				)
				(pin bidirectional line
					(at 0 -16.51 0)
					(length 3.81)
					(name "SSTX-"
						(effects
							(font
								(size 1.27 1.27)
							)
						)
					)
					(number "U15"
						(effects
							(font
								(size 1.27 1.27)
							)
						)
					)
				)
				(pin power_in line
					(at 0 -19.05 0)
					(length 3.81)
					(name "GND"
						(effects
							(font
								(size 1.27 1.27)
							)
						)
					)
					(number "U13"
						(effects
							(font
								(size 1.27 1.27)
							)
						)
					)
				)
				(pin power_in line
					(at 0 -21.59 0)
					(length 3.81)
					(name "GND_DRAIN"
						(effects
							(font
								(size 1.27 1.27)
							)
						)
					)
					(number "U16"
						(effects
							(font
								(size 1.27 1.27)
							)
						)
					)
				)
			)
		)
	(symbol "Amphenol_RJE361882415_2"
			(exclude_from_sim no)
			(in_bom yes)
			(on_board yes)
			(property "Reference" "J"
				(at 39.37 -2.54 0)
				(effects
					(font
						(size 1.27 1.27)
						(thickness 0.15)
					)
					(justify left bottom)
				)
			)
			(property "Value" "Amphenol_RJE361882415"
				(at 39.37 -10.16 0)
				(effects
					(font
						(size 1.27 1.27)
						(thickness 0.15)
					)
					(justify left bottom)
					(hide yes)
				)
			)
			(property "Footprint" "antmicro-footprints:RJ45_RJE361882415"
				(at 39.37 -12.7 0)
				(effects
					(font
						(size 1.27 1.27)
						(thickness 0.15)
					)
					(justify left bottom)
					(hide yes)
				)
			)
			(property "Datasheet" "https://cdn.amphenol-cs.com/media/wysiwyg/files/drawing/p-rje36-188-2xx5.pdf"
				(at 39.37 -15.24 0)
				(effects
					(font
						(size 1.27 1.27)
						(thickness 0.15)
					)
					(justify left bottom)
					(hide yes)
				)
			)
			(property "Description" "Modular Connectors / Ethernet Connectors MODULAR JACK"
				(at 0 0 0)
				(effects
					(font
						(size 1.27 1.27)
					)
					(hide yes)
				)
			)
			(property "MPN" "RJE361882415"
				(at 39.37 -5.08 0)
				(effects
					(font
						(size 1.27 1.27)
						(thickness 0.15)
					)
					(justify left bottom)
				)
			)
			(property "Manufacturer" "Amphenol"
				(at 39.37 -17.78 0)
				(effects
					(font
						(size 1.27 1.27)
						(thickness 0.15)
					)
					(justify left bottom)
					(hide yes)
				)
			)
			(property "Author" "Antmicro"
				(at 39.37 -20.32 0)
				(effects
					(font
						(size 1.27 1.27)
						(thickness 0.15)
					)
					(justify left bottom)
					(hide yes)
				)
			)
			(property "License" "Apache-2.0"
				(at 39.37 -22.86 0)
				(effects
					(font
						(size 1.27 1.27)
						(thickness 0.15)
					)
					(justify left bottom)
					(hide yes)
				)
			)
			(property "ki_locked" ""
				(at 0 0 0)
				(effects
					(font
						(size 1.27 1.27)
					)
				)
			)
			(property "ki_keywords" "THT, CONNECTOR"
				(at 0 0 0)
				(effects
					(font
						(size 1.27 1.27)
					)
					(hide yes)
				)
			)
			(symbol "Amphenol_RJE361882415_2_1_1"
				(rectangle
					(start 3.81 2.54)
					(end 21.59 -25.4)
					(stroke
						(width 0.254)
						(type default)
					)
					(fill
						(type background)
					)
				)
				(rectangle
					(start 7.62 -4.445)
					(end 19.05 -18.415)
					(stroke
						(width 0.254)
						(type default)
					)
					(fill
						(type background)
					)
				)
				(polyline
					(pts
						(xy 8.89 -5.715) (xy 15.24 -5.715)
					)
					(stroke
						(width 0.254)
						(type default)
					)
					(fill
						(type background)
					)
				)
				(polyline
					(pts
						(xy 8.89 -17.145) (xy 8.89 -5.715)
					)
					(stroke
						(width 0.254)
						(type default)
					)
					(fill
						(type background)
					)
				)
				(polyline
					(pts
						(xy 15.24 -5.715) (xy 15.24 -6.985)
					)
					(stroke
						(width 0.254)
						(type default)
					)
					(fill
						(type background)
					)
				)
				(polyline
					(pts
						(xy 15.24 -6.985) (xy 16.51 -6.985)
					)
					(stroke
						(width 0.254)
						(type default)
					)
					(fill
						(type background)
					)
				)
				(polyline
					(pts
						(xy 15.24 -15.875) (xy 16.51 -15.875)
					)
					(stroke
						(width 0.254)
						(type default)
					)
					(fill
						(type background)
					)
				)
				(polyline
					(pts
						(xy 15.24 -17.145) (xy 8.89 -17.145)
					)
					(stroke
						(width 0.254)
						(type default)
					)
					(fill
						(type background)
					)
				)
				(polyline
					(pts
						(xy 15.24 -17.145) (xy 15.24 -15.875)
					)
					(stroke
						(width 0.254)
						(type default)
					)
					(fill
						(type background)
					)
				)
				(polyline
					(pts
						(xy 16.51 -6.985) (xy 16.51 -8.255)
					)
					(stroke
						(width 0.254)
						(type default)
					)
					(fill
						(type background)
					)
				)
				(polyline
					(pts
						(xy 16.51 -8.255) (xy 17.78 -8.255)
					)
					(stroke
						(width 0.254)
						(type default)
					)
					(fill
						(type background)
					)
				)
				(polyline
					(pts
						(xy 16.51 -14.605) (xy 17.78 -14.605)
					)
					(stroke
						(width 0.254)
						(type default)
					)
					(fill
						(type background)
					)
				)
				(polyline
					(pts
						(xy 16.51 -15.875) (xy 16.51 -14.605)
					)
					(stroke
						(width 0.254)
						(type default)
					)
					(fill
						(type background)
					)
				)
				(polyline
					(pts
						(xy 17.78 -8.255) (xy 17.78 -14.605)
					)
					(stroke
						(width 0.254)
						(type default)
					)
					(fill
						(type background)
					)
				)
				(pin bidirectional line
					(at 0 0 0)
					(length 3.81)
					(name "1"
						(effects
							(font
								(size 1.27 1.27)
							)
						)
					)
					(number "1"
						(effects
							(font
								(size 1.27 1.27)
							)
						)
					)
				)
				(pin bidirectional line
					(at 0 -2.54 0)
					(length 3.81)
					(name "2"
						(effects
							(font
								(size 1.27 1.27)
							)
						)
					)
					(number "2"
						(effects
							(font
								(size 1.27 1.27)
							)
						)
					)
				)
				(pin bidirectional line
					(at 0 -5.08 0)
					(length 3.81)
					(name "3"
						(effects
							(font
								(size 1.27 1.27)
							)
						)
					)
					(number "3"
						(effects
							(font
								(size 1.27 1.27)
							)
						)
					)
				)
				(pin bidirectional line
					(at 0 -7.62 0)
					(length 3.81)
					(name "4"
						(effects
							(font
								(size 1.27 1.27)
							)
						)
					)
					(number "4"
						(effects
							(font
								(size 1.27 1.27)
							)
						)
					)
				)
				(pin bidirectional line
					(at 0 -10.16 0)
					(length 3.81)
					(name "5"
						(effects
							(font
								(size 1.27 1.27)
							)
						)
					)
					(number "5"
						(effects
							(font
								(size 1.27 1.27)
							)
						)
					)
				)
				(pin bidirectional line
					(at 0 -12.7 0)
					(length 3.81)
					(name "6"
						(effects
							(font
								(size 1.27 1.27)
							)
						)
					)
					(number "6"
						(effects
							(font
								(size 1.27 1.27)
							)
						)
					)
				)
				(pin bidirectional line
					(at 0 -15.24 0)
					(length 3.81)
					(name "7"
						(effects
							(font
								(size 1.27 1.27)
							)
						)
					)
					(number "7"
						(effects
							(font
								(size 1.27 1.27)
							)
						)
					)
				)
				(pin bidirectional line
					(at 0 -17.78 0)
					(length 3.81)
					(name "8"
						(effects
							(font
								(size 1.27 1.27)
							)
						)
					)
					(number "8"
						(effects
							(font
								(size 1.27 1.27)
							)
						)
					)
				)
				(pin bidirectional line
					(at 0 -22.86 0)
					(length 3.81)
					(name "MP"
						(effects
							(font
								(size 1.27 1.27)
							)
						)
					)
					(number "MP"
						(effects
							(font
								(size 1.27 1.27)
							)
						)
					)
				)
				(pin passive line
					(at 25.4 0 180)
					(length 3.81)
					(name "LED_D1"
						(effects
							(font
								(size 1.27 1.27)
							)
						)
					)
					(number "D1"
						(effects
							(font
								(size 1.27 1.27)
							)
						)
					)
				)
				(pin passive line
					(at 25.4 -2.54 180)
					(length 3.81)
					(name "LED_D2"
						(effects
							(font
								(size 1.27 1.27)
							)
						)
					)
					(number "D2"
						(effects
							(font
								(size 1.27 1.27)
							)
						)
					)
				)
				(pin passive line
					(at 25.4 -20.32 180)
					(length 3.81)
					(name "LED_D3"
						(effects
							(font
								(size 1.27 1.27)
							)
						)
					)
					(number "D3"
						(effects
							(font
								(size 1.27 1.27)
							)
						)
					)
				)
				(pin passive line
					(at 25.4 -22.86 180)
					(length 3.81)
					(name "LED_D4"
						(effects
							(font
								(size 1.27 1.27)
							)
						)
					)
					(number "D4"
						(effects
							(font
								(size 1.27 1.27)
							)
						)
					)
				)
			)
			(symbol "Amphenol_RJE361882415_2_2_1"
				(rectangle
					(start 3.81 2.54)
					(end 20.32 -24.13)
					(stroke
						(width 0.254)
						(type default)
					)
					(fill
						(type background)
					)
				)
				(circle
					(center 12.065 -5.08)
					(radius 0.381)
					(stroke
						(width 0.254)
						(type default)
					)
					(fill
						(type outline)
					)
				)
				(polyline
					(pts
						(xy 12.7 -3.81) (xy 13.97 -3.81) (xy 13.335 -2.54) (xy 12.7 -3.81)
					)
					(stroke
						(width 0.254)
						(type default)
					)
					(fill
						(type outline)
					)
				)
				(polyline
					(pts
						(xy 13.335 -6.35) (xy 13.335 -3.81)
					)
					(stroke
						(width 0.254)
						(type default)
					)
					(fill
						(type background)
					)
				)
				(polyline
					(pts
						(xy 13.335 -6.985) (xy 13.335 -6.35) (xy 14.605 -5.715) (xy 14.605 -4.445)
					)
					(stroke
						(width 0.254)
						(type default)
					)
					(fill
						(type background)
					)
				)
				(polyline
					(pts
						(xy 13.335 -7.62) (xy 13.335 -6.985) (xy 12.065 -5.715) (xy 12.065 -5.08)
					)
					(stroke
						(width 0.254)
						(type default)
					)
					(fill
						(type background)
					)
				)
				(circle
					(center 13.335 -8.255)
					(radius 0.635)
					(stroke
						(width 0.254)
						(type default)
					)
					(fill
						(type outline)
					)
				)
				(rectangle
					(start 14.224 -4.191)
					(end 14.986 -4.953)
					(stroke
						(width 0.254)
						(type default)
					)
					(fill
						(type outline)
					)
				)
				(rectangle
					(start 16.256 -3.81)
					(end 18.034 -8.382)
					(stroke
						(width 0.254)
						(type default)
					)
					(fill
						(type background)
					)
				)
				(rectangle
					(start 17.018 -4.318)
					(end 17.653 -7.874)
					(stroke
						(width 0.254)
						(type default)
					)
					(fill
						(type outline)
					)
				)
				(text "PORT 1"
					(at 12.7 0 0)
					(effects
						(font
							(size 1.27 1.27)
							(thickness 0.15)
						)
						(justify left bottom)
					)
				)
				(pin passive line
					(at 0 0 0)
					(length 3.81)
					(name "VBUS"
						(effects
							(font
								(size 1.27 1.27)
							)
						)
					)
					(number "U1"
						(effects
							(font
								(size 1.27 1.27)
							)
						)
					)
				)
				(pin bidirectional line
					(at 0 -3.81 0)
					(length 3.81)
					(name "D+"
						(effects
							(font
								(size 1.27 1.27)
							)
						)
					)
					(number "U3"
						(effects
							(font
								(size 1.27 1.27)
							)
						)
					)
				)
				(pin bidirectional line
					(at 0 -6.35 0)
					(length 3.81)
					(name "D-"
						(effects
							(font
								(size 1.27 1.27)
							)
						)
					)
					(number "U2"
						(effects
							(font
								(size 1.27 1.27)
							)
						)
					)
				)
				(pin bidirectional line
					(at 0 -8.89 0)
					(length 3.81)
					(name "SSRX+"
						(effects
							(font
								(size 1.27 1.27)
							)
						)
					)
					(number "U8"
						(effects
							(font
								(size 1.27 1.27)
							)
						)
					)
				)
				(pin bidirectional line
					(at 0 -11.43 0)
					(length 3.81)
					(name "SSRX-"
						(effects
							(font
								(size 1.27 1.27)
							)
						)
					)
					(number "U9"
						(effects
							(font
								(size 1.27 1.27)
							)
						)
					)
				)
				(pin bidirectional line
					(at 0 -13.97 0)
					(length 3.81)
					(name "SSTX+"
						(effects
							(font
								(size 1.27 1.27)
							)
						)
					)
					(number "U5"
						(effects
							(font
								(size 1.27 1.27)
							)
						)
					)
				)
				(pin bidirectional line
					(at 0 -16.51 0)
					(length 3.81)
					(name "SSTX-"
						(effects
							(font
								(size 1.27 1.27)
							)
						)
					)
					(number "U6"
						(effects
							(font
								(size 1.27 1.27)
							)
						)
					)
				)
				(pin power_in line
					(at 0 -19.05 0)
					(length 3.81)
					(name "GND"
						(effects
							(font
								(size 1.27 1.27)
							)
						)
					)
					(number "U4"
						(effects
							(font
								(size 1.27 1.27)
							)
						)
					)
				)
				(pin power_in line
					(at 0 -21.59 0)
					(length 3.81)
					(name "GND_DRAIN"
						(effects
							(font
								(size 1.27 1.27)
							)
						)
					)
					(number "U7"
						(effects
							(font
								(size 1.27 1.27)
							)
						)
					)
				)
			)
			(symbol "Amphenol_RJE361882415_2_3_1"
				(rectangle
					(start 3.81 2.54)
					(end 20.32 -24.13)
					(stroke
						(width 0.254)
						(type default)
					)
					(fill
						(type background)
					)
				)
				(circle
					(center 12.065 -5.08)
					(radius 0.381)
					(stroke
						(width 0.254)
						(type default)
					)
					(fill
						(type outline)
					)
				)
				(polyline
					(pts
						(xy 12.7 -3.81) (xy 13.97 -3.81) (xy 13.335 -2.54) (xy 12.7 -3.81)
					)
					(stroke
						(width 0.254)
						(type default)
					)
					(fill
						(type outline)
					)
				)
				(polyline
					(pts
						(xy 13.335 -6.35) (xy 13.335 -3.81)
					)
					(stroke
						(width 0.254)
						(type default)
					)
					(fill
						(type background)
					)
				)
				(polyline
					(pts
						(xy 13.335 -6.985) (xy 13.335 -6.35) (xy 14.605 -5.715) (xy 14.605 -4.445)
					)
					(stroke
						(width 0.254)
						(type default)
					)
					(fill
						(type background)
					)
				)
				(polyline
					(pts
						(xy 13.335 -7.62) (xy 13.335 -6.985) (xy 12.065 -5.715) (xy 12.065 -5.08)
					)
					(stroke
						(width 0.254)
						(type default)
					)
					(fill
						(type background)
					)
				)
				(circle
					(center 13.335 -8.255)
					(radius 0.635)
					(stroke
						(width 0.254)
						(type default)
					)
					(fill
						(type outline)
					)
				)
				(rectangle
					(start 14.224 -4.191)
					(end 14.986 -4.953)
					(stroke
						(width 0.254)
						(type default)
					)
					(fill
						(type outline)
					)
				)
				(rectangle
					(start 16.256 -3.81)
					(end 18.034 -8.382)
					(stroke
						(width 0.254)
						(type default)
					)
					(fill
						(type background)
					)
				)
				(rectangle
					(start 17.018 -4.318)
					(end 17.653 -7.874)
					(stroke
						(width 0.254)
						(type default)
					)
					(fill
						(type outline)
					)
				)
				(text "PORT 2"
					(at 12.7 0 0)
					(effects
						(font
							(size 1.27 1.27)
							(thickness 0.15)
						)
						(justify left bottom)
					)
				)
				(pin passive line
					(at 0 0 0)
					(length 3.81)
					(name "VBUS"
						(effects
							(font
								(size 1.27 1.27)
							)
						)
					)
					(number "U10"
						(effects
							(font
								(size 1.27 1.27)
							)
						)
					)
				)
				(pin bidirectional line
					(at 0 -3.81 0)
					(length 3.81)
					(name "D+"
						(effects
							(font
								(size 1.27 1.27)
							)
						)
					)
					(number "U12"
						(effects
							(font
								(size 1.27 1.27)
							)
						)
					)
				)
				(pin bidirectional line
					(at 0 -6.35 0)
					(length 3.81)
					(name "D-"
						(effects
							(font
								(size 1.27 1.27)
							)
						)
					)
					(number "U11"
						(effects
							(font
								(size 1.27 1.27)
							)
						)
					)
				)
				(pin bidirectional line
					(at 0 -8.89 0)
					(length 3.81)
					(name "SSRX+"
						(effects
							(font
								(size 1.27 1.27)
							)
						)
					)
					(number "U17"
						(effects
							(font
								(size 1.27 1.27)
							)
						)
					)
				)
				(pin bidirectional line
					(at 0 -11.43 0)
					(length 3.81)
					(name "SSRX-"
						(effects
							(font
								(size 1.27 1.27)
							)
						)
					)
					(number "U18"
						(effects
							(font
								(size 1.27 1.27)
							)
						)
					)
				)
				(pin bidirectional line
					(at 0 -13.97 0)
					(length 3.81)
					(name "SSTX+"
						(effects
							(font
								(size 1.27 1.27)
							)
						)
					)
					(number "U14"
						(effects
							(font
								(size 1.27 1.27)
							)
						)
					)
				)
				(pin bidirectional line
					(at 0 -16.51 0)
					(length 3.81)
					(name "SSTX-"
						(effects
							(font
								(size 1.27 1.27)
							)
						)
					)
					(number "U15"
						(effects
							(font
								(size 1.27 1.27)
							)
						)
					)
				)
				(pin power_in line
					(at 0 -19.05 0)
					(length 3.81)
					(name "GND"
						(effects
							(font
								(size 1.27 1.27)
							)
						)
					)
					(number "U13"
						(effects
							(font
								(size 1.27 1.27)
							)
						)
					)
				)
				(pin power_in line
					(at 0 -21.59 0)
					(length 3.81)
					(name "GND_DRAIN"
						(effects
							(font
								(size 1.27 1.27)
							)
						)
					)
					(number "U16"
						(effects
							(font
								(size 1.27 1.27)
							)
						)
					)
				)
			)
		)
	(symbol "R_10k_0402_1"
			(pin_numbers
				(hide yes)
			)
			(pin_names
				(hide yes)
			)
			(exclude_from_sim no)
			(in_bom yes)
			(on_board yes)
			(property "Reference" "R"
				(at 20.32 -5.08 0)
				(effects
					(font
						(size 1.27 1.27)
						(thickness 0.15)
					)
					(justify left bottom)
				)
			)
			(property "Value" "R_10k_0402"
				(at 20.32 -12.7 0)
				(effects
					(font
						(size 1.27 1.27)
						(thickness 0.15)
					)
					(justify left bottom)
					(hide yes)
				)
			)
			(property "Footprint" "antmicro-footprints:R_0402_1005Metric"
				(at 20.32 -15.24 0)
				(effects
					(font
						(size 1.27 1.27)
						(thickness 0.15)
					)
					(justify left bottom)
					(hide yes)
				)
			)
			(property "Datasheet" "https://www.bourns.com/docs/product-datasheets/cr.pdf"
				(at 20.32 -17.78 0)
				(effects
					(font
						(size 1.27 1.27)
						(thickness 0.15)
					)
					(justify left bottom)
					(hide yes)
				)
			)
			(property "Description" "SMD Chip Resistor, 10 kohm, ± 1%, 62.5 mW, 0402 [1005 Metric], Thick Film, General Purpose"
				(at 0 0 0)
				(effects
					(font
						(size 1.27 1.27)
					)
					(hide yes)
				)
			)
			(property "MPN" "CR0402-FX-1002GLF"
				(at 20.32 -20.32 0)
				(effects
					(font
						(size 1.27 1.27)
						(thickness 0.15)
					)
					(justify left bottom)
					(hide yes)
				)
			)
			(property "Manufacturer" "Bourns"
				(at 20.32 -22.86 0)
				(effects
					(font
						(size 1.27 1.27)
						(thickness 0.15)
					)
					(justify left bottom)
					(hide yes)
				)
			)
			(property "License" "Apache-2.0"
				(at 20.32 -25.4 0)
				(effects
					(font
						(size 1.27 1.27)
						(thickness 0.15)
					)
					(justify left bottom)
					(hide yes)
				)
			)
			(property "Author" "Antmicro"
				(at 20.32 -27.94 0)
				(effects
					(font
						(size 1.27 1.27)
						(thickness 0.15)
					)
					(justify left bottom)
					(hide yes)
				)
			)
			(property "Val" "10k"
				(at 20.32 -7.62 0)
				(effects
					(font
						(size 1.27 1.27)
						(thickness 0.15)
					)
					(justify left bottom)
				)
			)
			(property "Tolerance" "1%"
				(at 20.32 -10.16 0)
				(effects
					(font
						(size 1.27 1.27)
					)
					(justify left bottom)
					(hide yes)
				)
			)
			(property "ki_keywords" "0402, SMT, RESISTOR, PASSIVE"
				(at 0 0 0)
				(effects
					(font
						(size 1.27 1.27)
					)
					(hide yes)
				)
			)
			(symbol "R_10k_0402_1_0_1"
				(rectangle
					(start 0.635 0.889)
					(end 4.445 -0.889)
					(stroke
						(width 0.254)
						(type default)
					)
					(fill
						(type none)
					)
				)
			)
			(symbol "R_10k_0402_1_1_1"
				(pin passive line
					(at 0 0 0)
					(length 0.635)
					(name "~"
						(effects
							(font
								(size 1.27 1.27)
							)
						)
					)
					(number "1"
						(effects
							(font
								(size 1.27 1.27)
							)
						)
					)
				)
				(pin passive line
					(at 5.08 0 180)
					(length 0.635)
					(name "~"
						(effects
							(font
								(size 1.27 1.27)
							)
						)
					)
					(number "2"
						(effects
							(font
								(size 1.27 1.27)
							)
						)
					)
				)
			)
		)
	(symbol "antmicroB2BConnectors:Plug_Bus_CE7_EPT_401-51501-51"
			(exclude_from_sim no)
			(in_bom yes)
			(on_board yes)
			(property "Reference" "J"
				(at 53.34 -2.54 0)
				(effects
					(font
						(size 1.27 1.27)
						(thickness 0.15)
					)
					(justify left bottom)
				)
			)
			(property "Value" "Plug_Bus_CE7_EPT_401-51501-51"
				(at 53.34 -12.7 0)
				(effects
					(font
						(size 1.27 1.27)
						(thickness 0.15)
					)
					(justify left bottom)
					(hide yes)
				)
			)
			(property "Footprint" "antmicro-footprints:EPT_401-51501-51"
				(at 53.34 -7.62 0)
				(effects
					(font
						(size 1.27 1.27)
						(thickness 0.15)
					)
					(justify left bottom)
					(hide yes)
				)
			)
			(property "Datasheet" "https://www.farnell.com/datasheets/1905093.pdf"
				(at 53.34 -10.16 0)
				(effects
					(font
						(size 1.27 1.27)
						(thickness 0.15)
					)
					(justify left bottom)
					(hide yes)
				)
			)
			(property "Description" "Mezzanine Connector, 5mm Height, COM Express, Header, 0.5 mm, 2 Rows, 440 Contacts, Surface Mount"
				(at 0 0 0)
				(effects
					(font
						(size 1.27 1.27)
					)
					(hide yes)
				)
			)
			(property "Author" "Antmicro"
				(at 53.34 -17.78 0)
				(effects
					(font
						(size 1.27 1.27)
						(thickness 0.15)
					)
					(justify left bottom)
					(hide yes)
				)
			)
			(property "License" "Apache-2.0"
				(at 53.34 -20.32 0)
				(effects
					(font
						(size 1.27 1.27)
						(thickness 0.15)
					)
					(justify left bottom)
					(hide yes)
				)
			)
			(property "Manufacturer" "ept"
				(at 53.34 -15.24 0)
				(effects
					(font
						(size 1.27 1.27)
						(thickness 0.15)
					)
					(justify left bottom)
					(hide yes)
				)
			)
			(property "MPN" "401-51501-51"
				(at 53.34 -5.08 0)
				(effects
					(font
						(size 1.27 1.27)
						(thickness 0.15)
					)
					(justify left bottom)
				)
			)
			(property "ki_locked" ""
				(at 0 0 0)
				(effects
					(font
						(size 1.27 1.27)
					)
				)
			)
			(property "ki_keywords" "CONNECTOR, B2B, PLUG"
				(at 0 0 0)
				(effects
					(font
						(size 1.27 1.27)
					)
					(hide yes)
				)
			)
			(symbol "Plug_Bus_CE7_EPT_401-51501-51_1_1"
				(rectangle
					(start -33.02 2.54)
					(end -5.08 -25.4)
					(stroke
						(width 0.254)
						(type default)
					)
					(fill
						(type background)
					)
				)
				(text "A/B"
					(at -31.75 0 0)
					(effects
						(font
							(size 1.27 1.27)
							(thickness 0.15)
						)
						(justify left bottom)
					)
				)
				(text "NCSI"
					(at -31.75 -24.13 0)
					(effects
						(font
							(size 1.27 1.27)
							(thickness 0.15)
						)
						(justify left bottom)
					)
				)
				(pin output line
					(at 0 0 180)
					(length 5.08)
					(name "NCSI_TX_EN"
						(effects
							(font
								(size 1.27 1.27)
							)
						)
					)
					(number "A84"
						(effects
							(font
								(size 1.27 1.27)
							)
						)
					)
				)
				(pin input line
					(at 0 -2.54 180)
					(length 5.08)
					(name "NCSI_RXD0"
						(effects
							(font
								(size 1.27 1.27)
							)
						)
					)
					(number "B93"
						(effects
							(font
								(size 1.27 1.27)
							)
						)
					)
				)
				(pin input line
					(at 0 -5.08 180)
					(length 5.08)
					(name "NCSI_RXD1"
						(effects
							(font
								(size 1.27 1.27)
							)
						)
					)
					(number "B92"
						(effects
							(font
								(size 1.27 1.27)
							)
						)
					)
				)
				(pin output line
					(at 0 -7.62 180)
					(length 5.08)
					(name "NCSI_TXD0"
						(effects
							(font
								(size 1.27 1.27)
							)
						)
					)
					(number "B96"
						(effects
							(font
								(size 1.27 1.27)
							)
						)
					)
				)
				(pin output line
					(at 0 -10.16 180)
					(length 5.08)
					(name "NCSI_TXD1"
						(effects
							(font
								(size 1.27 1.27)
							)
						)
					)
					(number "B95"
						(effects
							(font
								(size 1.27 1.27)
							)
						)
					)
				)
				(pin input line
					(at 0 -12.7 180)
					(length 5.08)
					(name "NCSI_ARB_IN"
						(effects
							(font
								(size 1.27 1.27)
							)
						)
					)
					(number "B98"
						(effects
							(font
								(size 1.27 1.27)
							)
						)
					)
				)
				(pin output line
					(at 0 -15.24 180)
					(length 5.08)
					(name "NCSI_ARB_OUT"
						(effects
							(font
								(size 1.27 1.27)
							)
						)
					)
					(number "B99"
						(effects
							(font
								(size 1.27 1.27)
							)
						)
					)
				)
				(pin input line
					(at 0 -17.78 180)
					(length 5.08)
					(name "NCSI_RX_ER"
						(effects
							(font
								(size 1.27 1.27)
							)
						)
					)
					(number "B89"
						(effects
							(font
								(size 1.27 1.27)
							)
						)
					)
				)
				(pin input line
					(at 0 -20.32 180)
					(length 5.08)
					(name "NCSI_CLK_IN"
						(effects
							(font
								(size 1.27 1.27)
							)
						)
					)
					(number "B91"
						(effects
							(font
								(size 1.27 1.27)
							)
						)
					)
				)
				(pin output line
					(at 0 -22.86 180)
					(length 5.08)
					(name "NCSI_CRS_DV"
						(effects
							(font
								(size 1.27 1.27)
							)
						)
					)
					(number "B94"
						(effects
							(font
								(size 1.27 1.27)
							)
						)
					)
				)
			)
			(symbol "Plug_Bus_CE7_EPT_401-51501-51_2_1"
				(rectangle
					(start -33.02 2.54)
					(end -5.08 -50.8)
					(stroke
						(width 0.254)
						(type default)
					)
					(fill
						(type background)
					)
				)
				(text "A/B"
					(at -31.75 0 0)
					(effects
						(font
							(size 1.27 1.27)
							(thickness 0.15)
						)
						(justify left bottom)
					)
				)
				(text "GBE0"
					(at -31.75 -49.53 0)
					(effects
						(font
							(size 1.27 1.27)
							(thickness 0.15)
						)
						(justify left bottom)
					)
				)
				(pin passive line
					(at 0 0 180)
					(length 5.08)
					(name "GBE0_CTREF"
						(effects
							(font
								(size 1.27 1.27)
							)
						)
					)
					(number "A14"
						(effects
							(font
								(size 1.27 1.27)
							)
						)
					)
				)
				(pin bidirectional line
					(at 0 -5.08 180)
					(length 5.08)
					(name "GBE0_MDI3+"
						(effects
							(font
								(size 1.27 1.27)
							)
						)
					)
					(number "A3"
						(effects
							(font
								(size 1.27 1.27)
							)
						)
					)
				)
				(pin bidirectional line
					(at 0 -7.62 180)
					(length 5.08)
					(name "GBE0_MDI3-"
						(effects
							(font
								(size 1.27 1.27)
							)
						)
					)
					(number "A2"
						(effects
							(font
								(size 1.27 1.27)
							)
						)
					)
				)
				(pin bidirectional line
					(at 0 -12.7 180)
					(length 5.08)
					(name "GBE0_MDI2+"
						(effects
							(font
								(size 1.27 1.27)
							)
						)
					)
					(number "A7"
						(effects
							(font
								(size 1.27 1.27)
							)
						)
					)
				)
				(pin bidirectional line
					(at 0 -15.24 180)
					(length 5.08)
					(name "GBE0_MDI2-"
						(effects
							(font
								(size 1.27 1.27)
							)
						)
					)
					(number "A6"
						(effects
							(font
								(size 1.27 1.27)
							)
						)
					)
				)
				(pin bidirectional line
					(at 0 -20.32 180)
					(length 5.08)
					(name "GBE0_MDI1+"
						(effects
							(font
								(size 1.27 1.27)
							)
						)
					)
					(number "A10"
						(effects
							(font
								(size 1.27 1.27)
							)
						)
					)
				)
				(pin bidirectional line
					(at 0 -22.86 180)
					(length 5.08)
					(name "GBE0_MDI1-"
						(effects
							(font
								(size 1.27 1.27)
							)
						)
					)
					(number "A9"
						(effects
							(font
								(size 1.27 1.27)
							)
						)
					)
				)
				(pin bidirectional line
					(at 0 -27.94 180)
					(length 5.08)
					(name "GBE0_MDI0+"
						(effects
							(font
								(size 1.27 1.27)
							)
						)
					)
					(number "A13"
						(effects
							(font
								(size 1.27 1.27)
							)
						)
					)
				)
				(pin bidirectional line
					(at 0 -30.48 180)
					(length 5.08)
					(name "GBE0_MDI0-"
						(effects
							(font
								(size 1.27 1.27)
							)
						)
					)
					(number "A12"
						(effects
							(font
								(size 1.27 1.27)
							)
						)
					)
				)
				(pin output line
					(at 0 -35.56 180)
					(length 5.08)
					(name "~{GBE0_LINK1000}"
						(effects
							(font
								(size 1.27 1.27)
							)
						)
					)
					(number "A5"
						(effects
							(font
								(size 1.27 1.27)
							)
						)
					)
				)
				(pin output line
					(at 0 -38.1 180)
					(length 5.08)
					(name "~{GBE0_LINK100}"
						(effects
							(font
								(size 1.27 1.27)
							)
						)
					)
					(number "A4"
						(effects
							(font
								(size 1.27 1.27)
							)
						)
					)
				)
				(pin output line
					(at 0 -40.64 180)
					(length 5.08)
					(name "~{GBE0_LINK}"
						(effects
							(font
								(size 1.27 1.27)
							)
						)
					)
					(number "A8"
						(effects
							(font
								(size 1.27 1.27)
							)
						)
					)
				)
				(pin output line
					(at 0 -43.18 180)
					(length 5.08)
					(name "~{GBE0_ACT}"
						(effects
							(font
								(size 1.27 1.27)
							)
						)
					)
					(number "B2"
						(effects
							(font
								(size 1.27 1.27)
							)
						)
					)
				)
				(pin bidirectional line
					(at 0 -48.26 180)
					(length 5.08)
					(name "GBE0_SDP"
						(effects
							(font
								(size 1.27 1.27)
							)
						)
					)
					(number "A49"
						(effects
							(font
								(size 1.27 1.27)
							)
						)
					)
				)
			)
			(symbol "Plug_Bus_CE7_EPT_401-51501-51_3_1"
				(rectangle
					(start -33.02 2.54)
					(end -5.08 -35.56)
					(stroke
						(width 0.254)
						(type default)
					)
					(fill
						(type background)
					)
				)
				(text "A/B"
					(at -31.75 0 0)
					(effects
						(font
							(size 1.27 1.27)
							(thickness 0.15)
						)
						(justify left bottom)
					)
				)
				(text "LS"
					(at -31.75 -34.29 0)
					(effects
						(font
							(size 1.27 1.27)
							(thickness 0.15)
						)
						(justify left bottom)
					)
				)
				(pin power_out line
					(at 0 0 180)
					(length 5.08)
					(name "SPI_POWER"
						(effects
							(font
								(size 1.27 1.27)
							)
						)
					)
					(number "A91"
						(effects
							(font
								(size 1.27 1.27)
							)
						)
					)
				)
				(pin input line
					(at 0 -2.54 180)
					(length 5.08)
					(name "SPI_MISO"
						(effects
							(font
								(size 1.27 1.27)
							)
						)
					)
					(number "A92"
						(effects
							(font
								(size 1.27 1.27)
							)
						)
					)
				)
				(pin output line
					(at 0 -5.08 180)
					(length 5.08)
					(name "SPI_CLK"
						(effects
							(font
								(size 1.27 1.27)
							)
						)
					)
					(number "A94"
						(effects
							(font
								(size 1.27 1.27)
							)
						)
					)
				)
				(pin output line
					(at 0 -7.62 180)
					(length 5.08)
					(name "SPI_MOSI"
						(effects
							(font
								(size 1.27 1.27)
							)
						)
					)
					(number "A95"
						(effects
							(font
								(size 1.27 1.27)
							)
						)
					)
				)
				(pin output line
					(at 0 -10.16 180)
					(length 5.08)
					(name "~{SPI_CS}"
						(effects
							(font
								(size 1.27 1.27)
							)
						)
					)
					(number "B97"
						(effects
							(font
								(size 1.27 1.27)
							)
						)
					)
				)
				(pin output line
					(at 0 -15.24 180)
					(length 5.08)
					(name "SER0_TX"
						(effects
							(font
								(size 1.27 1.27)
							)
						)
					)
					(number "A98"
						(effects
							(font
								(size 1.27 1.27)
							)
						)
					)
				)
				(pin input line
					(at 0 -17.78 180)
					(length 5.08)
					(name "SER0_RX"
						(effects
							(font
								(size 1.27 1.27)
							)
						)
					)
					(number "A99"
						(effects
							(font
								(size 1.27 1.27)
							)
						)
					)
				)
				(pin output line
					(at 0 -22.86 180)
					(length 5.08)
					(name "SER1_TX"
						(effects
							(font
								(size 1.27 1.27)
							)
						)
					)
					(number "A101"
						(effects
							(font
								(size 1.27 1.27)
							)
						)
					)
				)
				(pin input line
					(at 0 -25.4 180)
					(length 5.08)
					(name "SER1_RX"
						(effects
							(font
								(size 1.27 1.27)
							)
						)
					)
					(number "A102"
						(effects
							(font
								(size 1.27 1.27)
							)
						)
					)
				)
				(pin open_collector line
					(at 0 -30.48 180)
					(length 5.08)
					(name "I2C_CK"
						(effects
							(font
								(size 1.27 1.27)
							)
						)
					)
					(number "B33"
						(effects
							(font
								(size 1.27 1.27)
							)
						)
					)
				)
				(pin open_collector line
					(at 0 -33.02 180)
					(length 5.08)
					(name "I2C_DAT"
						(effects
							(font
								(size 1.27 1.27)
							)
						)
					)
					(number "B34"
						(effects
							(font
								(size 1.27 1.27)
							)
						)
					)
				)
			)
			(symbol "Plug_Bus_CE7_EPT_401-51501-51_4_1"
				(rectangle
					(start -33.02 2.54)
					(end -5.08 -91.44)
					(stroke
						(width 0.254)
						(type default)
					)
					(fill
						(type background)
					)
				)
				(text "A/B"
					(at -31.75 0 0)
					(effects
						(font
							(size 1.27 1.27)
							(thickness 0.15)
						)
						(justify left bottom)
					)
				)
				(text "MGMT"
					(at -31.75 -90.17 0)
					(effects
						(font
							(size 1.27 1.27)
							(thickness 0.15)
						)
						(justify left bottom)
					)
				)
				(pin bidirectional line
					(at 0 0 180)
					(length 5.08)
					(name "LPC_AD3/ESPI_IO_3"
						(effects
							(font
								(size 1.27 1.27)
							)
						)
					)
					(number "B7"
						(effects
							(font
								(size 1.27 1.27)
							)
						)
					)
				)
				(pin bidirectional line
					(at 0 -2.54 180)
					(length 5.08)
					(name "LPC_AD2/ESPI_IO_2"
						(effects
							(font
								(size 1.27 1.27)
							)
						)
					)
					(number "B6"
						(effects
							(font
								(size 1.27 1.27)
							)
						)
					)
				)
				(pin bidirectional line
					(at 0 -5.08 180)
					(length 5.08)
					(name "LPC_AD1/ESPI_IO_1"
						(effects
							(font
								(size 1.27 1.27)
							)
						)
					)
					(number "B5"
						(effects
							(font
								(size 1.27 1.27)
							)
						)
					)
				)
				(pin bidirectional line
					(at 0 -7.62 180)
					(length 5.08)
					(name "LPC_AD0/ESPI_IO_0"
						(effects
							(font
								(size 1.27 1.27)
							)
						)
					)
					(number "B4"
						(effects
							(font
								(size 1.27 1.27)
							)
						)
					)
				)
				(pin output line
					(at 0 -10.16 180)
					(length 5.08)
					(name "LPC_CLK/ESPI_CK"
						(effects
							(font
								(size 1.27 1.27)
							)
						)
					)
					(number "B10"
						(effects
							(font
								(size 1.27 1.27)
							)
						)
					)
				)
				(pin bidirectional line
					(at 0 -12.7 180)
					(length 5.08)
					(name "LPC_SERIRQ/~{ESPI_CS1}"
						(effects
							(font
								(size 1.27 1.27)
							)
						)
					)
					(number "A50"
						(effects
							(font
								(size 1.27 1.27)
							)
						)
					)
				)
				(pin bidirectional line
					(at 0 -15.24 180)
					(length 5.08)
					(name "~{LPC_FRAME}/~{ESPI_CS0}"
						(effects
							(font
								(size 1.27 1.27)
							)
						)
					)
					(number "B3"
						(effects
							(font
								(size 1.27 1.27)
							)
						)
					)
				)
				(pin input line
					(at 0 -17.78 180)
					(length 5.08)
					(name "~{LPC_DRQ0}/~{ESPI_ALERT0}"
						(effects
							(font
								(size 1.27 1.27)
							)
						)
					)
					(number "B8"
						(effects
							(font
								(size 1.27 1.27)
							)
						)
					)
				)
				(pin input line
					(at 0 -20.32 180)
					(length 5.08)
					(name "~{LPC_DRQ1}/~{ESPI_ALERT1}"
						(effects
							(font
								(size 1.27 1.27)
							)
						)
					)
					(number "B9"
						(effects
							(font
								(size 1.27 1.27)
							)
						)
					)
				)
				(pin output line
					(at 0 -22.86 180)
					(length 5.08)
					(name "~{SUS_STAT}/~{ESPI_RESET}"
						(effects
							(font
								(size 1.27 1.27)
							)
						)
					)
					(number "B18"
						(effects
							(font
								(size 1.27 1.27)
							)
						)
					)
				)
				(pin input line
					(at 0 -25.4 180)
					(length 5.08)
					(name "~{BIOS_DIS0}/ESPI_SAFS"
						(effects
							(font
								(size 1.27 1.27)
							)
						)
					)
					(number "A34"
						(effects
							(font
								(size 1.27 1.27)
							)
						)
					)
				)
				(pin input line
					(at 0 -27.94 180)
					(length 5.08)
					(name "~{BIOS_DIS1}"
						(effects
							(font
								(size 1.27 1.27)
							)
						)
					)
					(number "B88"
						(effects
							(font
								(size 1.27 1.27)
							)
						)
					)
				)
				(pin input line
					(at 0 -30.48 180)
					(length 5.08)
					(name "~{ESPI_EN}"
						(effects
							(font
								(size 1.27 1.27)
							)
						)
					)
					(number "B47"
						(effects
							(font
								(size 1.27 1.27)
							)
						)
					)
				)
				(pin output line
					(at 0 -33.02 180)
					(length 5.08)
					(name "~{CB_RESET}"
						(effects
							(font
								(size 1.27 1.27)
							)
						)
					)
					(number "B50"
						(effects
							(font
								(size 1.27 1.27)
							)
						)
					)
				)
				(pin input line
					(at 0 -35.56 180)
					(length 5.08)
					(name "~{SYS_RESET}"
						(effects
							(font
								(size 1.27 1.27)
							)
						)
					)
					(number "B49"
						(effects
							(font
								(size 1.27 1.27)
							)
						)
					)
				)
				(pin input line
					(at 0 -38.1 180)
					(length 5.08)
					(name "PWR_OK"
						(effects
							(font
								(size 1.27 1.27)
							)
						)
					)
					(number "B24"
						(effects
							(font
								(size 1.27 1.27)
							)
						)
					)
				)
				(pin input line
					(at 0 -40.64 180)
					(length 5.08)
					(name "~{PWRBTN}"
						(effects
							(font
								(size 1.27 1.27)
							)
						)
					)
					(number "B12"
						(effects
							(font
								(size 1.27 1.27)
							)
						)
					)
				)
				(pin input line
					(at 0 -43.18 180)
					(length 5.08)
					(name "~{LID}"
						(effects
							(font
								(size 1.27 1.27)
							)
						)
					)
					(number "A103"
						(effects
							(font
								(size 1.27 1.27)
							)
						)
					)
				)
				(pin input line
					(at 0 -45.72 180)
					(length 5.08)
					(name "~{SLEEP}"
						(effects
							(font
								(size 1.27 1.27)
							)
						)
					)
					(number "B103"
						(effects
							(font
								(size 1.27 1.27)
							)
						)
					)
				)
				(pin input line
					(at 0 -48.26 180)
					(length 5.08)
					(name "~{SMB_ALERT}"
						(effects
							(font
								(size 1.27 1.27)
							)
						)
					)
					(number "B15"
						(effects
							(font
								(size 1.27 1.27)
							)
						)
					)
				)
				(pin open_collector line
					(at 0 -50.8 180)
					(length 5.08)
					(name "SMB_CK"
						(effects
							(font
								(size 1.27 1.27)
							)
						)
					)
					(number "B13"
						(effects
							(font
								(size 1.27 1.27)
							)
						)
					)
				)
				(pin open_collector line
					(at 0 -53.34 180)
					(length 5.08)
					(name "SMB_DAT"
						(effects
							(font
								(size 1.27 1.27)
							)
						)
					)
					(number "B14"
						(effects
							(font
								(size 1.27 1.27)
							)
						)
					)
				)
				(pin input line
					(at 0 -55.88 180)
					(length 5.08)
					(name "~{THRM}"
						(effects
							(font
								(size 1.27 1.27)
							)
						)
					)
					(number "B35"
						(effects
							(font
								(size 1.27 1.27)
							)
						)
					)
				)
				(pin output line
					(at 0 -58.42 180)
					(length 5.08)
					(name "~{THRMTRIP}"
						(effects
							(font
								(size 1.27 1.27)
							)
						)
					)
					(number "A35"
						(effects
							(font
								(size 1.27 1.27)
							)
						)
					)
				)
				(pin output line
					(at 0 -60.96 180)
					(length 5.08)
					(name "~{SUS_S3}"
						(effects
							(font
								(size 1.27 1.27)
							)
						)
					)
					(number "A15"
						(effects
							(font
								(size 1.27 1.27)
							)
						)
					)
				)
				(pin output line
					(at 0 -63.5 180)
					(length 5.08)
					(name "~{SUS_S4}"
						(effects
							(font
								(size 1.27 1.27)
							)
						)
					)
					(number "A18"
						(effects
							(font
								(size 1.27 1.27)
							)
						)
					)
				)
				(pin output line
					(at 0 -66.04 180)
					(length 5.08)
					(name "~{SUS_S5}"
						(effects
							(font
								(size 1.27 1.27)
							)
						)
					)
					(number "A24"
						(effects
							(font
								(size 1.27 1.27)
							)
						)
					)
				)
				(pin input line
					(at 0 -68.58 180)
					(length 5.08)
					(name "~{WAKE0}"
						(effects
							(font
								(size 1.27 1.27)
							)
						)
					)
					(number "B66"
						(effects
							(font
								(size 1.27 1.27)
							)
						)
					)
				)
				(pin input line
					(at 0 -71.12 180)
					(length 5.08)
					(name "~{WAKE1}"
						(effects
							(font
								(size 1.27 1.27)
							)
						)
					)
					(number "B67"
						(effects
							(font
								(size 1.27 1.27)
							)
						)
					)
				)
				(pin input line
					(at 0 -73.66 180)
					(length 5.08)
					(name "~{BATLOW}"
						(effects
							(font
								(size 1.27 1.27)
							)
						)
					)
					(number "A27"
						(effects
							(font
								(size 1.27 1.27)
							)
						)
					)
				)
				(pin passive line
					(at 0 -76.2 180)
					(length 5.08)
					(name "~{TYPE10}"
						(effects
							(font
								(size 1.27 1.27)
							)
						)
					)
					(number "A97"
						(effects
							(font
								(size 1.27 1.27)
							)
						)
					)
				)
				(pin input line
					(at 0 -78.74 180)
					(length 5.08)
					(name "TPM_PP"
						(effects
							(font
								(size 1.27 1.27)
							)
						)
					)
					(number "A96"
						(effects
							(font
								(size 1.27 1.27)
							)
						)
					)
				)
				(pin output line
					(at 0 -81.28 180)
					(length 5.08)
					(name "WDT"
						(effects
							(font
								(size 1.27 1.27)
							)
						)
					)
					(number "B27"
						(effects
							(font
								(size 1.27 1.27)
							)
						)
					)
				)
				(pin output line
					(at 0 -83.82 180)
					(length 5.08)
					(name "SPKR"
						(effects
							(font
								(size 1.27 1.27)
							)
						)
					)
					(number "B32"
						(effects
							(font
								(size 1.27 1.27)
							)
						)
					)
				)
				(pin output line
					(at 0 -86.36 180)
					(length 5.08)
					(name "FAN_PWMOUT"
						(effects
							(font
								(size 1.27 1.27)
							)
						)
					)
					(number "B101"
						(effects
							(font
								(size 1.27 1.27)
							)
						)
					)
				)
				(pin input line
					(at 0 -88.9 180)
					(length 5.08)
					(name "FAN_TACHIN"
						(effects
							(font
								(size 1.27 1.27)
							)
						)
					)
					(number "B102"
						(effects
							(font
								(size 1.27 1.27)
							)
						)
					)
				)
			)
			(symbol "Plug_Bus_CE7_EPT_401-51501-51_5_1"
				(rectangle
					(start -33.02 2.54)
					(end -5.08 -20.32)
					(stroke
						(width 0.254)
						(type default)
					)
					(fill
						(type background)
					)
				)
				(text "A/B"
					(at -31.75 0 0)
					(effects
						(font
							(size 1.27 1.27)
							(thickness 0.15)
						)
						(justify left bottom)
					)
				)
				(text "GPIO"
					(at -31.75 -19.05 0)
					(effects
						(font
							(size 1.27 1.27)
							(thickness 0.15)
						)
						(justify left bottom)
					)
				)
				(pin output line
					(at 0 0 180)
					(length 5.08)
					(name "GPO0"
						(effects
							(font
								(size 1.27 1.27)
							)
						)
					)
					(number "A93"
						(effects
							(font
								(size 1.27 1.27)
							)
						)
					)
				)
				(pin output line
					(at 0 -2.54 180)
					(length 5.08)
					(name "GPO1"
						(effects
							(font
								(size 1.27 1.27)
							)
						)
					)
					(number "B54"
						(effects
							(font
								(size 1.27 1.27)
							)
						)
					)
				)
				(pin output line
					(at 0 -5.08 180)
					(length 5.08)
					(name "GPO2"
						(effects
							(font
								(size 1.27 1.27)
							)
						)
					)
					(number "B57"
						(effects
							(font
								(size 1.27 1.27)
							)
						)
					)
				)
				(pin output line
					(at 0 -7.62 180)
					(length 5.08)
					(name "GPO3"
						(effects
							(font
								(size 1.27 1.27)
							)
						)
					)
					(number "B63"
						(effects
							(font
								(size 1.27 1.27)
							)
						)
					)
				)
				(pin input line
					(at 0 -10.16 180)
					(length 5.08)
					(name "GPI0"
						(effects
							(font
								(size 1.27 1.27)
							)
						)
					)
					(number "A54"
						(effects
							(font
								(size 1.27 1.27)
							)
						)
					)
				)
				(pin input line
					(at 0 -12.7 180)
					(length 5.08)
					(name "GPI1"
						(effects
							(font
								(size 1.27 1.27)
							)
						)
					)
					(number "A63"
						(effects
							(font
								(size 1.27 1.27)
							)
						)
					)
				)
				(pin input line
					(at 0 -15.24 180)
					(length 5.08)
					(name "GPI2"
						(effects
							(font
								(size 1.27 1.27)
							)
						)
					)
					(number "A67"
						(effects
							(font
								(size 1.27 1.27)
							)
						)
					)
				)
				(pin input line
					(at 0 -17.78 180)
					(length 5.08)
					(name "GPI3"
						(effects
							(font
								(size 1.27 1.27)
							)
						)
					)
					(number "A85"
						(effects
							(font
								(size 1.27 1.27)
							)
						)
					)
				)
			)
			(symbol "Plug_Bus_CE7_EPT_401-51501-51_6_1"
				(rectangle
					(start -33.02 2.54)
					(end -5.08 -33.02)
					(stroke
						(width 0.254)
						(type default)
					)
					(fill
						(type background)
					)
				)
				(text "A/B"
					(at -31.75 0 0)
					(effects
						(font
							(size 1.27 1.27)
							(thickness 0.15)
						)
						(justify left bottom)
					)
				)
				(text "SATA"
					(at -31.75 -31.75 0)
					(effects
						(font
							(size 1.27 1.27)
							(thickness 0.15)
						)
						(justify left bottom)
					)
				)
				(pin output line
					(at 0 0 180)
					(length 5.08)
					(name "SATA0_TX+"
						(effects
							(font
								(size 1.27 1.27)
							)
						)
					)
					(number "A16"
						(effects
							(font
								(size 1.27 1.27)
							)
						)
					)
				)
				(pin output line
					(at 0 -2.54 180)
					(length 5.08)
					(name "SATA0_TX-"
						(effects
							(font
								(size 1.27 1.27)
							)
						)
					)
					(number "A17"
						(effects
							(font
								(size 1.27 1.27)
							)
						)
					)
				)
				(pin input line
					(at 0 -7.62 180)
					(length 5.08)
					(name "SATA0_RX+"
						(effects
							(font
								(size 1.27 1.27)
							)
						)
					)
					(number "A19"
						(effects
							(font
								(size 1.27 1.27)
							)
						)
					)
				)
				(pin input line
					(at 0 -10.16 180)
					(length 5.08)
					(name "SATA0_RX-"
						(effects
							(font
								(size 1.27 1.27)
							)
						)
					)
					(number "A20"
						(effects
							(font
								(size 1.27 1.27)
							)
						)
					)
				)
				(pin output line
					(at 0 -15.24 180)
					(length 5.08)
					(name "SATA1_TX+"
						(effects
							(font
								(size 1.27 1.27)
							)
						)
					)
					(number "B16"
						(effects
							(font
								(size 1.27 1.27)
							)
						)
					)
				)
				(pin output line
					(at 0 -17.78 180)
					(length 5.08)
					(name "SATA1_TX-"
						(effects
							(font
								(size 1.27 1.27)
							)
						)
					)
					(number "B17"
						(effects
							(font
								(size 1.27 1.27)
							)
						)
					)
				)
				(pin input line
					(at 0 -22.86 180)
					(length 5.08)
					(name "SATA1_RX+"
						(effects
							(font
								(size 1.27 1.27)
							)
						)
					)
					(number "B19"
						(effects
							(font
								(size 1.27 1.27)
							)
						)
					)
				)
				(pin input line
					(at 0 -25.4 180)
					(length 5.08)
					(name "SATA1_RX-"
						(effects
							(font
								(size 1.27 1.27)
							)
						)
					)
					(number "B20"
						(effects
							(font
								(size 1.27 1.27)
							)
						)
					)
				)
				(pin bidirectional line
					(at 0 -30.48 180)
					(length 5.08)
					(name "~{(S)ATA_ACT}"
						(effects
							(font
								(size 1.27 1.27)
							)
						)
					)
					(number "A28"
						(effects
							(font
								(size 1.27 1.27)
							)
						)
					)
				)
			)
			(symbol "Plug_Bus_CE7_EPT_401-51501-51_7_1"
				(rectangle
					(start -33.02 2.54)
					(end -5.08 -38.1)
					(stroke
						(width 0.254)
						(type default)
					)
					(fill
						(type background)
					)
				)
				(text "A/B"
					(at -31.75 0 0)
					(effects
						(font
							(size 1.27 1.27)
							(thickness 0.15)
						)
						(justify left bottom)
					)
				)
				(text "USB"
					(at -31.75 -36.83 0)
					(effects
						(font
							(size 1.27 1.27)
							(thickness 0.15)
						)
						(justify left bottom)
					)
				)
				(pin bidirectional line
					(at 0 0 180)
					(length 5.08)
					(name "USB3+"
						(effects
							(font
								(size 1.27 1.27)
							)
						)
					)
					(number "B43"
						(effects
							(font
								(size 1.27 1.27)
							)
						)
					)
				)
				(pin bidirectional line
					(at 0 -2.54 180)
					(length 5.08)
					(name "USB3-"
						(effects
							(font
								(size 1.27 1.27)
							)
						)
					)
					(number "B42"
						(effects
							(font
								(size 1.27 1.27)
							)
						)
					)
				)
				(pin bidirectional line
					(at 0 -7.62 180)
					(length 5.08)
					(name "USB2+"
						(effects
							(font
								(size 1.27 1.27)
							)
						)
					)
					(number "A43"
						(effects
							(font
								(size 1.27 1.27)
							)
						)
					)
				)
				(pin bidirectional line
					(at 0 -10.16 180)
					(length 5.08)
					(name "USB2-"
						(effects
							(font
								(size 1.27 1.27)
							)
						)
					)
					(number "A42"
						(effects
							(font
								(size 1.27 1.27)
							)
						)
					)
				)
				(pin bidirectional line
					(at 0 -15.24 180)
					(length 5.08)
					(name "USB1+"
						(effects
							(font
								(size 1.27 1.27)
							)
						)
					)
					(number "B46"
						(effects
							(font
								(size 1.27 1.27)
							)
						)
					)
				)
				(pin bidirectional line
					(at 0 -17.78 180)
					(length 5.08)
					(name "USB1-"
						(effects
							(font
								(size 1.27 1.27)
							)
						)
					)
					(number "B45"
						(effects
							(font
								(size 1.27 1.27)
							)
						)
					)
				)
				(pin bidirectional line
					(at 0 -22.86 180)
					(length 5.08)
					(name "USB0+"
						(effects
							(font
								(size 1.27 1.27)
							)
						)
					)
					(number "A46"
						(effects
							(font
								(size 1.27 1.27)
							)
						)
					)
				)
				(pin bidirectional line
					(at 0 -25.4 180)
					(length 5.08)
					(name "USB0-"
						(effects
							(font
								(size 1.27 1.27)
							)
						)
					)
					(number "A45"
						(effects
							(font
								(size 1.27 1.27)
							)
						)
					)
				)
				(pin input line
					(at 0 -30.48 180)
					(length 5.08)
					(name "USB0_HOST_PRSNT"
						(effects
							(font
								(size 1.27 1.27)
							)
						)
					)
					(number "B48"
						(effects
							(font
								(size 1.27 1.27)
							)
						)
					)
				)
				(pin input line
					(at 0 -33.02 180)
					(length 5.08)
					(name "~{USB_0_1_OC}"
						(effects
							(font
								(size 1.27 1.27)
							)
						)
					)
					(number "B44"
						(effects
							(font
								(size 1.27 1.27)
							)
						)
					)
				)
				(pin input line
					(at 0 -35.56 180)
					(length 5.08)
					(name "~{USB_2_3_OC}"
						(effects
							(font
								(size 1.27 1.27)
							)
						)
					)
					(number "A44"
						(effects
							(font
								(size 1.27 1.27)
							)
						)
					)
				)
			)
			(symbol "Plug_Bus_CE7_EPT_401-51501-51_8_1"
				(rectangle
					(start -33.02 2.54)
					(end -5.08 -17.78)
					(stroke
						(width 0.254)
						(type default)
					)
					(fill
						(type background)
					)
				)
				(text "A/B"
					(at -31.75 0 0)
					(effects
						(font
							(size 1.27 1.27)
							(thickness 0.15)
						)
						(justify left bottom)
					)
				)
				(text "POWER"
					(at -31.75 -16.51 0)
					(effects
						(font
							(size 1.27 1.27)
							(thickness 0.15)
						)
						(justify left bottom)
					)
				)
				(pin no_connect line
					(at -33.02 -2.54 0)
					(length 5.08)
					(hide yes)
					(name "RSVD"
						(effects
							(font
								(size 1.27 1.27)
							)
						)
					)
					(number "A29"
						(effects
							(font
								(size 1.27 1.27)
							)
						)
					)
				)
				(pin no_connect line
					(at -33.02 -3.81 0)
					(length 5.08)
					(hide yes)
					(name "RSVD"
						(effects
							(font
								(size 1.27 1.27)
							)
						)
					)
					(number "A30"
						(effects
							(font
								(size 1.27 1.27)
							)
						)
					)
				)
				(pin no_connect line
					(at -33.02 -5.08 0)
					(length 5.08)
					(hide yes)
					(name "RSVD"
						(effects
							(font
								(size 1.27 1.27)
							)
						)
					)
					(number "A32"
						(effects
							(font
								(size 1.27 1.27)
							)
						)
					)
				)
				(pin no_connect line
					(at -33.02 -6.35 0)
					(length 5.08)
					(hide yes)
					(name "RSVD"
						(effects
							(font
								(size 1.27 1.27)
							)
						)
					)
					(number "A33"
						(effects
							(font
								(size 1.27 1.27)
							)
						)
					)
				)
				(pin no_connect line
					(at -33.02 -7.62 0)
					(length 5.08)
					(hide yes)
					(name "RSVD"
						(effects
							(font
								(size 1.27 1.27)
							)
						)
					)
					(number "A48"
						(effects
							(font
								(size 1.27 1.27)
							)
						)
					)
				)
				(pin no_connect line
					(at -33.02 -8.89 0)
					(length 5.08)
					(hide yes)
					(name "RSVD"
						(effects
							(font
								(size 1.27 1.27)
							)
						)
					)
					(number "A86"
						(effects
							(font
								(size 1.27 1.27)
							)
						)
					)
				)
				(pin no_connect line
					(at -33.02 -10.16 0)
					(length 5.08)
					(hide yes)
					(name "RSVD"
						(effects
							(font
								(size 1.27 1.27)
							)
						)
					)
					(number "A87"
						(effects
							(font
								(size 1.27 1.27)
							)
						)
					)
				)
				(pin no_connect line
					(at -33.02 -11.43 0)
					(length 5.08)
					(hide yes)
					(name "RSVD"
						(effects
							(font
								(size 1.27 1.27)
							)
						)
					)
					(number "B28"
						(effects
							(font
								(size 1.27 1.27)
							)
						)
					)
				)
				(pin no_connect line
					(at -33.02 -12.7 0)
					(length 5.08)
					(hide yes)
					(name "RSVD"
						(effects
							(font
								(size 1.27 1.27)
							)
						)
					)
					(number "B29"
						(effects
							(font
								(size 1.27 1.27)
							)
						)
					)
				)
				(pin no_connect line
					(at -33.02 -13.97 0)
					(length 5.08)
					(hide yes)
					(name "RSVD"
						(effects
							(font
								(size 1.27 1.27)
							)
						)
					)
					(number "B30"
						(effects
							(font
								(size 1.27 1.27)
							)
						)
					)
				)
				(pin power_in line
					(at 0 0 180)
					(length 5.08)
					(name "VCC_12V"
						(effects
							(font
								(size 1.27 1.27)
							)
						)
					)
					(number "A104"
						(effects
							(font
								(size 1.27 1.27)
							)
						)
					)
				)
				(pin passive line
					(at 0 0 180)
					(length 5.08)
					(hide yes)
					(name "VCC_12V"
						(effects
							(font
								(size 1.27 1.27)
							)
						)
					)
					(number "A105"
						(effects
							(font
								(size 1.27 1.27)
							)
						)
					)
				)
				(pin passive line
					(at 0 0 180)
					(length 5.08)
					(hide yes)
					(name "VCC_12V"
						(effects
							(font
								(size 1.27 1.27)
							)
						)
					)
					(number "A106"
						(effects
							(font
								(size 1.27 1.27)
							)
						)
					)
				)
				(pin passive line
					(at 0 0 180)
					(length 5.08)
					(hide yes)
					(name "VCC_12V"
						(effects
							(font
								(size 1.27 1.27)
							)
						)
					)
					(number "A107"
						(effects
							(font
								(size 1.27 1.27)
							)
						)
					)
				)
				(pin passive line
					(at 0 0 180)
					(length 5.08)
					(hide yes)
					(name "VCC_12V"
						(effects
							(font
								(size 1.27 1.27)
							)
						)
					)
					(number "A108"
						(effects
							(font
								(size 1.27 1.27)
							)
						)
					)
				)
				(pin passive line
					(at 0 0 180)
					(length 5.08)
					(hide yes)
					(name "VCC_12V"
						(effects
							(font
								(size 1.27 1.27)
							)
						)
					)
					(number "A109"
						(effects
							(font
								(size 1.27 1.27)
							)
						)
					)
				)
				(pin passive line
					(at 0 0 180)
					(length 5.08)
					(hide yes)
					(name "VCC_12V"
						(effects
							(font
								(size 1.27 1.27)
							)
						)
					)
					(number "B104"
						(effects
							(font
								(size 1.27 1.27)
							)
						)
					)
				)
				(pin passive line
					(at 0 0 180)
					(length 5.08)
					(hide yes)
					(name "VCC_12V"
						(effects
							(font
								(size 1.27 1.27)
							)
						)
					)
					(number "B105"
						(effects
							(font
								(size 1.27 1.27)
							)
						)
					)
				)
				(pin passive line
					(at 0 0 180)
					(length 5.08)
					(hide yes)
					(name "VCC_12V"
						(effects
							(font
								(size 1.27 1.27)
							)
						)
					)
					(number "B106"
						(effects
							(font
								(size 1.27 1.27)
							)
						)
					)
				)
				(pin passive line
					(at 0 0 180)
					(length 5.08)
					(hide yes)
					(name "VCC_12V"
						(effects
							(font
								(size 1.27 1.27)
							)
						)
					)
					(number "B107"
						(effects
							(font
								(size 1.27 1.27)
							)
						)
					)
				)
				(pin passive line
					(at 0 0 180)
					(length 5.08)
					(hide yes)
					(name "VCC_12V"
						(effects
							(font
								(size 1.27 1.27)
							)
						)
					)
					(number "B108"
						(effects
							(font
								(size 1.27 1.27)
							)
						)
					)
				)
				(pin passive line
					(at 0 0 180)
					(length 5.08)
					(hide yes)
					(name "VCC_12V"
						(effects
							(font
								(size 1.27 1.27)
							)
						)
					)
					(number "B109"
						(effects
							(font
								(size 1.27 1.27)
							)
						)
					)
				)
				(pin power_in line
					(at 0 -2.54 180)
					(length 5.08)
					(name "VCC_RTC"
						(effects
							(font
								(size 1.27 1.27)
							)
						)
					)
					(number "A47"
						(effects
							(font
								(size 1.27 1.27)
							)
						)
					)
				)
				(pin power_in line
					(at 0 -5.08 180)
					(length 5.08)
					(name "VCC_5V_SBY"
						(effects
							(font
								(size 1.27 1.27)
							)
						)
					)
					(number "B84"
						(effects
							(font
								(size 1.27 1.27)
							)
						)
					)
				)
				(pin passive line
					(at 0 -5.08 180)
					(length 5.08)
					(hide yes)
					(name "VCC_5V_SBY"
						(effects
							(font
								(size 1.27 1.27)
							)
						)
					)
					(number "B85"
						(effects
							(font
								(size 1.27 1.27)
							)
						)
					)
				)
				(pin passive line
					(at 0 -5.08 180)
					(length 5.08)
					(hide yes)
					(name "VCC_5V_SBY"
						(effects
							(font
								(size 1.27 1.27)
							)
						)
					)
					(number "B86"
						(effects
							(font
								(size 1.27 1.27)
							)
						)
					)
				)
				(pin passive line
					(at 0 -5.08 180)
					(length 5.08)
					(hide yes)
					(name "VCC_5V_SBY"
						(effects
							(font
								(size 1.27 1.27)
							)
						)
					)
					(number "B87"
						(effects
							(font
								(size 1.27 1.27)
							)
						)
					)
				)
				(pin power_in line
					(at 0 -12.7 180)
					(length 5.08)
					(name "GND(FIXED)"
						(effects
							(font
								(size 1.27 1.27)
							)
						)
					)
					(number "A1"
						(effects
							(font
								(size 1.27 1.27)
							)
						)
					)
				)
				(pin passive line
					(at 0 -12.7 180)
					(length 5.08)
					(hide yes)
					(name "GND(FIXED)"
						(effects
							(font
								(size 1.27 1.27)
							)
						)
					)
					(number "A100"
						(effects
							(font
								(size 1.27 1.27)
							)
						)
					)
				)
				(pin passive line
					(at 0 -12.7 180)
					(length 5.08)
					(hide yes)
					(name "GND(FIXED)"
						(effects
							(font
								(size 1.27 1.27)
							)
						)
					)
					(number "A11"
						(effects
							(font
								(size 1.27 1.27)
							)
						)
					)
				)
				(pin passive line
					(at 0 -12.7 180)
					(length 5.08)
					(hide yes)
					(name "GND(FIXED)"
						(effects
							(font
								(size 1.27 1.27)
							)
						)
					)
					(number "A110"
						(effects
							(font
								(size 1.27 1.27)
							)
						)
					)
				)
				(pin passive line
					(at 0 -12.7 180)
					(length 5.08)
					(hide yes)
					(name "GND(FIXED)"
						(effects
							(font
								(size 1.27 1.27)
							)
						)
					)
					(number "A21"
						(effects
							(font
								(size 1.27 1.27)
							)
						)
					)
				)
				(pin passive line
					(at 0 -12.7 180)
					(length 5.08)
					(hide yes)
					(name "GND(FIXED)"
						(effects
							(font
								(size 1.27 1.27)
							)
						)
					)
					(number "A31"
						(effects
							(font
								(size 1.27 1.27)
							)
						)
					)
				)
				(pin passive line
					(at 0 -12.7 180)
					(length 5.08)
					(hide yes)
					(name "GND(FIXED)"
						(effects
							(font
								(size 1.27 1.27)
							)
						)
					)
					(number "A41"
						(effects
							(font
								(size 1.27 1.27)
							)
						)
					)
				)
				(pin passive line
					(at 0 -12.7 180)
					(length 5.08)
					(hide yes)
					(name "GND(FIXED)"
						(effects
							(font
								(size 1.27 1.27)
							)
						)
					)
					(number "A51"
						(effects
							(font
								(size 1.27 1.27)
							)
						)
					)
				)
				(pin passive line
					(at 0 -12.7 180)
					(length 5.08)
					(hide yes)
					(name "GND(FIXED)"
						(effects
							(font
								(size 1.27 1.27)
							)
						)
					)
					(number "A60"
						(effects
							(font
								(size 1.27 1.27)
							)
						)
					)
				)
				(pin passive line
					(at 0 -12.7 180)
					(length 5.08)
					(hide yes)
					(name "GND(FIXED)"
						(effects
							(font
								(size 1.27 1.27)
							)
						)
					)
					(number "A70"
						(effects
							(font
								(size 1.27 1.27)
							)
						)
					)
				)
				(pin passive line
					(at 0 -12.7 180)
					(length 5.08)
					(hide yes)
					(name "GND(FIXED)"
						(effects
							(font
								(size 1.27 1.27)
							)
						)
					)
					(number "A80"
						(effects
							(font
								(size 1.27 1.27)
							)
						)
					)
				)
				(pin passive line
					(at 0 -12.7 180)
					(length 5.08)
					(hide yes)
					(name "GND(FIXED)"
						(effects
							(font
								(size 1.27 1.27)
							)
						)
					)
					(number "A90"
						(effects
							(font
								(size 1.27 1.27)
							)
						)
					)
				)
				(pin passive line
					(at 0 -12.7 180)
					(length 5.08)
					(hide yes)
					(name "GND(FIXED)"
						(effects
							(font
								(size 1.27 1.27)
							)
						)
					)
					(number "B1"
						(effects
							(font
								(size 1.27 1.27)
							)
						)
					)
				)
				(pin passive line
					(at 0 -12.7 180)
					(length 5.08)
					(hide yes)
					(name "GND(FIXED)"
						(effects
							(font
								(size 1.27 1.27)
							)
						)
					)
					(number "B100"
						(effects
							(font
								(size 1.27 1.27)
							)
						)
					)
				)
				(pin passive line
					(at 0 -12.7 180)
					(length 5.08)
					(hide yes)
					(name "GND(FIXED)"
						(effects
							(font
								(size 1.27 1.27)
							)
						)
					)
					(number "B11"
						(effects
							(font
								(size 1.27 1.27)
							)
						)
					)
				)
				(pin passive line
					(at 0 -12.7 180)
					(length 5.08)
					(hide yes)
					(name "GND(FIXED)"
						(effects
							(font
								(size 1.27 1.27)
							)
						)
					)
					(number "B110"
						(effects
							(font
								(size 1.27 1.27)
							)
						)
					)
				)
				(pin passive line
					(at 0 -12.7 180)
					(length 5.08)
					(hide yes)
					(name "GND(FIXED)"
						(effects
							(font
								(size 1.27 1.27)
							)
						)
					)
					(number "B21"
						(effects
							(font
								(size 1.27 1.27)
							)
						)
					)
				)
				(pin passive line
					(at 0 -12.7 180)
					(length 5.08)
					(hide yes)
					(name "GND(FIXED)"
						(effects
							(font
								(size 1.27 1.27)
							)
						)
					)
					(number "B31"
						(effects
							(font
								(size 1.27 1.27)
							)
						)
					)
				)
				(pin passive line
					(at 0 -12.7 180)
					(length 5.08)
					(hide yes)
					(name "GND(FIXED)"
						(effects
							(font
								(size 1.27 1.27)
							)
						)
					)
					(number "B41"
						(effects
							(font
								(size 1.27 1.27)
							)
						)
					)
				)
				(pin passive line
					(at 0 -12.7 180)
					(length 5.08)
					(hide yes)
					(name "GND(FIXED)"
						(effects
							(font
								(size 1.27 1.27)
							)
						)
					)
					(number "B51"
						(effects
							(font
								(size 1.27 1.27)
							)
						)
					)
				)
				(pin passive line
					(at 0 -12.7 180)
					(length 5.08)
					(hide yes)
					(name "GND(FIXED)"
						(effects
							(font
								(size 1.27 1.27)
							)
						)
					)
					(number "B60"
						(effects
							(font
								(size 1.27 1.27)
							)
						)
					)
				)
				(pin passive line
					(at 0 -12.7 180)
					(length 5.08)
					(hide yes)
					(name "GND(FIXED)"
						(effects
							(font
								(size 1.27 1.27)
							)
						)
					)
					(number "B70"
						(effects
							(font
								(size 1.27 1.27)
							)
						)
					)
				)
				(pin passive line
					(at 0 -12.7 180)
					(length 5.08)
					(hide yes)
					(name "GND(FIXED)"
						(effects
							(font
								(size 1.27 1.27)
							)
						)
					)
					(number "B80"
						(effects
							(font
								(size 1.27 1.27)
							)
						)
					)
				)
				(pin passive line
					(at 0 -12.7 180)
					(length 5.08)
					(hide yes)
					(name "GND(FIXED)"
						(effects
							(font
								(size 1.27 1.27)
							)
						)
					)
					(number "B90"
						(effects
							(font
								(size 1.27 1.27)
							)
						)
					)
				)
				(pin power_in line
					(at 0 -15.24 180)
					(length 5.08)
					(name "GND"
						(effects
							(font
								(size 1.27 1.27)
							)
						)
					)
					(number "A38"
						(effects
							(font
								(size 1.27 1.27)
							)
						)
					)
				)
				(pin passive line
					(at 0 -15.24 180)
					(length 5.08)
					(hide yes)
					(name "GND"
						(effects
							(font
								(size 1.27 1.27)
							)
						)
					)
					(number "A57"
						(effects
							(font
								(size 1.27 1.27)
							)
						)
					)
				)
				(pin passive line
					(at 0 -15.24 180)
					(length 5.08)
					(hide yes)
					(name "GND"
						(effects
							(font
								(size 1.27 1.27)
							)
						)
					)
					(number "A66"
						(effects
							(font
								(size 1.27 1.27)
							)
						)
					)
				)
				(pin passive line
					(at 0 -15.24 180)
					(length 5.08)
					(hide yes)
					(name "GND"
						(effects
							(font
								(size 1.27 1.27)
							)
						)
					)
					(number "A73"
						(effects
							(font
								(size 1.27 1.27)
							)
						)
					)
				)
				(pin passive line
					(at 0 -15.24 180)
					(length 5.08)
					(hide yes)
					(name "GND"
						(effects
							(font
								(size 1.27 1.27)
							)
						)
					)
					(number "A76"
						(effects
							(font
								(size 1.27 1.27)
							)
						)
					)
				)
				(pin passive line
					(at 0 -15.24 180)
					(length 5.08)
					(hide yes)
					(name "GND"
						(effects
							(font
								(size 1.27 1.27)
							)
						)
					)
					(number "A79"
						(effects
							(font
								(size 1.27 1.27)
							)
						)
					)
				)
				(pin passive line
					(at 0 -15.24 180)
					(length 5.08)
					(hide yes)
					(name "GND"
						(effects
							(font
								(size 1.27 1.27)
							)
						)
					)
					(number "A83"
						(effects
							(font
								(size 1.27 1.27)
							)
						)
					)
				)
				(pin passive line
					(at 0 -15.24 180)
					(length 5.08)
					(hide yes)
					(name "GND"
						(effects
							(font
								(size 1.27 1.27)
							)
						)
					)
					(number "B38"
						(effects
							(font
								(size 1.27 1.27)
							)
						)
					)
				)
				(pin passive line
					(at 0 -15.24 180)
					(length 5.08)
					(hide yes)
					(name "GND"
						(effects
							(font
								(size 1.27 1.27)
							)
						)
					)
					(number "B73"
						(effects
							(font
								(size 1.27 1.27)
							)
						)
					)
				)
				(pin passive line
					(at 0 -15.24 180)
					(length 5.08)
					(hide yes)
					(name "GND"
						(effects
							(font
								(size 1.27 1.27)
							)
						)
					)
					(number "B76"
						(effects
							(font
								(size 1.27 1.27)
							)
						)
					)
				)
				(pin passive line
					(at 0 -15.24 180)
					(length 5.08)
					(hide yes)
					(name "GND"
						(effects
							(font
								(size 1.27 1.27)
							)
						)
					)
					(number "B79"
						(effects
							(font
								(size 1.27 1.27)
							)
						)
					)
				)
				(pin passive line
					(at 0 -15.24 180)
					(length 5.08)
					(hide yes)
					(name "GND"
						(effects
							(font
								(size 1.27 1.27)
							)
						)
					)
					(number "B83"
						(effects
							(font
								(size 1.27 1.27)
							)
						)
					)
				)
			)
			(symbol "Plug_Bus_CE7_EPT_401-51501-51_9_1"
				(rectangle
					(start -33.02 2.54)
					(end -5.08 -119.38)
					(stroke
						(width 0.254)
						(type default)
					)
					(fill
						(type background)
					)
				)
				(text "A/B"
					(at -31.75 0 0)
					(effects
						(font
							(size 1.27 1.27)
							(thickness 0.15)
						)
						(justify left bottom)
					)
				)
				(text "PCIe"
					(at -31.75 -118.11 0)
					(effects
						(font
							(size 1.27 1.27)
							(thickness 0.15)
						)
						(justify left bottom)
					)
				)
				(pin output line
					(at 0 0 180)
					(length 5.08)
					(name "PCIE_TX15+"
						(effects
							(font
								(size 1.27 1.27)
							)
						)
					)
					(number "A22"
						(effects
							(font
								(size 1.27 1.27)
							)
						)
					)
				)
				(pin output line
					(at 0 -2.54 180)
					(length 5.08)
					(name "PCIE_TX15-"
						(effects
							(font
								(size 1.27 1.27)
							)
						)
					)
					(number "A23"
						(effects
							(font
								(size 1.27 1.27)
							)
						)
					)
				)
				(pin input line
					(at 0 -7.62 180)
					(length 5.08)
					(name "PCIE_RX15+"
						(effects
							(font
								(size 1.27 1.27)
							)
						)
					)
					(number "B22"
						(effects
							(font
								(size 1.27 1.27)
							)
						)
					)
				)
				(pin input line
					(at 0 -10.16 180)
					(length 5.08)
					(name "PCIE_RX15-"
						(effects
							(font
								(size 1.27 1.27)
							)
						)
					)
					(number "B23"
						(effects
							(font
								(size 1.27 1.27)
							)
						)
					)
				)
				(pin output line
					(at 0 -15.24 180)
					(length 5.08)
					(name "PCIE_TX14+"
						(effects
							(font
								(size 1.27 1.27)
							)
						)
					)
					(number "A25"
						(effects
							(font
								(size 1.27 1.27)
							)
						)
					)
				)
				(pin output line
					(at 0 -17.78 180)
					(length 5.08)
					(name "PCIE_TX14-"
						(effects
							(font
								(size 1.27 1.27)
							)
						)
					)
					(number "A26"
						(effects
							(font
								(size 1.27 1.27)
							)
						)
					)
				)
				(pin input line
					(at 0 -22.86 180)
					(length 5.08)
					(name "PCIE_RX14+"
						(effects
							(font
								(size 1.27 1.27)
							)
						)
					)
					(number "B25"
						(effects
							(font
								(size 1.27 1.27)
							)
						)
					)
				)
				(pin input line
					(at 0 -25.4 180)
					(length 5.08)
					(name "PCIE_RX14-"
						(effects
							(font
								(size 1.27 1.27)
							)
						)
					)
					(number "B26"
						(effects
							(font
								(size 1.27 1.27)
							)
						)
					)
				)
				(pin output line
					(at 0 -30.48 180)
					(length 5.08)
					(name "PCIE_TX13+"
						(effects
							(font
								(size 1.27 1.27)
							)
						)
					)
					(number "A36"
						(effects
							(font
								(size 1.27 1.27)
							)
						)
					)
				)
				(pin output line
					(at 0 -33.02 180)
					(length 5.08)
					(name "PCIE_TX13-"
						(effects
							(font
								(size 1.27 1.27)
							)
						)
					)
					(number "A37"
						(effects
							(font
								(size 1.27 1.27)
							)
						)
					)
				)
				(pin input line
					(at 0 -38.1 180)
					(length 5.08)
					(name "PCIE_RX13+"
						(effects
							(font
								(size 1.27 1.27)
							)
						)
					)
					(number "B36"
						(effects
							(font
								(size 1.27 1.27)
							)
						)
					)
				)
				(pin input line
					(at 0 -40.64 180)
					(length 5.08)
					(name "PCIE_RX13-"
						(effects
							(font
								(size 1.27 1.27)
							)
						)
					)
					(number "B37"
						(effects
							(font
								(size 1.27 1.27)
							)
						)
					)
				)
				(pin output line
					(at 0 -45.72 180)
					(length 5.08)
					(name "PCIE_TX12+"
						(effects
							(font
								(size 1.27 1.27)
							)
						)
					)
					(number "A39"
						(effects
							(font
								(size 1.27 1.27)
							)
						)
					)
				)
				(pin output line
					(at 0 -48.26 180)
					(length 5.08)
					(name "PCIE_TX12-"
						(effects
							(font
								(size 1.27 1.27)
							)
						)
					)
					(number "A40"
						(effects
							(font
								(size 1.27 1.27)
							)
						)
					)
				)
				(pin input line
					(at 0 -53.34 180)
					(length 5.08)
					(name "PCIE_RX12+"
						(effects
							(font
								(size 1.27 1.27)
							)
						)
					)
					(number "B39"
						(effects
							(font
								(size 1.27 1.27)
							)
						)
					)
				)
				(pin input line
					(at 0 -55.88 180)
					(length 5.08)
					(name "PCIE_RX12-"
						(effects
							(font
								(size 1.27 1.27)
							)
						)
					)
					(number "B40"
						(effects
							(font
								(size 1.27 1.27)
							)
						)
					)
				)
				(pin output line
					(at 0 -60.96 180)
					(length 5.08)
					(name "PCIE_TX11+"
						(effects
							(font
								(size 1.27 1.27)
							)
						)
					)
					(number "A81"
						(effects
							(font
								(size 1.27 1.27)
							)
						)
					)
				)
				(pin output line
					(at 0 -63.5 180)
					(length 5.08)
					(name "PCIE_TX11-"
						(effects
							(font
								(size 1.27 1.27)
							)
						)
					)
					(number "A82"
						(effects
							(font
								(size 1.27 1.27)
							)
						)
					)
				)
				(pin input line
					(at 0 -68.58 180)
					(length 5.08)
					(name "PCIE_RX11+"
						(effects
							(font
								(size 1.27 1.27)
							)
						)
					)
					(number "B81"
						(effects
							(font
								(size 1.27 1.27)
							)
						)
					)
				)
				(pin input line
					(at 0 -71.12 180)
					(length 5.08)
					(name "PCIE_RX11-"
						(effects
							(font
								(size 1.27 1.27)
							)
						)
					)
					(number "B82"
						(effects
							(font
								(size 1.27 1.27)
							)
						)
					)
				)
				(pin output line
					(at 0 -76.2 180)
					(length 5.08)
					(name "PCIE_TX10+"
						(effects
							(font
								(size 1.27 1.27)
							)
						)
					)
					(number "A77"
						(effects
							(font
								(size 1.27 1.27)
							)
						)
					)
				)
				(pin output line
					(at 0 -78.74 180)
					(length 5.08)
					(name "PCIE_TX10-"
						(effects
							(font
								(size 1.27 1.27)
							)
						)
					)
					(number "A78"
						(effects
							(font
								(size 1.27 1.27)
							)
						)
					)
				)
				(pin input line
					(at 0 -83.82 180)
					(length 5.08)
					(name "PCIE_RX10+"
						(effects
							(font
								(size 1.27 1.27)
							)
						)
					)
					(number "B77"
						(effects
							(font
								(size 1.27 1.27)
							)
						)
					)
				)
				(pin input line
					(at 0 -86.36 180)
					(length 5.08)
					(name "PCIE_RX10-"
						(effects
							(font
								(size 1.27 1.27)
							)
						)
					)
					(number "B78"
						(effects
							(font
								(size 1.27 1.27)
							)
						)
					)
				)
				(pin output line
					(at 0 -91.44 180)
					(length 5.08)
					(name "PCIE_TX9+"
						(effects
							(font
								(size 1.27 1.27)
							)
						)
					)
					(number "A74"
						(effects
							(font
								(size 1.27 1.27)
							)
						)
					)
				)
				(pin output line
					(at 0 -93.98 180)
					(length 5.08)
					(name "PCIE_TX9-"
						(effects
							(font
								(size 1.27 1.27)
							)
						)
					)
					(number "A75"
						(effects
							(font
								(size 1.27 1.27)
							)
						)
					)
				)
				(pin input line
					(at 0 -99.06 180)
					(length 5.08)
					(name "PCIE_RX9+"
						(effects
							(font
								(size 1.27 1.27)
							)
						)
					)
					(number "B74"
						(effects
							(font
								(size 1.27 1.27)
							)
						)
					)
				)
				(pin input line
					(at 0 -101.6 180)
					(length 5.08)
					(name "PCIE_RX9-"
						(effects
							(font
								(size 1.27 1.27)
							)
						)
					)
					(number "B75"
						(effects
							(font
								(size 1.27 1.27)
							)
						)
					)
				)
				(pin output line
					(at 0 -106.68 180)
					(length 5.08)
					(name "PCIE_TX8+"
						(effects
							(font
								(size 1.27 1.27)
							)
						)
					)
					(number "A71"
						(effects
							(font
								(size 1.27 1.27)
							)
						)
					)
				)
				(pin output line
					(at 0 -109.22 180)
					(length 5.08)
					(name "PCIE_TX8-"
						(effects
							(font
								(size 1.27 1.27)
							)
						)
					)
					(number "A72"
						(effects
							(font
								(size 1.27 1.27)
							)
						)
					)
				)
				(pin input line
					(at 0 -114.3 180)
					(length 5.08)
					(name "PCIE_RX8+"
						(effects
							(font
								(size 1.27 1.27)
							)
						)
					)
					(number "B71"
						(effects
							(font
								(size 1.27 1.27)
							)
						)
					)
				)
				(pin input line
					(at 0 -116.84 180)
					(length 5.08)
					(name "PCIE_RX8-"
						(effects
							(font
								(size 1.27 1.27)
							)
						)
					)
					(number "B72"
						(effects
							(font
								(size 1.27 1.27)
							)
						)
					)
				)
			)
			(symbol "Plug_Bus_CE7_EPT_401-51501-51_10_1"
				(rectangle
					(start -33.02 2.54)
					(end -5.08 -58.42)
					(stroke
						(width 0.254)
						(type default)
					)
					(fill
						(type background)
					)
				)
				(text "C/D"
					(at -31.75 0 0)
					(effects
						(font
							(size 1.27 1.27)
							(thickness 0.15)
						)
						(justify left bottom)
					)
				)
				(text "USBSS"
					(at -31.75 -57.15 0)
					(effects
						(font
							(size 1.27 1.27)
							(thickness 0.15)
						)
						(justify left bottom)
					)
				)
				(pin output line
					(at 0 0 180)
					(length 5.08)
					(name "USB_SSTX3+"
						(effects
							(font
								(size 1.27 1.27)
							)
						)
					)
					(number "D13"
						(effects
							(font
								(size 1.27 1.27)
							)
						)
					)
				)
				(pin output line
					(at 0 -2.54 180)
					(length 5.08)
					(name "USB_SSTX3-"
						(effects
							(font
								(size 1.27 1.27)
							)
						)
					)
					(number "D12"
						(effects
							(font
								(size 1.27 1.27)
							)
						)
					)
				)
				(pin input line
					(at 0 -7.62 180)
					(length 5.08)
					(name "USB_SSRX3+"
						(effects
							(font
								(size 1.27 1.27)
							)
						)
					)
					(number "C13"
						(effects
							(font
								(size 1.27 1.27)
							)
						)
					)
				)
				(pin input line
					(at 0 -10.16 180)
					(length 5.08)
					(name "USB_SSRX3-"
						(effects
							(font
								(size 1.27 1.27)
							)
						)
					)
					(number "C12"
						(effects
							(font
								(size 1.27 1.27)
							)
						)
					)
				)
				(pin output line
					(at 0 -15.24 180)
					(length 5.08)
					(name "USB_SSTX2+"
						(effects
							(font
								(size 1.27 1.27)
							)
						)
					)
					(number "D10"
						(effects
							(font
								(size 1.27 1.27)
							)
						)
					)
				)
				(pin output line
					(at 0 -17.78 180)
					(length 5.08)
					(name "USB_SSTX2-"
						(effects
							(font
								(size 1.27 1.27)
							)
						)
					)
					(number "D9"
						(effects
							(font
								(size 1.27 1.27)
							)
						)
					)
				)
				(pin input line
					(at 0 -22.86 180)
					(length 5.08)
					(name "USB_SSRX2+"
						(effects
							(font
								(size 1.27 1.27)
							)
						)
					)
					(number "C10"
						(effects
							(font
								(size 1.27 1.27)
							)
						)
					)
				)
				(pin input line
					(at 0 -25.4 180)
					(length 5.08)
					(name "USB_SSRX2-"
						(effects
							(font
								(size 1.27 1.27)
							)
						)
					)
					(number "C9"
						(effects
							(font
								(size 1.27 1.27)
							)
						)
					)
				)
				(pin output line
					(at 0 -30.48 180)
					(length 5.08)
					(name "USB_SSTX1+"
						(effects
							(font
								(size 1.27 1.27)
							)
						)
					)
					(number "D7"
						(effects
							(font
								(size 1.27 1.27)
							)
						)
					)
				)
				(pin output line
					(at 0 -33.02 180)
					(length 5.08)
					(name "USB_SSTX1-"
						(effects
							(font
								(size 1.27 1.27)
							)
						)
					)
					(number "D6"
						(effects
							(font
								(size 1.27 1.27)
							)
						)
					)
				)
				(pin input line
					(at 0 -38.1 180)
					(length 5.08)
					(name "USB_SSRX1+"
						(effects
							(font
								(size 1.27 1.27)
							)
						)
					)
					(number "C7"
						(effects
							(font
								(size 1.27 1.27)
							)
						)
					)
				)
				(pin input line
					(at 0 -40.64 180)
					(length 5.08)
					(name "USB_SSRX1-"
						(effects
							(font
								(size 1.27 1.27)
							)
						)
					)
					(number "C6"
						(effects
							(font
								(size 1.27 1.27)
							)
						)
					)
				)
				(pin output line
					(at 0 -45.72 180)
					(length 5.08)
					(name "USB_SSTX0+"
						(effects
							(font
								(size 1.27 1.27)
							)
						)
					)
					(number "D4"
						(effects
							(font
								(size 1.27 1.27)
							)
						)
					)
				)
				(pin output line
					(at 0 -48.26 180)
					(length 5.08)
					(name "USB_SSTX0-"
						(effects
							(font
								(size 1.27 1.27)
							)
						)
					)
					(number "D3"
						(effects
							(font
								(size 1.27 1.27)
							)
						)
					)
				)
				(pin input line
					(at 0 -53.34 180)
					(length 5.08)
					(name "USB_SSRX0+"
						(effects
							(font
								(size 1.27 1.27)
							)
						)
					)
					(number "C4"
						(effects
							(font
								(size 1.27 1.27)
							)
						)
					)
				)
				(pin input line
					(at 0 -55.88 180)
					(length 5.08)
					(name "USB_SSRX0-"
						(effects
							(font
								(size 1.27 1.27)
							)
						)
					)
					(number "C3"
						(effects
							(font
								(size 1.27 1.27)
							)
						)
					)
				)
			)
			(symbol "Plug_Bus_CE7_EPT_401-51501-51_11_1"
				(rectangle
					(start -33.02 2.54)
					(end -5.08 -154.94)
					(stroke
						(width 0.254)
						(type default)
					)
					(fill
						(type background)
					)
				)
				(text "C/D"
					(at -31.75 0 0)
					(effects
						(font
							(size 1.27 1.27)
							(thickness 0.15)
						)
						(justify left bottom)
					)
				)
				(text "10GBaseKR"
					(at -31.75 -153.67 0)
					(effects
						(font
							(size 1.27 1.27)
							(thickness 0.15)
						)
						(justify left bottom)
					)
				)
				(pin output line
					(at 0 0 180)
					(length 5.08)
					(name "10G_KR_TX3+"
						(effects
							(font
								(size 1.27 1.27)
							)
						)
					)
					(number "D26"
						(effects
							(font
								(size 1.27 1.27)
							)
						)
					)
				)
				(pin output line
					(at 0 -2.54 180)
					(length 5.08)
					(name "10G_KR_TX3-"
						(effects
							(font
								(size 1.27 1.27)
							)
						)
					)
					(number "D27"
						(effects
							(font
								(size 1.27 1.27)
							)
						)
					)
				)
				(pin input line
					(at 0 -7.62 180)
					(length 5.08)
					(name "10G_KR_RX3+"
						(effects
							(font
								(size 1.27 1.27)
							)
						)
					)
					(number "C26"
						(effects
							(font
								(size 1.27 1.27)
							)
						)
					)
				)
				(pin input line
					(at 0 -10.16 180)
					(length 5.08)
					(name "10G_KR_RX3-"
						(effects
							(font
								(size 1.27 1.27)
							)
						)
					)
					(number "C27"
						(effects
							(font
								(size 1.27 1.27)
							)
						)
					)
				)
				(pin output line
					(at 0 -15.24 180)
					(length 5.08)
					(name "10G_KR_TX2+"
						(effects
							(font
								(size 1.27 1.27)
							)
						)
					)
					(number "D29"
						(effects
							(font
								(size 1.27 1.27)
							)
						)
					)
				)
				(pin output line
					(at 0 -17.78 180)
					(length 5.08)
					(name "10G_KR_TX2-"
						(effects
							(font
								(size 1.27 1.27)
							)
						)
					)
					(number "D30"
						(effects
							(font
								(size 1.27 1.27)
							)
						)
					)
				)
				(pin input line
					(at 0 -22.86 180)
					(length 5.08)
					(name "10G_KR_RX2+"
						(effects
							(font
								(size 1.27 1.27)
							)
						)
					)
					(number "C29"
						(effects
							(font
								(size 1.27 1.27)
							)
						)
					)
				)
				(pin input line
					(at 0 -25.4 180)
					(length 5.08)
					(name "10G_KR_RX2-"
						(effects
							(font
								(size 1.27 1.27)
							)
						)
					)
					(number "C30"
						(effects
							(font
								(size 1.27 1.27)
							)
						)
					)
				)
				(pin output line
					(at 0 -30.48 180)
					(length 5.08)
					(name "10G_KR_TX1+"
						(effects
							(font
								(size 1.27 1.27)
							)
						)
					)
					(number "D42"
						(effects
							(font
								(size 1.27 1.27)
							)
						)
					)
				)
				(pin output line
					(at 0 -33.02 180)
					(length 5.08)
					(name "10G_KR_TX1-"
						(effects
							(font
								(size 1.27 1.27)
							)
						)
					)
					(number "D43"
						(effects
							(font
								(size 1.27 1.27)
							)
						)
					)
				)
				(pin input line
					(at 0 -38.1 180)
					(length 5.08)
					(name "10G_KR_RX1+"
						(effects
							(font
								(size 1.27 1.27)
							)
						)
					)
					(number "C42"
						(effects
							(font
								(size 1.27 1.27)
							)
						)
					)
				)
				(pin input line
					(at 0 -40.64 180)
					(length 5.08)
					(name "10G_KR_RX1-"
						(effects
							(font
								(size 1.27 1.27)
							)
						)
					)
					(number "C43"
						(effects
							(font
								(size 1.27 1.27)
							)
						)
					)
				)
				(pin output line
					(at 0 -45.72 180)
					(length 5.08)
					(name "10G_KR_TX0+"
						(effects
							(font
								(size 1.27 1.27)
							)
						)
					)
					(number "D49"
						(effects
							(font
								(size 1.27 1.27)
							)
						)
					)
				)
				(pin output line
					(at 0 -48.26 180)
					(length 5.08)
					(name "10G_KR_TX0-"
						(effects
							(font
								(size 1.27 1.27)
							)
						)
					)
					(number "D50"
						(effects
							(font
								(size 1.27 1.27)
							)
						)
					)
				)
				(pin input line
					(at 0 -53.34 180)
					(length 5.08)
					(name "10G_KR_RX0+"
						(effects
							(font
								(size 1.27 1.27)
							)
						)
					)
					(number "C49"
						(effects
							(font
								(size 1.27 1.27)
							)
						)
					)
				)
				(pin input line
					(at 0 -55.88 180)
					(length 5.08)
					(name "10G_KR_RX0-"
						(effects
							(font
								(size 1.27 1.27)
							)
						)
					)
					(number "C50"
						(effects
							(font
								(size 1.27 1.27)
							)
						)
					)
				)
				(pin output line
					(at 0 -60.96 180)
					(length 5.08)
					(name "10G_PHY_RST_01"
						(effects
							(font
								(size 1.27 1.27)
							)
						)
					)
					(number "C35"
						(effects
							(font
								(size 1.27 1.27)
							)
						)
					)
				)
				(pin input line
					(at 0 -63.5 180)
					(length 5.08)
					(name "10G_PHY_CAP_01"
						(effects
							(font
								(size 1.27 1.27)
							)
						)
					)
					(number "D35"
						(effects
							(font
								(size 1.27 1.27)
							)
						)
					)
				)
				(pin open_collector line
					(at 0 -68.58 180)
					(length 5.08)
					(name "10G_SFP_SDA0"
						(effects
							(font
								(size 1.27 1.27)
							)
						)
					)
					(number "C39"
						(effects
							(font
								(size 1.27 1.27)
							)
						)
					)
				)
				(pin open_collector line
					(at 0 -71.12 180)
					(length 5.08)
					(name "10G_SFP_SCL0"
						(effects
							(font
								(size 1.27 1.27)
							)
						)
					)
					(number "D39"
						(effects
							(font
								(size 1.27 1.27)
							)
						)
					)
				)
				(pin open_collector line
					(at 0 -73.66 180)
					(length 5.08)
					(name "10G_PHY_MDIO_SDA0"
						(effects
							(font
								(size 1.27 1.27)
							)
						)
					)
					(number "D46"
						(effects
							(font
								(size 1.27 1.27)
							)
						)
					)
				)
				(pin open_collector line
					(at 0 -76.2 180)
					(length 5.08)
					(name "10G_PHY_MDC_SCL0"
						(effects
							(font
								(size 1.27 1.27)
							)
						)
					)
					(number "C46"
						(effects
							(font
								(size 1.27 1.27)
							)
						)
					)
				)
				(pin input line
					(at 0 -78.74 180)
					(length 5.08)
					(name "10G_INT0"
						(effects
							(font
								(size 1.27 1.27)
							)
						)
					)
					(number "C47"
						(effects
							(font
								(size 1.27 1.27)
							)
						)
					)
				)
				(pin open_collector line
					(at 0 -83.82 180)
					(length 5.08)
					(name "10G_SFP_SDA1"
						(effects
							(font
								(size 1.27 1.27)
							)
						)
					)
					(number "C38"
						(effects
							(font
								(size 1.27 1.27)
							)
						)
					)
				)
				(pin open_collector line
					(at 0 -86.36 180)
					(length 5.08)
					(name "10G_SFP_SCL1"
						(effects
							(font
								(size 1.27 1.27)
							)
						)
					)
					(number "D38"
						(effects
							(font
								(size 1.27 1.27)
							)
						)
					)
				)
				(pin open_collector line
					(at 0 -88.9 180)
					(length 5.08)
					(name "10G_PHY_MDIO_SDA1"
						(effects
							(font
								(size 1.27 1.27)
							)
						)
					)
					(number "D45"
						(effects
							(font
								(size 1.27 1.27)
							)
						)
					)
				)
				(pin open_collector line
					(at 0 -91.44 180)
					(length 5.08)
					(name "10G_PHY_MDC_SCL1"
						(effects
							(font
								(size 1.27 1.27)
							)
						)
					)
					(number "C45"
						(effects
							(font
								(size 1.27 1.27)
							)
						)
					)
				)
				(pin input line
					(at 0 -93.98 180)
					(length 5.08)
					(name "10G_INT1"
						(effects
							(font
								(size 1.27 1.27)
							)
						)
					)
					(number "D47"
						(effects
							(font
								(size 1.27 1.27)
							)
						)
					)
				)
				(pin output line
					(at 0 -99.06 180)
					(length 5.08)
					(name "10G_PHY_RST_23"
						(effects
							(font
								(size 1.27 1.27)
							)
						)
					)
					(number "C34"
						(effects
							(font
								(size 1.27 1.27)
							)
						)
					)
				)
				(pin input line
					(at 0 -101.6 180)
					(length 5.08)
					(name "10G_PHY_CAP_23"
						(effects
							(font
								(size 1.27 1.27)
							)
						)
					)
					(number "D34"
						(effects
							(font
								(size 1.27 1.27)
							)
						)
					)
				)
				(pin open_collector line
					(at 0 -106.68 180)
					(length 5.08)
					(name "10G_SFP_SDA2"
						(effects
							(font
								(size 1.27 1.27)
							)
						)
					)
					(number "C33"
						(effects
							(font
								(size 1.27 1.27)
							)
						)
					)
				)
				(pin open_collector line
					(at 0 -109.22 180)
					(length 5.08)
					(name "10G_SFP_SCL2"
						(effects
							(font
								(size 1.27 1.27)
							)
						)
					)
					(number "D33"
						(effects
							(font
								(size 1.27 1.27)
							)
						)
					)
				)
				(pin open_collector line
					(at 0 -111.76 180)
					(length 5.08)
					(name "10G_PHY_MDIO_SDA2"
						(effects
							(font
								(size 1.27 1.27)
							)
						)
					)
					(number "D16"
						(effects
							(font
								(size 1.27 1.27)
							)
						)
					)
				)
				(pin open_collector line
					(at 0 -114.3 180)
					(length 5.08)
					(name "10G_PHY_MDC_SCL2"
						(effects
							(font
								(size 1.27 1.27)
							)
						)
					)
					(number "C16"
						(effects
							(font
								(size 1.27 1.27)
							)
						)
					)
				)
				(pin input line
					(at 0 -116.84 180)
					(length 5.08)
					(name "10G_INT2"
						(effects
							(font
								(size 1.27 1.27)
							)
						)
					)
					(number "C24"
						(effects
							(font
								(size 1.27 1.27)
							)
						)
					)
				)
				(pin open_collector line
					(at 0 -121.92 180)
					(length 5.08)
					(name "10G_SFP_SDA3"
						(effects
							(font
								(size 1.27 1.27)
							)
						)
					)
					(number "C32"
						(effects
							(font
								(size 1.27 1.27)
							)
						)
					)
				)
				(pin open_collector line
					(at 0 -124.46 180)
					(length 5.08)
					(name "10G_SFP_SCL3"
						(effects
							(font
								(size 1.27 1.27)
							)
						)
					)
					(number "D32"
						(effects
							(font
								(size 1.27 1.27)
							)
						)
					)
				)
				(pin open_collector line
					(at 0 -127 180)
					(length 5.08)
					(name "10G_PHY_MDIO_SDA3"
						(effects
							(font
								(size 1.27 1.27)
							)
						)
					)
					(number "D15"
						(effects
							(font
								(size 1.27 1.27)
							)
						)
					)
				)
				(pin open_collector line
					(at 0 -129.54 180)
					(length 5.08)
					(name "10G_PHY_MDC_SCL3"
						(effects
							(font
								(size 1.27 1.27)
							)
						)
					)
					(number "C15"
						(effects
							(font
								(size 1.27 1.27)
							)
						)
					)
				)
				(pin input line
					(at 0 -132.08 180)
					(length 5.08)
					(name "10G_INT3"
						(effects
							(font
								(size 1.27 1.27)
							)
						)
					)
					(number "D24"
						(effects
							(font
								(size 1.27 1.27)
							)
						)
					)
				)
				(pin bidirectional line
					(at 0 -137.16 180)
					(length 5.08)
					(name "10G_SDP0"
						(effects
							(font
								(size 1.27 1.27)
							)
						)
					)
					(number "C40"
						(effects
							(font
								(size 1.27 1.27)
							)
						)
					)
				)
				(pin bidirectional line
					(at 0 -139.7 180)
					(length 5.08)
					(name "10G_SDP1"
						(effects
							(font
								(size 1.27 1.27)
							)
						)
					)
					(number "D40"
						(effects
							(font
								(size 1.27 1.27)
							)
						)
					)
				)
				(pin bidirectional line
					(at 0 -142.24 180)
					(length 5.08)
					(name "10G_SDP2"
						(effects
							(font
								(size 1.27 1.27)
							)
						)
					)
					(number "C17"
						(effects
							(font
								(size 1.27 1.27)
							)
						)
					)
				)
				(pin bidirectional line
					(at 0 -144.78 180)
					(length 5.08)
					(name "10G_SDP3"
						(effects
							(font
								(size 1.27 1.27)
							)
						)
					)
					(number "D17"
						(effects
							(font
								(size 1.27 1.27)
							)
						)
					)
				)
				(pin open_collector line
					(at 0 -149.86 180)
					(length 5.08)
					(name "10G_LED_SDA"
						(effects
							(font
								(size 1.27 1.27)
							)
						)
					)
					(number "C36"
						(effects
							(font
								(size 1.27 1.27)
							)
						)
					)
				)
				(pin open_collector line
					(at 0 -152.4 180)
					(length 5.08)
					(name "10G_LED_SCL"
						(effects
							(font
								(size 1.27 1.27)
							)
						)
					)
					(number "C37"
						(effects
							(font
								(size 1.27 1.27)
							)
						)
					)
				)
			)
			(symbol "Plug_Bus_CE7_EPT_401-51501-51_12_1"
				(rectangle
					(start -33.02 2.54)
					(end -5.08 -10.16)
					(stroke
						(width 0.254)
						(type default)
					)
					(fill
						(type background)
					)
				)
				(text "C/D"
					(at -31.75 0 0)
					(effects
						(font
							(size 1.27 1.27)
							(thickness 0.15)
						)
						(justify left bottom)
					)
				)
				(text "MGMT"
					(at -31.75 -8.89 0)
					(effects
						(font
							(size 1.27 1.27)
							(thickness 0.15)
						)
						(justify left bottom)
					)
				)
				(pin passive line
					(at 0 0 180)
					(length 5.08)
					(name "~{TYPE0}"
						(effects
							(font
								(size 1.27 1.27)
							)
						)
					)
					(number "C54"
						(effects
							(font
								(size 1.27 1.27)
							)
						)
					)
				)
				(pin passive line
					(at 0 -2.54 180)
					(length 5.08)
					(name "~{TYPE1}"
						(effects
							(font
								(size 1.27 1.27)
							)
						)
					)
					(number "C57"
						(effects
							(font
								(size 1.27 1.27)
							)
						)
					)
				)
				(pin passive line
					(at 0 -5.08 180)
					(length 5.08)
					(name "~{TYPE2}"
						(effects
							(font
								(size 1.27 1.27)
							)
						)
					)
					(number "D57"
						(effects
							(font
								(size 1.27 1.27)
							)
						)
					)
				)
				(pin input line
					(at 0 -7.62 180)
					(length 5.08)
					(name "RAPID_SHUTDOWN"
						(effects
							(font
								(size 1.27 1.27)
							)
						)
					)
					(number "C67"
						(effects
							(font
								(size 1.27 1.27)
							)
						)
					)
				)
			)
			(symbol "Plug_Bus_CE7_EPT_401-51501-51_13_1"
				(rectangle
					(start -33.02 2.54)
					(end -5.08 -17.78)
					(stroke
						(width 0.254)
						(type default)
					)
					(fill
						(type background)
					)
				)
				(text "C/D"
					(at -31.75 0 0)
					(effects
						(font
							(size 1.27 1.27)
							(thickness 0.15)
						)
						(justify left bottom)
					)
				)
				(text "POWER"
					(at -31.75 -16.51 0)
					(effects
						(font
							(size 1.27 1.27)
							(thickness 0.15)
						)
						(justify left bottom)
					)
				)
				(pin no_connect line
					(at -33.02 0 0)
					(length 5.08)
					(hide yes)
					(name "RSVD"
						(effects
							(font
								(size 1.27 1.27)
							)
						)
					)
					(number "D77"
						(effects
							(font
								(size 1.27 1.27)
							)
						)
					)
				)
				(pin no_connect line
					(at -33.02 -1.27 0)
					(length 5.08)
					(hide yes)
					(name "RSVD"
						(effects
							(font
								(size 1.27 1.27)
							)
						)
					)
					(number "D97"
						(effects
							(font
								(size 1.27 1.27)
							)
						)
					)
				)
				(pin no_connect line
					(at -33.02 -2.54 0)
					(length 5.08)
					(hide yes)
					(name "RSVD"
						(effects
							(font
								(size 1.27 1.27)
							)
						)
					)
					(number "C63"
						(effects
							(font
								(size 1.27 1.27)
							)
						)
					)
				)
				(pin no_connect line
					(at -33.02 -3.81 0)
					(length 5.08)
					(hide yes)
					(name "RSVD"
						(effects
							(font
								(size 1.27 1.27)
							)
						)
					)
					(number "C64"
						(effects
							(font
								(size 1.27 1.27)
							)
						)
					)
				)
				(pin no_connect line
					(at -33.02 -5.08 0)
					(length 5.08)
					(hide yes)
					(name "RSVD"
						(effects
							(font
								(size 1.27 1.27)
							)
						)
					)
					(number "C77"
						(effects
							(font
								(size 1.27 1.27)
							)
						)
					)
				)
				(pin no_connect line
					(at -33.02 -6.35 0)
					(length 5.08)
					(hide yes)
					(name "RSVD"
						(effects
							(font
								(size 1.27 1.27)
							)
						)
					)
					(number "C83"
						(effects
							(font
								(size 1.27 1.27)
							)
						)
					)
				)
				(pin no_connect line
					(at -33.02 -7.62 0)
					(length 5.08)
					(hide yes)
					(name "RSVD"
						(effects
							(font
								(size 1.27 1.27)
							)
						)
					)
					(number "C97"
						(effects
							(font
								(size 1.27 1.27)
							)
						)
					)
				)
				(pin no_connect line
					(at -33.02 -8.89 0)
					(length 5.08)
					(hide yes)
					(name "RSVD"
						(effects
							(font
								(size 1.27 1.27)
							)
						)
					)
					(number "D54"
						(effects
							(font
								(size 1.27 1.27)
							)
						)
					)
				)
				(pin no_connect line
					(at -33.02 -10.16 0)
					(length 5.08)
					(hide yes)
					(name "RSVD"
						(effects
							(font
								(size 1.27 1.27)
							)
						)
					)
					(number "D64"
						(effects
							(font
								(size 1.27 1.27)
							)
						)
					)
				)
				(pin no_connect line
					(at -33.02 -11.43 0)
					(length 5.08)
					(hide yes)
					(name "RSVD"
						(effects
							(font
								(size 1.27 1.27)
							)
						)
					)
					(number "D63"
						(effects
							(font
								(size 1.27 1.27)
							)
						)
					)
				)
				(pin no_connect line
					(at -33.02 -12.7 0)
					(length 5.08)
					(hide yes)
					(name "RSVD"
						(effects
							(font
								(size 1.27 1.27)
							)
						)
					)
					(number "D37"
						(effects
							(font
								(size 1.27 1.27)
							)
						)
					)
				)
				(pin no_connect line
					(at -33.02 -13.97 0)
					(length 5.08)
					(hide yes)
					(name "RSVD"
						(effects
							(font
								(size 1.27 1.27)
							)
						)
					)
					(number "D36"
						(effects
							(font
								(size 1.27 1.27)
							)
						)
					)
				)
				(pin no_connect line
					(at -33.02 -15.24 0)
					(length 5.08)
					(hide yes)
					(name "RSVD"
						(effects
							(font
								(size 1.27 1.27)
							)
						)
					)
					(number "D83"
						(effects
							(font
								(size 1.27 1.27)
							)
						)
					)
				)
				(pin power_in line
					(at 0 0 180)
					(length 5.08)
					(name "VCC_12V"
						(effects
							(font
								(size 1.27 1.27)
							)
						)
					)
					(number "C104"
						(effects
							(font
								(size 1.27 1.27)
							)
						)
					)
				)
				(pin passive line
					(at 0 0 180)
					(length 5.08)
					(hide yes)
					(name "VCC_12V"
						(effects
							(font
								(size 1.27 1.27)
							)
						)
					)
					(number "C105"
						(effects
							(font
								(size 1.27 1.27)
							)
						)
					)
				)
				(pin passive line
					(at 0 0 180)
					(length 5.08)
					(hide yes)
					(name "VCC_12V"
						(effects
							(font
								(size 1.27 1.27)
							)
						)
					)
					(number "C106"
						(effects
							(font
								(size 1.27 1.27)
							)
						)
					)
				)
				(pin passive line
					(at 0 0 180)
					(length 5.08)
					(hide yes)
					(name "VCC_12V"
						(effects
							(font
								(size 1.27 1.27)
							)
						)
					)
					(number "C107"
						(effects
							(font
								(size 1.27 1.27)
							)
						)
					)
				)
				(pin passive line
					(at 0 0 180)
					(length 5.08)
					(hide yes)
					(name "VCC_12V"
						(effects
							(font
								(size 1.27 1.27)
							)
						)
					)
					(number "C108"
						(effects
							(font
								(size 1.27 1.27)
							)
						)
					)
				)
				(pin passive line
					(at 0 0 180)
					(length 5.08)
					(hide yes)
					(name "VCC_12V"
						(effects
							(font
								(size 1.27 1.27)
							)
						)
					)
					(number "C109"
						(effects
							(font
								(size 1.27 1.27)
							)
						)
					)
				)
				(pin passive line
					(at 0 0 180)
					(length 5.08)
					(hide yes)
					(name "VCC_12V"
						(effects
							(font
								(size 1.27 1.27)
							)
						)
					)
					(number "D104"
						(effects
							(font
								(size 1.27 1.27)
							)
						)
					)
				)
				(pin passive line
					(at 0 0 180)
					(length 5.08)
					(hide yes)
					(name "VCC_12V"
						(effects
							(font
								(size 1.27 1.27)
							)
						)
					)
					(number "D105"
						(effects
							(font
								(size 1.27 1.27)
							)
						)
					)
				)
				(pin passive line
					(at 0 0 180)
					(length 5.08)
					(hide yes)
					(name "VCC_12V"
						(effects
							(font
								(size 1.27 1.27)
							)
						)
					)
					(number "D106"
						(effects
							(font
								(size 1.27 1.27)
							)
						)
					)
				)
				(pin passive line
					(at 0 0 180)
					(length 5.08)
					(hide yes)
					(name "VCC_12V"
						(effects
							(font
								(size 1.27 1.27)
							)
						)
					)
					(number "D107"
						(effects
							(font
								(size 1.27 1.27)
							)
						)
					)
				)
				(pin passive line
					(at 0 0 180)
					(length 5.08)
					(hide yes)
					(name "VCC_12V"
						(effects
							(font
								(size 1.27 1.27)
							)
						)
					)
					(number "D108"
						(effects
							(font
								(size 1.27 1.27)
							)
						)
					)
				)
				(pin passive line
					(at 0 0 180)
					(length 5.08)
					(hide yes)
					(name "VCC_12V"
						(effects
							(font
								(size 1.27 1.27)
							)
						)
					)
					(number "D109"
						(effects
							(font
								(size 1.27 1.27)
							)
						)
					)
				)
				(pin passive line
					(at 0 -10.16 180)
					(length 5.08)
					(name "MP"
						(effects
							(font
								(size 1.27 1.27)
							)
						)
					)
					(number "MP"
						(effects
							(font
								(size 1.27 1.27)
							)
						)
					)
				)
				(pin power_in line
					(at 0 -12.7 180)
					(length 5.08)
					(name "GND(FIXED)"
						(effects
							(font
								(size 1.27 1.27)
							)
						)
					)
					(number "C1"
						(effects
							(font
								(size 1.27 1.27)
							)
						)
					)
				)
				(pin passive line
					(at 0 -12.7 180)
					(length 5.08)
					(hide yes)
					(name "GND(FIXED)"
						(effects
							(font
								(size 1.27 1.27)
							)
						)
					)
					(number "C100"
						(effects
							(font
								(size 1.27 1.27)
							)
						)
					)
				)
				(pin passive line
					(at 0 -12.7 180)
					(length 5.08)
					(hide yes)
					(name "GND(FIXED)"
						(effects
							(font
								(size 1.27 1.27)
							)
						)
					)
					(number "C11"
						(effects
							(font
								(size 1.27 1.27)
							)
						)
					)
				)
				(pin passive line
					(at 0 -12.7 180)
					(length 5.08)
					(hide yes)
					(name "GND(FIXED)"
						(effects
							(font
								(size 1.27 1.27)
							)
						)
					)
					(number "C110"
						(effects
							(font
								(size 1.27 1.27)
							)
						)
					)
				)
				(pin passive line
					(at 0 -12.7 180)
					(length 5.08)
					(hide yes)
					(name "GND(FIXED)"
						(effects
							(font
								(size 1.27 1.27)
							)
						)
					)
					(number "C21"
						(effects
							(font
								(size 1.27 1.27)
							)
						)
					)
				)
				(pin passive line
					(at 0 -12.7 180)
					(length 5.08)
					(hide yes)
					(name "GND(FIXED)"
						(effects
							(font
								(size 1.27 1.27)
							)
						)
					)
					(number "C31"
						(effects
							(font
								(size 1.27 1.27)
							)
						)
					)
				)
				(pin passive line
					(at 0 -12.7 180)
					(length 5.08)
					(hide yes)
					(name "GND(FIXED)"
						(effects
							(font
								(size 1.27 1.27)
							)
						)
					)
					(number "C41"
						(effects
							(font
								(size 1.27 1.27)
							)
						)
					)
				)
				(pin passive line
					(at 0 -12.7 180)
					(length 5.08)
					(hide yes)
					(name "GND(FIXED)"
						(effects
							(font
								(size 1.27 1.27)
							)
						)
					)
					(number "C51"
						(effects
							(font
								(size 1.27 1.27)
							)
						)
					)
				)
				(pin passive line
					(at 0 -12.7 180)
					(length 5.08)
					(hide yes)
					(name "GND(FIXED)"
						(effects
							(font
								(size 1.27 1.27)
							)
						)
					)
					(number "C60"
						(effects
							(font
								(size 1.27 1.27)
							)
						)
					)
				)
				(pin passive line
					(at 0 -12.7 180)
					(length 5.08)
					(hide yes)
					(name "GND(FIXED)"
						(effects
							(font
								(size 1.27 1.27)
							)
						)
					)
					(number "C70"
						(effects
							(font
								(size 1.27 1.27)
							)
						)
					)
				)
				(pin passive line
					(at 0 -12.7 180)
					(length 5.08)
					(hide yes)
					(name "GND(FIXED)"
						(effects
							(font
								(size 1.27 1.27)
							)
						)
					)
					(number "C80"
						(effects
							(font
								(size 1.27 1.27)
							)
						)
					)
				)
				(pin passive line
					(at 0 -12.7 180)
					(length 5.08)
					(hide yes)
					(name "GND(FIXED)"
						(effects
							(font
								(size 1.27 1.27)
							)
						)
					)
					(number "C90"
						(effects
							(font
								(size 1.27 1.27)
							)
						)
					)
				)
				(pin passive line
					(at 0 -12.7 180)
					(length 5.08)
					(hide yes)
					(name "GND(FIXED)"
						(effects
							(font
								(size 1.27 1.27)
							)
						)
					)
					(number "D1"
						(effects
							(font
								(size 1.27 1.27)
							)
						)
					)
				)
				(pin passive line
					(at 0 -12.7 180)
					(length 5.08)
					(hide yes)
					(name "GND(FIXED)"
						(effects
							(font
								(size 1.27 1.27)
							)
						)
					)
					(number "D100"
						(effects
							(font
								(size 1.27 1.27)
							)
						)
					)
				)
				(pin passive line
					(at 0 -12.7 180)
					(length 5.08)
					(hide yes)
					(name "GND(FIXED)"
						(effects
							(font
								(size 1.27 1.27)
							)
						)
					)
					(number "D11"
						(effects
							(font
								(size 1.27 1.27)
							)
						)
					)
				)
				(pin passive line
					(at 0 -12.7 180)
					(length 5.08)
					(hide yes)
					(name "GND(FIXED)"
						(effects
							(font
								(size 1.27 1.27)
							)
						)
					)
					(number "D110"
						(effects
							(font
								(size 1.27 1.27)
							)
						)
					)
				)
				(pin passive line
					(at 0 -12.7 180)
					(length 5.08)
					(hide yes)
					(name "GND(FIXED)"
						(effects
							(font
								(size 1.27 1.27)
							)
						)
					)
					(number "D21"
						(effects
							(font
								(size 1.27 1.27)
							)
						)
					)
				)
				(pin passive line
					(at 0 -12.7 180)
					(length 5.08)
					(hide yes)
					(name "GND(FIXED)"
						(effects
							(font
								(size 1.27 1.27)
							)
						)
					)
					(number "D31"
						(effects
							(font
								(size 1.27 1.27)
							)
						)
					)
				)
				(pin passive line
					(at 0 -12.7 180)
					(length 5.08)
					(hide yes)
					(name "GND(FIXED)"
						(effects
							(font
								(size 1.27 1.27)
							)
						)
					)
					(number "D41"
						(effects
							(font
								(size 1.27 1.27)
							)
						)
					)
				)
				(pin passive line
					(at 0 -12.7 180)
					(length 5.08)
					(hide yes)
					(name "GND(FIXED)"
						(effects
							(font
								(size 1.27 1.27)
							)
						)
					)
					(number "D51"
						(effects
							(font
								(size 1.27 1.27)
							)
						)
					)
				)
				(pin passive line
					(at 0 -12.7 180)
					(length 5.08)
					(hide yes)
					(name "GND(FIXED)"
						(effects
							(font
								(size 1.27 1.27)
							)
						)
					)
					(number "D60"
						(effects
							(font
								(size 1.27 1.27)
							)
						)
					)
				)
				(pin passive line
					(at 0 -12.7 180)
					(length 5.08)
					(hide yes)
					(name "GND(FIXED)"
						(effects
							(font
								(size 1.27 1.27)
							)
						)
					)
					(number "D70"
						(effects
							(font
								(size 1.27 1.27)
							)
						)
					)
				)
				(pin passive line
					(at 0 -12.7 180)
					(length 5.08)
					(hide yes)
					(name "GND(FIXED)"
						(effects
							(font
								(size 1.27 1.27)
							)
						)
					)
					(number "D80"
						(effects
							(font
								(size 1.27 1.27)
							)
						)
					)
				)
				(pin passive line
					(at 0 -12.7 180)
					(length 5.08)
					(hide yes)
					(name "GND(FIXED)"
						(effects
							(font
								(size 1.27 1.27)
							)
						)
					)
					(number "D90"
						(effects
							(font
								(size 1.27 1.27)
							)
						)
					)
				)
				(pin power_in line
					(at 0 -15.24 180)
					(length 5.08)
					(name "GND"
						(effects
							(font
								(size 1.27 1.27)
							)
						)
					)
					(number "C103"
						(effects
							(font
								(size 1.27 1.27)
							)
						)
					)
				)
				(pin passive line
					(at 0 -15.24 180)
					(length 5.08)
					(hide yes)
					(name "GND"
						(effects
							(font
								(size 1.27 1.27)
							)
						)
					)
					(number "C14"
						(effects
							(font
								(size 1.27 1.27)
							)
						)
					)
				)
				(pin passive line
					(at 0 -15.24 180)
					(length 5.08)
					(hide yes)
					(name "GND"
						(effects
							(font
								(size 1.27 1.27)
							)
						)
					)
					(number "C18"
						(effects
							(font
								(size 1.27 1.27)
							)
						)
					)
				)
				(pin passive line
					(at 0 -15.24 180)
					(length 5.08)
					(hide yes)
					(name "GND"
						(effects
							(font
								(size 1.27 1.27)
							)
						)
					)
					(number "C2"
						(effects
							(font
								(size 1.27 1.27)
							)
						)
					)
				)
				(pin passive line
					(at 0 -15.24 180)
					(length 5.08)
					(hide yes)
					(name "GND"
						(effects
							(font
								(size 1.27 1.27)
							)
						)
					)
					(number "C25"
						(effects
							(font
								(size 1.27 1.27)
							)
						)
					)
				)
				(pin passive line
					(at 0 -15.24 180)
					(length 5.08)
					(hide yes)
					(name "GND"
						(effects
							(font
								(size 1.27 1.27)
							)
						)
					)
					(number "C28"
						(effects
							(font
								(size 1.27 1.27)
							)
						)
					)
				)
				(pin passive line
					(at 0 -15.24 180)
					(length 5.08)
					(hide yes)
					(name "GND"
						(effects
							(font
								(size 1.27 1.27)
							)
						)
					)
					(number "C44"
						(effects
							(font
								(size 1.27 1.27)
							)
						)
					)
				)
				(pin passive line
					(at 0 -15.24 180)
					(length 5.08)
					(hide yes)
					(name "GND"
						(effects
							(font
								(size 1.27 1.27)
							)
						)
					)
					(number "C48"
						(effects
							(font
								(size 1.27 1.27)
							)
						)
					)
				)
				(pin passive line
					(at 0 -15.24 180)
					(length 5.08)
					(hide yes)
					(name "GND"
						(effects
							(font
								(size 1.27 1.27)
							)
						)
					)
					(number "C5"
						(effects
							(font
								(size 1.27 1.27)
							)
						)
					)
				)
				(pin passive line
					(at 0 -15.24 180)
					(length 5.08)
					(hide yes)
					(name "GND"
						(effects
							(font
								(size 1.27 1.27)
							)
						)
					)
					(number "C73"
						(effects
							(font
								(size 1.27 1.27)
							)
						)
					)
				)
				(pin passive line
					(at 0 -15.24 180)
					(length 5.08)
					(hide yes)
					(name "GND"
						(effects
							(font
								(size 1.27 1.27)
							)
						)
					)
					(number "C76"
						(effects
							(font
								(size 1.27 1.27)
							)
						)
					)
				)
				(pin passive line
					(at 0 -15.24 180)
					(length 5.08)
					(hide yes)
					(name "GND"
						(effects
							(font
								(size 1.27 1.27)
							)
						)
					)
					(number "C8"
						(effects
							(font
								(size 1.27 1.27)
							)
						)
					)
				)
				(pin passive line
					(at 0 -15.24 180)
					(length 5.08)
					(hide yes)
					(name "GND"
						(effects
							(font
								(size 1.27 1.27)
							)
						)
					)
					(number "C84"
						(effects
							(font
								(size 1.27 1.27)
							)
						)
					)
				)
				(pin passive line
					(at 0 -15.24 180)
					(length 5.08)
					(hide yes)
					(name "GND"
						(effects
							(font
								(size 1.27 1.27)
							)
						)
					)
					(number "C87"
						(effects
							(font
								(size 1.27 1.27)
							)
						)
					)
				)
				(pin passive line
					(at 0 -15.24 180)
					(length 5.08)
					(hide yes)
					(name "GND"
						(effects
							(font
								(size 1.27 1.27)
							)
						)
					)
					(number "C93"
						(effects
							(font
								(size 1.27 1.27)
							)
						)
					)
				)
				(pin passive line
					(at 0 -15.24 180)
					(length 5.08)
					(hide yes)
					(name "GND"
						(effects
							(font
								(size 1.27 1.27)
							)
						)
					)
					(number "C96"
						(effects
							(font
								(size 1.27 1.27)
							)
						)
					)
				)
				(pin passive line
					(at 0 -15.24 180)
					(length 5.08)
					(hide yes)
					(name "GND"
						(effects
							(font
								(size 1.27 1.27)
							)
						)
					)
					(number "D103"
						(effects
							(font
								(size 1.27 1.27)
							)
						)
					)
				)
				(pin passive line
					(at 0 -15.24 180)
					(length 5.08)
					(hide yes)
					(name "GND"
						(effects
							(font
								(size 1.27 1.27)
							)
						)
					)
					(number "D14"
						(effects
							(font
								(size 1.27 1.27)
							)
						)
					)
				)
				(pin passive line
					(at 0 -15.24 180)
					(length 5.08)
					(hide yes)
					(name "GND"
						(effects
							(font
								(size 1.27 1.27)
							)
						)
					)
					(number "D18"
						(effects
							(font
								(size 1.27 1.27)
							)
						)
					)
				)
				(pin passive line
					(at 0 -15.24 180)
					(length 5.08)
					(hide yes)
					(name "GND"
						(effects
							(font
								(size 1.27 1.27)
							)
						)
					)
					(number "D2"
						(effects
							(font
								(size 1.27 1.27)
							)
						)
					)
				)
				(pin passive line
					(at 0 -15.24 180)
					(length 5.08)
					(hide yes)
					(name "GND"
						(effects
							(font
								(size 1.27 1.27)
							)
						)
					)
					(number "D25"
						(effects
							(font
								(size 1.27 1.27)
							)
						)
					)
				)
				(pin passive line
					(at 0 -15.24 180)
					(length 5.08)
					(hide yes)
					(name "GND"
						(effects
							(font
								(size 1.27 1.27)
							)
						)
					)
					(number "D28"
						(effects
							(font
								(size 1.27 1.27)
							)
						)
					)
				)
				(pin passive line
					(at 0 -15.24 180)
					(length 5.08)
					(hide yes)
					(name "GND"
						(effects
							(font
								(size 1.27 1.27)
							)
						)
					)
					(number "D44"
						(effects
							(font
								(size 1.27 1.27)
							)
						)
					)
				)
				(pin passive line
					(at 0 -15.24 180)
					(length 5.08)
					(hide yes)
					(name "GND"
						(effects
							(font
								(size 1.27 1.27)
							)
						)
					)
					(number "D48"
						(effects
							(font
								(size 1.27 1.27)
							)
						)
					)
				)
				(pin passive line
					(at 0 -15.24 180)
					(length 5.08)
					(hide yes)
					(name "GND"
						(effects
							(font
								(size 1.27 1.27)
							)
						)
					)
					(number "D5"
						(effects
							(font
								(size 1.27 1.27)
							)
						)
					)
				)
				(pin passive line
					(at 0 -15.24 180)
					(length 5.08)
					(hide yes)
					(name "GND"
						(effects
							(font
								(size 1.27 1.27)
							)
						)
					)
					(number "D67"
						(effects
							(font
								(size 1.27 1.27)
							)
						)
					)
				)
				(pin passive line
					(at 0 -15.24 180)
					(length 5.08)
					(hide yes)
					(name "GND"
						(effects
							(font
								(size 1.27 1.27)
							)
						)
					)
					(number "D73"
						(effects
							(font
								(size 1.27 1.27)
							)
						)
					)
				)
				(pin passive line
					(at 0 -15.24 180)
					(length 5.08)
					(hide yes)
					(name "GND"
						(effects
							(font
								(size 1.27 1.27)
							)
						)
					)
					(number "D76"
						(effects
							(font
								(size 1.27 1.27)
							)
						)
					)
				)
				(pin passive line
					(at 0 -15.24 180)
					(length 5.08)
					(hide yes)
					(name "GND"
						(effects
							(font
								(size 1.27 1.27)
							)
						)
					)
					(number "D8"
						(effects
							(font
								(size 1.27 1.27)
							)
						)
					)
				)
				(pin passive line
					(at 0 -15.24 180)
					(length 5.08)
					(hide yes)
					(name "GND"
						(effects
							(font
								(size 1.27 1.27)
							)
						)
					)
					(number "D84"
						(effects
							(font
								(size 1.27 1.27)
							)
						)
					)
				)
				(pin passive line
					(at 0 -15.24 180)
					(length 5.08)
					(hide yes)
					(name "GND"
						(effects
							(font
								(size 1.27 1.27)
							)
						)
					)
					(number "D87"
						(effects
							(font
								(size 1.27 1.27)
							)
						)
					)
				)
				(pin passive line
					(at 0 -15.24 180)
					(length 5.08)
					(hide yes)
					(name "GND"
						(effects
							(font
								(size 1.27 1.27)
							)
						)
					)
					(number "D93"
						(effects
							(font
								(size 1.27 1.27)
							)
						)
					)
				)
				(pin passive line
					(at 0 -15.24 180)
					(length 5.08)
					(hide yes)
					(name "GND"
						(effects
							(font
								(size 1.27 1.27)
							)
						)
					)
					(number "D96"
						(effects
							(font
								(size 1.27 1.27)
							)
						)
					)
				)
			)
			(symbol "Plug_Bus_CE7_EPT_401-51501-51_14_1"
				(rectangle
					(start -33.02 2.54)
					(end -5.08 -241.3)
					(stroke
						(width 0.254)
						(type default)
					)
					(fill
						(type background)
					)
				)
				(text "C/D"
					(at -31.75 0 0)
					(effects
						(font
							(size 1.27 1.27)
							(thickness 0.15)
						)
						(justify left bottom)
					)
				)
				(text "PCIe"
					(at -31.75 -240.03 0)
					(effects
						(font
							(size 1.27 1.27)
							(thickness 0.15)
						)
						(justify left bottom)
					)
				)
				(pin output line
					(at 0 0 180)
					(length 5.08)
					(name "PCIE_TX31+"
						(effects
							(font
								(size 1.27 1.27)
							)
						)
					)
					(number "D101"
						(effects
							(font
								(size 1.27 1.27)
							)
						)
					)
				)
				(pin output line
					(at 0 -2.54 180)
					(length 5.08)
					(name "PCIE_TX31-"
						(effects
							(font
								(size 1.27 1.27)
							)
						)
					)
					(number "D102"
						(effects
							(font
								(size 1.27 1.27)
							)
						)
					)
				)
				(pin input line
					(at 0 -7.62 180)
					(length 5.08)
					(name "PCIE_RX31+"
						(effects
							(font
								(size 1.27 1.27)
							)
						)
					)
					(number "C101"
						(effects
							(font
								(size 1.27 1.27)
							)
						)
					)
				)
				(pin input line
					(at 0 -10.16 180)
					(length 5.08)
					(name "PCIE_RX31-"
						(effects
							(font
								(size 1.27 1.27)
							)
						)
					)
					(number "C102"
						(effects
							(font
								(size 1.27 1.27)
							)
						)
					)
				)
				(pin output line
					(at 0 -15.24 180)
					(length 5.08)
					(name "PCIE_TX30+"
						(effects
							(font
								(size 1.27 1.27)
							)
						)
					)
					(number "D98"
						(effects
							(font
								(size 1.27 1.27)
							)
						)
					)
				)
				(pin output line
					(at 0 -17.78 180)
					(length 5.08)
					(name "PCIE_TX30-"
						(effects
							(font
								(size 1.27 1.27)
							)
						)
					)
					(number "D99"
						(effects
							(font
								(size 1.27 1.27)
							)
						)
					)
				)
				(pin input line
					(at 0 -22.86 180)
					(length 5.08)
					(name "PCIE_RX30+"
						(effects
							(font
								(size 1.27 1.27)
							)
						)
					)
					(number "C98"
						(effects
							(font
								(size 1.27 1.27)
							)
						)
					)
				)
				(pin input line
					(at 0 -25.4 180)
					(length 5.08)
					(name "PCIE_RX30-"
						(effects
							(font
								(size 1.27 1.27)
							)
						)
					)
					(number "C99"
						(effects
							(font
								(size 1.27 1.27)
							)
						)
					)
				)
				(pin output line
					(at 0 -30.48 180)
					(length 5.08)
					(name "PCIE_TX29+"
						(effects
							(font
								(size 1.27 1.27)
							)
						)
					)
					(number "D94"
						(effects
							(font
								(size 1.27 1.27)
							)
						)
					)
				)
				(pin output line
					(at 0 -33.02 180)
					(length 5.08)
					(name "PCIE_TX29-"
						(effects
							(font
								(size 1.27 1.27)
							)
						)
					)
					(number "D95"
						(effects
							(font
								(size 1.27 1.27)
							)
						)
					)
				)
				(pin input line
					(at 0 -38.1 180)
					(length 5.08)
					(name "PCIE_RX29+"
						(effects
							(font
								(size 1.27 1.27)
							)
						)
					)
					(number "C94"
						(effects
							(font
								(size 1.27 1.27)
							)
						)
					)
				)
				(pin input line
					(at 0 -40.64 180)
					(length 5.08)
					(name "PCIE_RX29-"
						(effects
							(font
								(size 1.27 1.27)
							)
						)
					)
					(number "C95"
						(effects
							(font
								(size 1.27 1.27)
							)
						)
					)
				)
				(pin output line
					(at 0 -45.72 180)
					(length 5.08)
					(name "PCIE_TX28+"
						(effects
							(font
								(size 1.27 1.27)
							)
						)
					)
					(number "D91"
						(effects
							(font
								(size 1.27 1.27)
							)
						)
					)
				)
				(pin output line
					(at 0 -48.26 180)
					(length 5.08)
					(name "PCIE_TX28-"
						(effects
							(font
								(size 1.27 1.27)
							)
						)
					)
					(number "D92"
						(effects
							(font
								(size 1.27 1.27)
							)
						)
					)
				)
				(pin input line
					(at 0 -53.34 180)
					(length 5.08)
					(name "PCIE_RX28+"
						(effects
							(font
								(size 1.27 1.27)
							)
						)
					)
					(number "C91"
						(effects
							(font
								(size 1.27 1.27)
							)
						)
					)
				)
				(pin input line
					(at 0 -55.88 180)
					(length 5.08)
					(name "PCIE_RX28-"
						(effects
							(font
								(size 1.27 1.27)
							)
						)
					)
					(number "C92"
						(effects
							(font
								(size 1.27 1.27)
							)
						)
					)
				)
				(pin output line
					(at 0 -60.96 180)
					(length 5.08)
					(name "PCIE_TX27+"
						(effects
							(font
								(size 1.27 1.27)
							)
						)
					)
					(number "D88"
						(effects
							(font
								(size 1.27 1.27)
							)
						)
					)
				)
				(pin output line
					(at 0 -63.5 180)
					(length 5.08)
					(name "PCIE_TX27-"
						(effects
							(font
								(size 1.27 1.27)
							)
						)
					)
					(number "D89"
						(effects
							(font
								(size 1.27 1.27)
							)
						)
					)
				)
				(pin input line
					(at 0 -68.58 180)
					(length 5.08)
					(name "PCIE_RX27+"
						(effects
							(font
								(size 1.27 1.27)
							)
						)
					)
					(number "C88"
						(effects
							(font
								(size 1.27 1.27)
							)
						)
					)
				)
				(pin input line
					(at 0 -71.12 180)
					(length 5.08)
					(name "PCIE_RX27-"
						(effects
							(font
								(size 1.27 1.27)
							)
						)
					)
					(number "C89"
						(effects
							(font
								(size 1.27 1.27)
							)
						)
					)
				)
				(pin output line
					(at 0 -76.2 180)
					(length 5.08)
					(name "PCIE_TX26+"
						(effects
							(font
								(size 1.27 1.27)
							)
						)
					)
					(number "D85"
						(effects
							(font
								(size 1.27 1.27)
							)
						)
					)
				)
				(pin output line
					(at 0 -78.74 180)
					(length 5.08)
					(name "PCIE_TX26-"
						(effects
							(font
								(size 1.27 1.27)
							)
						)
					)
					(number "D86"
						(effects
							(font
								(size 1.27 1.27)
							)
						)
					)
				)
				(pin input line
					(at 0 -83.82 180)
					(length 5.08)
					(name "PCIE_RX26+"
						(effects
							(font
								(size 1.27 1.27)
							)
						)
					)
					(number "C85"
						(effects
							(font
								(size 1.27 1.27)
							)
						)
					)
				)
				(pin input line
					(at 0 -86.36 180)
					(length 5.08)
					(name "PCIE_RX26-"
						(effects
							(font
								(size 1.27 1.27)
							)
						)
					)
					(number "C86"
						(effects
							(font
								(size 1.27 1.27)
							)
						)
					)
				)
				(pin output line
					(at 0 -91.44 180)
					(length 5.08)
					(name "PCIE_TX25+"
						(effects
							(font
								(size 1.27 1.27)
							)
						)
					)
					(number "D81"
						(effects
							(font
								(size 1.27 1.27)
							)
						)
					)
				)
				(pin output line
					(at 0 -93.98 180)
					(length 5.08)
					(name "PCIE_TX25-"
						(effects
							(font
								(size 1.27 1.27)
							)
						)
					)
					(number "D82"
						(effects
							(font
								(size 1.27 1.27)
							)
						)
					)
				)
				(pin input line
					(at 0 -99.06 180)
					(length 5.08)
					(name "PCIE_RX25+"
						(effects
							(font
								(size 1.27 1.27)
							)
						)
					)
					(number "C81"
						(effects
							(font
								(size 1.27 1.27)
							)
						)
					)
				)
				(pin input line
					(at 0 -101.6 180)
					(length 5.08)
					(name "PCIE_RX25-"
						(effects
							(font
								(size 1.27 1.27)
							)
						)
					)
					(number "C82"
						(effects
							(font
								(size 1.27 1.27)
							)
						)
					)
				)
				(pin output line
					(at 0 -106.68 180)
					(length 5.08)
					(name "PCIE_TX24+"
						(effects
							(font
								(size 1.27 1.27)
							)
						)
					)
					(number "D78"
						(effects
							(font
								(size 1.27 1.27)
							)
						)
					)
				)
				(pin output line
					(at 0 -109.22 180)
					(length 5.08)
					(name "PCIE_TX24-"
						(effects
							(font
								(size 1.27 1.27)
							)
						)
					)
					(number "D79"
						(effects
							(font
								(size 1.27 1.27)
							)
						)
					)
				)
				(pin input line
					(at 0 -114.3 180)
					(length 5.08)
					(name "PCIE_RX24+"
						(effects
							(font
								(size 1.27 1.27)
							)
						)
					)
					(number "C78"
						(effects
							(font
								(size 1.27 1.27)
							)
						)
					)
				)
				(pin input line
					(at 0 -116.84 180)
					(length 5.08)
					(name "PCIE_RX24-"
						(effects
							(font
								(size 1.27 1.27)
							)
						)
					)
					(number "C79"
						(effects
							(font
								(size 1.27 1.27)
							)
						)
					)
				)
				(pin output line
					(at 0 -121.92 180)
					(length 5.08)
					(name "PCIE_TX23+"
						(effects
							(font
								(size 1.27 1.27)
							)
						)
					)
					(number "D74"
						(effects
							(font
								(size 1.27 1.27)
							)
						)
					)
				)
				(pin output line
					(at 0 -124.46 180)
					(length 5.08)
					(name "PCIE_TX23-"
						(effects
							(font
								(size 1.27 1.27)
							)
						)
					)
					(number "D75"
						(effects
							(font
								(size 1.27 1.27)
							)
						)
					)
				)
				(pin input line
					(at 0 -129.54 180)
					(length 5.08)
					(name "PCIE_RX23+"
						(effects
							(font
								(size 1.27 1.27)
							)
						)
					)
					(number "C74"
						(effects
							(font
								(size 1.27 1.27)
							)
						)
					)
				)
				(pin input line
					(at 0 -132.08 180)
					(length 5.08)
					(name "PCIE_RX23-"
						(effects
							(font
								(size 1.27 1.27)
							)
						)
					)
					(number "C75"
						(effects
							(font
								(size 1.27 1.27)
							)
						)
					)
				)
				(pin output line
					(at 0 -137.16 180)
					(length 5.08)
					(name "PCIE_TX22+"
						(effects
							(font
								(size 1.27 1.27)
							)
						)
					)
					(number "D71"
						(effects
							(font
								(size 1.27 1.27)
							)
						)
					)
				)
				(pin output line
					(at 0 -139.7 180)
					(length 5.08)
					(name "PCIE_TX22-"
						(effects
							(font
								(size 1.27 1.27)
							)
						)
					)
					(number "D72"
						(effects
							(font
								(size 1.27 1.27)
							)
						)
					)
				)
				(pin input line
					(at 0 -144.78 180)
					(length 5.08)
					(name "PCIE_RX22+"
						(effects
							(font
								(size 1.27 1.27)
							)
						)
					)
					(number "C71"
						(effects
							(font
								(size 1.27 1.27)
							)
						)
					)
				)
				(pin input line
					(at 0 -147.32 180)
					(length 5.08)
					(name "PCIE_RX22-"
						(effects
							(font
								(size 1.27 1.27)
							)
						)
					)
					(number "C72"
						(effects
							(font
								(size 1.27 1.27)
							)
						)
					)
				)
				(pin output line
					(at 0 -152.4 180)
					(length 5.08)
					(name "PCIE_TX21+"
						(effects
							(font
								(size 1.27 1.27)
							)
						)
					)
					(number "D68"
						(effects
							(font
								(size 1.27 1.27)
							)
						)
					)
				)
				(pin output line
					(at 0 -154.94 180)
					(length 5.08)
					(name "PCIE_TX21-"
						(effects
							(font
								(size 1.27 1.27)
							)
						)
					)
					(number "D69"
						(effects
							(font
								(size 1.27 1.27)
							)
						)
					)
				)
				(pin input line
					(at 0 -160.02 180)
					(length 5.08)
					(name "PCIE_RX21+"
						(effects
							(font
								(size 1.27 1.27)
							)
						)
					)
					(number "C68"
						(effects
							(font
								(size 1.27 1.27)
							)
						)
					)
				)
				(pin input line
					(at 0 -162.56 180)
					(length 5.08)
					(name "PCIE_RX21-"
						(effects
							(font
								(size 1.27 1.27)
							)
						)
					)
					(number "C69"
						(effects
							(font
								(size 1.27 1.27)
							)
						)
					)
				)
				(pin output line
					(at 0 -167.64 180)
					(length 5.08)
					(name "PCIE_TX20+"
						(effects
							(font
								(size 1.27 1.27)
							)
						)
					)
					(number "D65"
						(effects
							(font
								(size 1.27 1.27)
							)
						)
					)
				)
				(pin output line
					(at 0 -170.18 180)
					(length 5.08)
					(name "PCIE_TX20-"
						(effects
							(font
								(size 1.27 1.27)
							)
						)
					)
					(number "D66"
						(effects
							(font
								(size 1.27 1.27)
							)
						)
					)
				)
				(pin input line
					(at 0 -175.26 180)
					(length 5.08)
					(name "PCIE_RX20+"
						(effects
							(font
								(size 1.27 1.27)
							)
						)
					)
					(number "C65"
						(effects
							(font
								(size 1.27 1.27)
							)
						)
					)
				)
				(pin input line
					(at 0 -177.8 180)
					(length 5.08)
					(name "PCIE_RX20-"
						(effects
							(font
								(size 1.27 1.27)
							)
						)
					)
					(number "C66"
						(effects
							(font
								(size 1.27 1.27)
							)
						)
					)
				)
				(pin output line
					(at 0 -182.88 180)
					(length 5.08)
					(name "PCIE_TX19+"
						(effects
							(font
								(size 1.27 1.27)
							)
						)
					)
					(number "D61"
						(effects
							(font
								(size 1.27 1.27)
							)
						)
					)
				)
				(pin output line
					(at 0 -185.42 180)
					(length 5.08)
					(name "PCIE_TX19-"
						(effects
							(font
								(size 1.27 1.27)
							)
						)
					)
					(number "D62"
						(effects
							(font
								(size 1.27 1.27)
							)
						)
					)
				)
				(pin input line
					(at 0 -190.5 180)
					(length 5.08)
					(name "PCIE_RX19+"
						(effects
							(font
								(size 1.27 1.27)
							)
						)
					)
					(number "C61"
						(effects
							(font
								(size 1.27 1.27)
							)
						)
					)
				)
				(pin input line
					(at 0 -193.04 180)
					(length 5.08)
					(name "PCIE_RX19-"
						(effects
							(font
								(size 1.27 1.27)
							)
						)
					)
					(number "C62"
						(effects
							(font
								(size 1.27 1.27)
							)
						)
					)
				)
				(pin output line
					(at 0 -198.12 180)
					(length 5.08)
					(name "PCIE_TX18+"
						(effects
							(font
								(size 1.27 1.27)
							)
						)
					)
					(number "D58"
						(effects
							(font
								(size 1.27 1.27)
							)
						)
					)
				)
				(pin output line
					(at 0 -200.66 180)
					(length 5.08)
					(name "PCIE_TX18-"
						(effects
							(font
								(size 1.27 1.27)
							)
						)
					)
					(number "D59"
						(effects
							(font
								(size 1.27 1.27)
							)
						)
					)
				)
				(pin input line
					(at 0 -205.74 180)
					(length 5.08)
					(name "PCIE_RX18+"
						(effects
							(font
								(size 1.27 1.27)
							)
						)
					)
					(number "C58"
						(effects
							(font
								(size 1.27 1.27)
							)
						)
					)
				)
				(pin input line
					(at 0 -208.28 180)
					(length 5.08)
					(name "PCIE_RX18-"
						(effects
							(font
								(size 1.27 1.27)
							)
						)
					)
					(number "C59"
						(effects
							(font
								(size 1.27 1.27)
							)
						)
					)
				)
				(pin output line
					(at 0 -213.36 180)
					(length 5.08)
					(name "PCIE_TX17+"
						(effects
							(font
								(size 1.27 1.27)
							)
						)
					)
					(number "D55"
						(effects
							(font
								(size 1.27 1.27)
							)
						)
					)
				)
				(pin output line
					(at 0 -215.9 180)
					(length 5.08)
					(name "PCIE_TX17-"
						(effects
							(font
								(size 1.27 1.27)
							)
						)
					)
					(number "D56"
						(effects
							(font
								(size 1.27 1.27)
							)
						)
					)
				)
				(pin input line
					(at 0 -220.98 180)
					(length 5.08)
					(name "PCIE_RX17+"
						(effects
							(font
								(size 1.27 1.27)
							)
						)
					)
					(number "C55"
						(effects
							(font
								(size 1.27 1.27)
							)
						)
					)
				)
				(pin input line
					(at 0 -223.52 180)
					(length 5.08)
					(name "PCIE_RX17-"
						(effects
							(font
								(size 1.27 1.27)
							)
						)
					)
					(number "C56"
						(effects
							(font
								(size 1.27 1.27)
							)
						)
					)
				)
				(pin output line
					(at 0 -228.6 180)
					(length 5.08)
					(name "PCIE_TX16+"
						(effects
							(font
								(size 1.27 1.27)
							)
						)
					)
					(number "D52"
						(effects
							(font
								(size 1.27 1.27)
							)
						)
					)
				)
				(pin output line
					(at 0 -231.14 180)
					(length 5.08)
					(name "PCIE_TX16-"
						(effects
							(font
								(size 1.27 1.27)
							)
						)
					)
					(number "D53"
						(effects
							(font
								(size 1.27 1.27)
							)
						)
					)
				)
				(pin input line
					(at 0 -236.22 180)
					(length 5.08)
					(name "PCIE_RX16+"
						(effects
							(font
								(size 1.27 1.27)
							)
						)
					)
					(number "C52"
						(effects
							(font
								(size 1.27 1.27)
							)
						)
					)
				)
				(pin input line
					(at 0 -238.76 180)
					(length 5.08)
					(name "PCIE_RX16-"
						(effects
							(font
								(size 1.27 1.27)
							)
						)
					)
					(number "C53"
						(effects
							(font
								(size 1.27 1.27)
							)
						)
					)
				)
			)
			(symbol "Plug_Bus_CE7_EPT_401-51501-51_15_1"
				(rectangle
					(start -33.02 2.54)
					(end -5.08 -27.94)
					(stroke
						(width 0.254)
						(type default)
					)
					(fill
						(type background)
					)
				)
				(text "C/D"
					(at -31.75 0 0)
					(effects
						(font
							(size 1.27 1.27)
							(thickness 0.15)
						)
						(justify left bottom)
					)
				)
				(text "PCIe"
					(at -31.75 -26.67 0)
					(effects
						(font
							(size 1.27 1.27)
							(thickness 0.15)
						)
						(justify left bottom)
					)
				)
				(pin output line
					(at 0 0 180)
					(length 5.08)
					(name "PCIE_TX7+"
						(effects
							(font
								(size 1.27 1.27)
							)
						)
					)
					(number "D22"
						(effects
							(font
								(size 1.27 1.27)
							)
						)
					)
				)
				(pin output line
					(at 0 -2.54 180)
					(length 5.08)
					(name "PCIE_TX7-"
						(effects
							(font
								(size 1.27 1.27)
							)
						)
					)
					(number "D23"
						(effects
							(font
								(size 1.27 1.27)
							)
						)
					)
				)
				(pin input line
					(at 0 -7.62 180)
					(length 5.08)
					(name "PCIE_RX7+"
						(effects
							(font
								(size 1.27 1.27)
							)
						)
					)
					(number "C22"
						(effects
							(font
								(size 1.27 1.27)
							)
						)
					)
				)
				(pin input line
					(at 0 -10.16 180)
					(length 5.08)
					(name "PCIE_RX7-"
						(effects
							(font
								(size 1.27 1.27)
							)
						)
					)
					(number "C23"
						(effects
							(font
								(size 1.27 1.27)
							)
						)
					)
				)
				(pin output line
					(at 0 -15.24 180)
					(length 5.08)
					(name "PCIE_TX6+"
						(effects
							(font
								(size 1.27 1.27)
							)
						)
					)
					(number "D19"
						(effects
							(font
								(size 1.27 1.27)
							)
						)
					)
				)
				(pin output line
					(at 0 -17.78 180)
					(length 5.08)
					(name "PCIE_TX6-"
						(effects
							(font
								(size 1.27 1.27)
							)
						)
					)
					(number "D20"
						(effects
							(font
								(size 1.27 1.27)
							)
						)
					)
				)
				(pin input line
					(at 0 -22.86 180)
					(length 5.08)
					(name "PCIE_RX6+"
						(effects
							(font
								(size 1.27 1.27)
							)
						)
					)
					(number "C19"
						(effects
							(font
								(size 1.27 1.27)
							)
						)
					)
				)
				(pin input line
					(at 0 -25.4 180)
					(length 5.08)
					(name "PCIE_RX6-"
						(effects
							(font
								(size 1.27 1.27)
							)
						)
					)
					(number "C20"
						(effects
							(font
								(size 1.27 1.27)
							)
						)
					)
				)
			)
			(symbol "Plug_Bus_CE7_EPT_401-51501-51_16_1"
				(rectangle
					(start -33.02 2.54)
					(end -5.08 -96.52)
					(stroke
						(width 0.254)
						(type default)
					)
					(fill
						(type background)
					)
				)
				(text "A/B"
					(at -31.75 0 0)
					(effects
						(font
							(size 1.27 1.27)
							(thickness 0.15)
						)
						(justify left bottom)
					)
				)
				(text "PCIe"
					(at -31.75 -95.25 0)
					(effects
						(font
							(size 1.27 1.27)
							(thickness 0.15)
						)
						(justify left bottom)
					)
				)
				(pin output line
					(at 0 0 180)
					(length 5.08)
					(name "PCIE_TX5+"
						(effects
							(font
								(size 1.27 1.27)
							)
						)
					)
					(number "A52"
						(effects
							(font
								(size 1.27 1.27)
							)
						)
					)
				)
				(pin output line
					(at 0 -2.54 180)
					(length 5.08)
					(name "PCIE_TX5-"
						(effects
							(font
								(size 1.27 1.27)
							)
						)
					)
					(number "A53"
						(effects
							(font
								(size 1.27 1.27)
							)
						)
					)
				)
				(pin input line
					(at 0 -7.62 180)
					(length 5.08)
					(name "PCIE_RX5+"
						(effects
							(font
								(size 1.27 1.27)
							)
						)
					)
					(number "B52"
						(effects
							(font
								(size 1.27 1.27)
							)
						)
					)
				)
				(pin input line
					(at 0 -10.16 180)
					(length 5.08)
					(name "PCIE_RX5-"
						(effects
							(font
								(size 1.27 1.27)
							)
						)
					)
					(number "B53"
						(effects
							(font
								(size 1.27 1.27)
							)
						)
					)
				)
				(pin output line
					(at 0 -15.24 180)
					(length 5.08)
					(name "PCIE_TX4+"
						(effects
							(font
								(size 1.27 1.27)
							)
						)
					)
					(number "A55"
						(effects
							(font
								(size 1.27 1.27)
							)
						)
					)
				)
				(pin output line
					(at 0 -17.78 180)
					(length 5.08)
					(name "PCIE_TX4-"
						(effects
							(font
								(size 1.27 1.27)
							)
						)
					)
					(number "A56"
						(effects
							(font
								(size 1.27 1.27)
							)
						)
					)
				)
				(pin input line
					(at 0 -22.86 180)
					(length 5.08)
					(name "PCIE_RX4+"
						(effects
							(font
								(size 1.27 1.27)
							)
						)
					)
					(number "B55"
						(effects
							(font
								(size 1.27 1.27)
							)
						)
					)
				)
				(pin input line
					(at 0 -25.4 180)
					(length 5.08)
					(name "PCIE_RX4-"
						(effects
							(font
								(size 1.27 1.27)
							)
						)
					)
					(number "B56"
						(effects
							(font
								(size 1.27 1.27)
							)
						)
					)
				)
				(pin output line
					(at 0 -30.48 180)
					(length 5.08)
					(name "PCIE_TX3+"
						(effects
							(font
								(size 1.27 1.27)
							)
						)
					)
					(number "A58"
						(effects
							(font
								(size 1.27 1.27)
							)
						)
					)
				)
				(pin output line
					(at 0 -33.02 180)
					(length 5.08)
					(name "PCIE_TX3-"
						(effects
							(font
								(size 1.27 1.27)
							)
						)
					)
					(number "A59"
						(effects
							(font
								(size 1.27 1.27)
							)
						)
					)
				)
				(pin input line
					(at 0 -38.1 180)
					(length 5.08)
					(name "PCIE_RX3+"
						(effects
							(font
								(size 1.27 1.27)
							)
						)
					)
					(number "B58"
						(effects
							(font
								(size 1.27 1.27)
							)
						)
					)
				)
				(pin input line
					(at 0 -40.64 180)
					(length 5.08)
					(name "PCIE_RX3-"
						(effects
							(font
								(size 1.27 1.27)
							)
						)
					)
					(number "B59"
						(effects
							(font
								(size 1.27 1.27)
							)
						)
					)
				)
				(pin output line
					(at 0 -45.72 180)
					(length 5.08)
					(name "PCIE_TX2+"
						(effects
							(font
								(size 1.27 1.27)
							)
						)
					)
					(number "A61"
						(effects
							(font
								(size 1.27 1.27)
							)
						)
					)
				)
				(pin output line
					(at 0 -48.26 180)
					(length 5.08)
					(name "PCIE_TX2-"
						(effects
							(font
								(size 1.27 1.27)
							)
						)
					)
					(number "A62"
						(effects
							(font
								(size 1.27 1.27)
							)
						)
					)
				)
				(pin input line
					(at 0 -53.34 180)
					(length 5.08)
					(name "PCIE_RX2+"
						(effects
							(font
								(size 1.27 1.27)
							)
						)
					)
					(number "B61"
						(effects
							(font
								(size 1.27 1.27)
							)
						)
					)
				)
				(pin input line
					(at 0 -55.88 180)
					(length 5.08)
					(name "PCIE_RX2-"
						(effects
							(font
								(size 1.27 1.27)
							)
						)
					)
					(number "B62"
						(effects
							(font
								(size 1.27 1.27)
							)
						)
					)
				)
				(pin output line
					(at 0 -60.96 180)
					(length 5.08)
					(name "PCIE_TX1+"
						(effects
							(font
								(size 1.27 1.27)
							)
						)
					)
					(number "A64"
						(effects
							(font
								(size 1.27 1.27)
							)
						)
					)
				)
				(pin output line
					(at 0 -63.5 180)
					(length 5.08)
					(name "PCIE_TX1-"
						(effects
							(font
								(size 1.27 1.27)
							)
						)
					)
					(number "A65"
						(effects
							(font
								(size 1.27 1.27)
							)
						)
					)
				)
				(pin input line
					(at 0 -68.58 180)
					(length 5.08)
					(name "PCIE_RX1+"
						(effects
							(font
								(size 1.27 1.27)
							)
						)
					)
					(number "B64"
						(effects
							(font
								(size 1.27 1.27)
							)
						)
					)
				)
				(pin input line
					(at 0 -71.12 180)
					(length 5.08)
					(name "PCIE_RX1-"
						(effects
							(font
								(size 1.27 1.27)
							)
						)
					)
					(number "B65"
						(effects
							(font
								(size 1.27 1.27)
							)
						)
					)
				)
				(pin output line
					(at 0 -76.2 180)
					(length 5.08)
					(name "PCIE_TX0+"
						(effects
							(font
								(size 1.27 1.27)
							)
						)
					)
					(number "A68"
						(effects
							(font
								(size 1.27 1.27)
							)
						)
					)
				)
				(pin output line
					(at 0 -78.74 180)
					(length 5.08)
					(name "PCIE_TX0-"
						(effects
							(font
								(size 1.27 1.27)
							)
						)
					)
					(number "A69"
						(effects
							(font
								(size 1.27 1.27)
							)
						)
					)
				)
				(pin input line
					(at 0 -83.82 180)
					(length 5.08)
					(name "PCIE_RX0+"
						(effects
							(font
								(size 1.27 1.27)
							)
						)
					)
					(number "B68"
						(effects
							(font
								(size 1.27 1.27)
							)
						)
					)
				)
				(pin input line
					(at 0 -86.36 180)
					(length 5.08)
					(name "PCIE_RX0-"
						(effects
							(font
								(size 1.27 1.27)
							)
						)
					)
					(number "B69"
						(effects
							(font
								(size 1.27 1.27)
							)
						)
					)
				)
				(pin output line
					(at 0 -91.44 180)
					(length 5.08)
					(name "PCIE_CK_REF+"
						(effects
							(font
								(size 1.27 1.27)
							)
						)
					)
					(number "A88"
						(effects
							(font
								(size 1.27 1.27)
							)
						)
					)
				)
				(pin output line
					(at 0 -93.98 180)
					(length 5.08)
					(name "PCIE_CK_REF-"
						(effects
							(font
								(size 1.27 1.27)
							)
						)
					)
					(number "A89"
						(effects
							(font
								(size 1.27 1.27)
							)
						)
					)
				)
			)
		)
	(symbol "antmicroBatteryHoldersClipsContacts:Battery_Holder_MS621FE-FL11E"
			(pin_names
				(offset 0)
			)
			(exclude_from_sim no)
			(in_bom yes)
			(on_board yes)
			(property "Reference" "BT"
				(at 17.78 -2.54 0)
				(effects
					(font
						(size 1.27 1.27)
						(thickness 0.15)
					)
					(justify left bottom)
				)
			)
			(property "Value" "Battery_Holder_MS621FE-FL11E"
				(at 17.78 -7.62 0)
				(effects
					(font
						(size 1.27 1.27)
						(thickness 0.15)
					)
					(justify left bottom)
					(hide yes)
				)
			)
			(property "Footprint" "antmicro-footprints:MS621FE-FL11E"
				(at 17.78 -10.16 0)
				(effects
					(font
						(size 1.27 1.27)
						(thickness 0.15)
					)
					(justify left bottom)
					(hide yes)
				)
			)
			(property "Datasheet" "https://www.sii.co.jp/en/me/datasheets/ms-rechargeable/ms621fe/"
				(at 17.78 -12.7 0)
				(effects
					(font
						(size 1.27 1.27)
						(thickness 0.15)
					)
					(justify left bottom)
					(hide yes)
				)
			)
			(property "Description" "Rechargeable Battery, Coin Cell, Single Cell, 3 V, Lithium Manganese Dioxide, 5.5 mAh, Button Cell"
				(at 0 0 0)
				(effects
					(font
						(size 1.27 1.27)
					)
					(hide yes)
				)
			)
			(property "Manufacturer" "Seiko Instruments"
				(at 17.78 -15.24 0)
				(effects
					(font
						(size 1.27 1.27)
						(thickness 0.15)
					)
					(justify left bottom)
					(hide yes)
				)
			)
			(property "MPN" "MS621FE-FL11E"
				(at 17.78 -5.08 0)
				(effects
					(font
						(size 1.27 1.27)
						(thickness 0.15)
					)
					(justify left bottom)
				)
			)
			(property "Author" "Antmicro"
				(at 17.78 -17.78 0)
				(effects
					(font
						(size 1.27 1.27)
						(thickness 0.15)
					)
					(justify left bottom)
					(hide yes)
				)
			)
			(property "License" "Apache-2.0"
				(at 17.78 -20.32 0)
				(effects
					(font
						(size 1.27 1.27)
						(thickness 0.15)
					)
					(justify left bottom)
					(hide yes)
				)
			)
			(property "ki_keywords" "HORIZONTAL, SMT, HOLDER, BATTERY"
				(at 0 0 0)
				(effects
					(font
						(size 1.27 1.27)
					)
					(hide yes)
				)
			)
			(symbol "Battery_Holder_MS621FE-FL11E_0_1"
				(rectangle
					(start -1.27 -5.08)
					(end 1.27 -4.826)
					(stroke
						(width 0.254)
						(type default)
					)
					(fill
						(type outline)
					)
				)
				(polyline
					(pts
						(xy 0 -2.54) (xy 0 -3.81)
					)
					(stroke
						(width 0.254)
						(type default)
					)
					(fill
						(type none)
					)
				)
			)
			(symbol "Battery_Holder_MS621FE-FL11E_1_1"
				(polyline
					(pts
						(xy -2.54 -3.81) (xy 2.54 -3.81)
					)
					(stroke
						(width 0.254)
						(type default)
					)
					(fill
						(type background)
					)
				)
				(polyline
					(pts
						(xy 0 -6.35) (xy 0 -5.08)
					)
					(stroke
						(width 0.254)
						(type default)
					)
					(fill
						(type background)
					)
				)
				(pin passive line
					(at 0 0 270)
					(length 2.54)
					(name "+"
						(effects
							(font
								(size 1.27 1.27)
							)
						)
					)
					(number "1"
						(effects
							(font
								(size 1.27 1.27)
							)
						)
					)
				)
				(pin passive line
					(at 0 -8.89 90)
					(length 2.54)
					(name "-"
						(effects
							(font
								(size 1.27 1.27)
							)
						)
					)
					(number "2"
						(effects
							(font
								(size 1.27 1.27)
							)
						)
					)
				)
			)
		)
	(symbol "antmicroCapacitors0402:C_100n_0402"
			(pin_numbers
				(hide yes)
			)
			(pin_names
				(hide yes)
			)
			(exclude_from_sim no)
			(in_bom yes)
			(on_board yes)
			(property "Reference" "C"
				(at 20.32 -5.08 0)
				(effects
					(font
						(size 1.27 1.27)
						(thickness 0.15)
					)
					(justify left bottom)
				)
			)
			(property "Value" "C_100n_0402"
				(at 20.32 -10.16 0)
				(effects
					(font
						(size 1.27 1.27)
						(thickness 0.15)
					)
					(justify left bottom)
					(hide yes)
				)
			)
			(property "Footprint" "antmicro-footprints:C_0402_1005Metric"
				(at 20.32 -12.7 0)
				(effects
					(font
						(size 1.27 1.27)
						(thickness 0.15)
					)
					(justify left bottom)
					(hide yes)
				)
			)
			(property "Datasheet" "https://www.murata.com/products/productdetail?partno=GRM155R61H104KE14%23"
				(at 20.32 -15.24 0)
				(effects
					(font
						(size 1.27 1.27)
						(thickness 0.15)
					)
					(justify left bottom)
					(hide yes)
				)
			)
			(property "Description" "SMD Multilayer Ceramic Capacitor, 0.1 µF, 50 V, 0402 [1005 Metric], ± 10%, X5R, GRM Series"
				(at 0 0 0)
				(effects
					(font
						(size 1.27 1.27)
					)
					(hide yes)
				)
			)
			(property "MPN" "GRM155R61H104KE14D"
				(at 20.32 -17.78 0)
				(effects
					(font
						(size 1.27 1.27)
						(thickness 0.15)
					)
					(justify left bottom)
					(hide yes)
				)
			)
			(property "Manufacturer" "Murata"
				(at 20.32 -20.32 0)
				(effects
					(font
						(size 1.27 1.27)
						(thickness 0.15)
					)
					(justify left bottom)
					(hide yes)
				)
			)
			(property "License" "Apache-2.0"
				(at 20.32 -22.86 0)
				(effects
					(font
						(size 1.27 1.27)
						(thickness 0.15)
					)
					(justify left bottom)
					(hide yes)
				)
			)
			(property "Author" "Antmicro"
				(at 20.32 -25.4 0)
				(effects
					(font
						(size 1.27 1.27)
						(thickness 0.15)
					)
					(justify left bottom)
					(hide yes)
				)
			)
			(property "Val" "100n"
				(at 20.32 -7.62 0)
				(effects
					(font
						(size 1.27 1.27)
						(thickness 0.15)
					)
					(justify left bottom)
				)
			)
			(property "Voltage" "50V"
				(at 20.32 -27.94 0)
				(effects
					(font
						(size 1.27 1.27)
					)
					(justify left bottom)
					(hide yes)
				)
			)
			(property "Dielectric" "X5R"
				(at 20.32 -30.48 0)
				(effects
					(font
						(size 1.27 1.27)
					)
					(justify left bottom)
					(hide yes)
				)
			)
			(property "Public" "False"
				(at 20.32 -33.02 0)
				(effects
					(font
						(size 1.27 1.27)
					)
					(justify left bottom)
					(hide yes)
				)
			)
			(property "ki_keywords" "0402, SMT, CAPACITOR, PASSIVE, CERAMIC, MLCC"
				(at 0 0 0)
				(effects
					(font
						(size 1.27 1.27)
					)
					(hide yes)
				)
			)
			(symbol "C_100n_0402_0_1"
				(polyline
					(pts
						(xy 2.032 -1.524) (xy 2.032 1.524)
					)
					(stroke
						(width 0.3048)
						(type default)
					)
					(fill
						(type none)
					)
				)
				(polyline
					(pts
						(xy 3.048 -1.524) (xy 3.048 1.524)
					)
					(stroke
						(width 0.3302)
						(type default)
					)
					(fill
						(type none)
					)
				)
			)
			(symbol "C_100n_0402_1_1"
				(pin passive line
					(at 0 0 0)
					(length 2.032)
					(name "~"
						(effects
							(font
								(size 1.27 1.27)
							)
						)
					)
					(number "1"
						(effects
							(font
								(size 1.27 1.27)
							)
						)
					)
				)
				(pin passive line
					(at 5.08 0 180)
					(length 2.032)
					(name "~"
						(effects
							(font
								(size 1.27 1.27)
							)
						)
					)
					(number "2"
						(effects
							(font
								(size 1.27 1.27)
							)
						)
					)
				)
			)
		)
	(symbol "antmicroCapacitors0402:C_1u_0402"
			(pin_numbers
				(hide yes)
			)
			(pin_names
				(hide yes)
			)
			(exclude_from_sim no)
			(in_bom yes)
			(on_board yes)
			(property "Reference" "C"
				(at 20.32 -5.08 0)
				(effects
					(font
						(size 1.27 1.27)
						(thickness 0.15)
					)
					(justify left bottom)
				)
			)
			(property "Value" "C_1u_0402"
				(at 20.32 -10.16 0)
				(effects
					(font
						(size 1.27 1.27)
						(thickness 0.15)
					)
					(justify left bottom)
					(hide yes)
				)
			)
			(property "Footprint" "antmicro-footprints:C_0402_1005Metric"
				(at 20.32 -12.7 0)
				(effects
					(font
						(size 1.27 1.27)
						(thickness 0.15)
					)
					(justify left bottom)
					(hide yes)
				)
			)
			(property "Datasheet" "https://product.tdk.com/en/search/capacitor/ceramic/mlcc/info?part_no=C1005X6S1A105K050BC"
				(at 20.32 -15.24 0)
				(effects
					(font
						(size 1.27 1.27)
						(thickness 0.15)
					)
					(justify left bottom)
					(hide yes)
				)
			)
			(property "Description" "SMD Multilayer Ceramic Capacitor, 1 µF, 10 V, 0402 [1005 Metric], ± 10%, X6S, C"
				(at 0 0 0)
				(effects
					(font
						(size 1.27 1.27)
					)
					(hide yes)
				)
			)
			(property "MPN" "C1005X6S1A105K050BC"
				(at 20.32 -17.78 0)
				(effects
					(font
						(size 1.27 1.27)
						(thickness 0.15)
					)
					(justify left bottom)
					(hide yes)
				)
			)
			(property "Manufacturer" "TDK"
				(at 20.32 -20.32 0)
				(effects
					(font
						(size 1.27 1.27)
						(thickness 0.15)
					)
					(justify left bottom)
					(hide yes)
				)
			)
			(property "License" "Apache-2.0"
				(at 20.32 -22.86 0)
				(effects
					(font
						(size 1.27 1.27)
						(thickness 0.15)
					)
					(justify left bottom)
					(hide yes)
				)
			)
			(property "Author" "Antmicro"
				(at 20.32 -25.4 0)
				(effects
					(font
						(size 1.27 1.27)
						(thickness 0.15)
					)
					(justify left bottom)
					(hide yes)
				)
			)
			(property "Val" "1u"
				(at 20.32 -7.62 0)
				(effects
					(font
						(size 1.27 1.27)
						(thickness 0.15)
					)
					(justify left bottom)
				)
			)
			(property "Voltage" ""
				(at 20.32 -27.94 0)
				(effects
					(font
						(size 1.27 1.27)
					)
					(justify left bottom)
					(hide yes)
				)
			)
			(property "Dielectric" ""
				(at 20.32 -30.48 0)
				(effects
					(font
						(size 1.27 1.27)
					)
					(justify left bottom)
					(hide yes)
				)
			)
			(property "Public" "False"
				(at 20.32 -33.02 0)
				(effects
					(font
						(size 1.27 1.27)
					)
					(justify left bottom)
					(hide yes)
				)
			)
			(property "ki_keywords" "0402, SMT, CAPACITOR, PASSIVE, CERAMIC, MLCC"
				(at 0 0 0)
				(effects
					(font
						(size 1.27 1.27)
					)
					(hide yes)
				)
			)
			(symbol "C_1u_0402_0_1"
				(polyline
					(pts
						(xy 2.032 -1.524) (xy 2.032 1.524)
					)
					(stroke
						(width 0.3048)
						(type default)
					)
					(fill
						(type none)
					)
				)
				(polyline
					(pts
						(xy 3.048 -1.524) (xy 3.048 1.524)
					)
					(stroke
						(width 0.3302)
						(type default)
					)
					(fill
						(type none)
					)
				)
			)
			(symbol "C_1u_0402_1_1"
				(pin passive line
					(at 0 0 0)
					(length 2.032)
					(name "~"
						(effects
							(font
								(size 1.27 1.27)
							)
						)
					)
					(number "1"
						(effects
							(font
								(size 1.27 1.27)
							)
						)
					)
				)
				(pin passive line
					(at 5.08 0 180)
					(length 2.032)
					(name "~"
						(effects
							(font
								(size 1.27 1.27)
							)
						)
					)
					(number "2"
						(effects
							(font
								(size 1.27 1.27)
							)
						)
					)
				)
			)
		)
	(symbol "antmicroCapacitors0402:C_1u_25V_0402"
			(pin_numbers
				(hide yes)
			)
			(pin_names
				(hide yes)
			)
			(exclude_from_sim no)
			(in_bom yes)
			(on_board yes)
			(property "Reference" "C"
				(at 20.32 -5.08 0)
				(effects
					(font
						(size 1.27 1.27)
						(thickness 0.15)
					)
					(justify left bottom)
				)
			)
			(property "Value" "C_1u_25V_0402"
				(at 20.32 -10.16 0)
				(effects
					(font
						(size 1.27 1.27)
						(thickness 0.15)
					)
					(justify left bottom)
					(hide yes)
				)
			)
			(property "Footprint" "antmicro-footprints:C_0402_1005Metric"
				(at 20.32 -12.7 0)
				(effects
					(font
						(size 1.27 1.27)
						(thickness 0.15)
					)
					(justify left bottom)
					(hide yes)
				)
			)
			(property "Datasheet" "https://www.murata.com/products/productdetail?partno=GRM155R61E105KE11%23"
				(at 20.32 -15.24 0)
				(effects
					(font
						(size 1.27 1.27)
						(thickness 0.15)
					)
					(justify left bottom)
					(hide yes)
				)
			)
			(property "Description" "SMD Multilayer Ceramic Capacitor, 1 µF, 25 V, 0402 [1005 Metric], ± 10%, X5R, GRM Series"
				(at 0 0 0)
				(effects
					(font
						(size 1.27 1.27)
					)
					(hide yes)
				)
			)
			(property "MPN" "GRM155R61E105KE11J"
				(at 20.32 -17.78 0)
				(effects
					(font
						(size 1.27 1.27)
						(thickness 0.15)
					)
					(justify left bottom)
					(hide yes)
				)
			)
			(property "Manufacturer" "Murata"
				(at 20.32 -20.32 0)
				(effects
					(font
						(size 1.27 1.27)
						(thickness 0.15)
					)
					(justify left bottom)
					(hide yes)
				)
			)
			(property "License" "Apache-2.0"
				(at 20.32 -22.86 0)
				(effects
					(font
						(size 1.27 1.27)
						(thickness 0.15)
					)
					(justify left bottom)
					(hide yes)
				)
			)
			(property "Author" "Antmicro"
				(at 20.32 -25.4 0)
				(effects
					(font
						(size 1.27 1.27)
						(thickness 0.15)
					)
					(justify left bottom)
					(hide yes)
				)
			)
			(property "Val" "1u"
				(at 20.32 -7.62 0)
				(effects
					(font
						(size 1.27 1.27)
						(thickness 0.15)
					)
					(justify left bottom)
				)
			)
			(property "Voltage" "25V"
				(at 20.32 -27.94 0)
				(effects
					(font
						(size 1.27 1.27)
					)
					(justify left bottom)
					(hide yes)
				)
			)
			(property "Dielectric" "X5R"
				(at 20.32 -30.48 0)
				(effects
					(font
						(size 1.27 1.27)
					)
					(justify left bottom)
					(hide yes)
				)
			)
			(property "ki_keywords" "0402, SMT, CAPACITOR, PASSIVE, CERAMIC"
				(at 0 0 0)
				(effects
					(font
						(size 1.27 1.27)
					)
					(hide yes)
				)
			)
			(symbol "C_1u_25V_0402_0_1"
				(polyline
					(pts
						(xy 2.032 -1.524) (xy 2.032 1.524)
					)
					(stroke
						(width 0.3048)
						(type default)
					)
					(fill
						(type none)
					)
				)
				(polyline
					(pts
						(xy 3.048 -1.524) (xy 3.048 1.524)
					)
					(stroke
						(width 0.3302)
						(type default)
					)
					(fill
						(type none)
					)
				)
			)
			(symbol "C_1u_25V_0402_1_1"
				(pin passive line
					(at 0 0 0)
					(length 2.032)
					(name "~"
						(effects
							(font
								(size 1.27 1.27)
							)
						)
					)
					(number "1"
						(effects
							(font
								(size 1.27 1.27)
							)
						)
					)
				)
				(pin passive line
					(at 5.08 0 180)
					(length 2.032)
					(name "~"
						(effects
							(font
								(size 1.27 1.27)
							)
						)
					)
					(number "2"
						(effects
							(font
								(size 1.27 1.27)
							)
						)
					)
				)
			)
		)
	(symbol "antmicroCapacitors0402:C_220n_0402"
			(pin_numbers
				(hide yes)
			)
			(pin_names
				(hide yes)
			)
			(exclude_from_sim no)
			(in_bom yes)
			(on_board yes)
			(property "Reference" "C"
				(at 20.32 -5.08 0)
				(effects
					(font
						(size 1.27 1.27)
						(thickness 0.15)
					)
					(justify left bottom)
				)
			)
			(property "Value" "C_220n_0402"
				(at 20.32 -10.16 0)
				(effects
					(font
						(size 1.27 1.27)
						(thickness 0.15)
					)
					(justify left bottom)
					(hide yes)
				)
			)
			(property "Footprint" "antmicro-footprints:C_0402_1005Metric"
				(at 20.32 -12.7 0)
				(effects
					(font
						(size 1.27 1.27)
						(thickness 0.15)
					)
					(justify left bottom)
					(hide yes)
				)
			)
			(property "Datasheet" "https://www.yageo.com/en/Chart/Download/pdf/CC0402KRX5R6BB224"
				(at 20.32 -15.24 0)
				(effects
					(font
						(size 1.27 1.27)
						(thickness 0.15)
					)
					(justify left bottom)
					(hide yes)
				)
			)
			(property "Description" "SMD Multilayer Ceramic Capacitor, 0.22 µF, 10 V, 0402 [1005 Metric], ± 10%, X5R, CC Series"
				(at 0 0 0)
				(effects
					(font
						(size 1.27 1.27)
					)
					(hide yes)
				)
			)
			(property "MPN" "CC0402KRX5R6BB224"
				(at 20.32 -17.78 0)
				(effects
					(font
						(size 1.27 1.27)
						(thickness 0.15)
					)
					(justify left bottom)
					(hide yes)
				)
			)
			(property "Manufacturer" "YAGEO"
				(at 20.32 -20.32 0)
				(effects
					(font
						(size 1.27 1.27)
						(thickness 0.15)
					)
					(justify left bottom)
					(hide yes)
				)
			)
			(property "License" "Apache-2.0"
				(at 20.32 -22.86 0)
				(effects
					(font
						(size 1.27 1.27)
						(thickness 0.15)
					)
					(justify left bottom)
					(hide yes)
				)
			)
			(property "Author" "Antmicro"
				(at 20.32 -25.4 0)
				(effects
					(font
						(size 1.27 1.27)
						(thickness 0.15)
					)
					(justify left bottom)
					(hide yes)
				)
			)
			(property "Val" "220n"
				(at 20.32 -7.62 0)
				(effects
					(font
						(size 1.27 1.27)
						(thickness 0.15)
					)
					(justify left bottom)
				)
			)
			(property "Voltage" ""
				(at 20.32 -27.94 0)
				(effects
					(font
						(size 1.27 1.27)
					)
					(justify left bottom)
					(hide yes)
				)
			)
			(property "Dielectric" ""
				(at 20.32 -30.48 0)
				(effects
					(font
						(size 1.27 1.27)
					)
					(justify left bottom)
					(hide yes)
				)
			)
			(property "Public" "False"
				(at 20.32 -33.02 0)
				(effects
					(font
						(size 1.27 1.27)
					)
					(justify left bottom)
					(hide yes)
				)
			)
			(property "ki_keywords" "0402, SMT, CAPACITOR, PASSIVE, MLCC, CERAMIC"
				(at 0 0 0)
				(effects
					(font
						(size 1.27 1.27)
					)
					(hide yes)
				)
			)
			(symbol "C_220n_0402_0_1"
				(polyline
					(pts
						(xy 2.032 -1.524) (xy 2.032 1.524)
					)
					(stroke
						(width 0.3048)
						(type default)
					)
					(fill
						(type none)
					)
				)
				(polyline
					(pts
						(xy 3.048 -1.524) (xy 3.048 1.524)
					)
					(stroke
						(width 0.3302)
						(type default)
					)
					(fill
						(type none)
					)
				)
			)
			(symbol "C_220n_0402_1_1"
				(pin passive line
					(at 0 0 0)
					(length 2.032)
					(name "~"
						(effects
							(font
								(size 1.27 1.27)
							)
						)
					)
					(number "1"
						(effects
							(font
								(size 1.27 1.27)
							)
						)
					)
				)
				(pin passive line
					(at 5.08 0 180)
					(length 2.032)
					(name "~"
						(effects
							(font
								(size 1.27 1.27)
							)
						)
					)
					(number "2"
						(effects
							(font
								(size 1.27 1.27)
							)
						)
					)
				)
			)
		)
	(symbol "antmicroCapacitors0402:C_47p_0402"
			(pin_numbers
				(hide yes)
			)
			(pin_names
				(hide yes)
			)
			(exclude_from_sim no)
			(in_bom yes)
			(on_board yes)
			(property "Reference" "C"
				(at 20.32 -5.08 0)
				(effects
					(font
						(size 1.27 1.27)
						(thickness 0.15)
					)
					(justify left bottom)
				)
			)
			(property "Value" "C_47p_0402"
				(at 20.32 -10.16 0)
				(effects
					(font
						(size 1.27 1.27)
						(thickness 0.15)
					)
					(justify left bottom)
					(hide yes)
				)
			)
			(property "Footprint" "antmicro-footprints:C_0402_1005Metric"
				(at 20.32 -12.7 0)
				(effects
					(font
						(size 1.27 1.27)
						(thickness 0.15)
					)
					(justify left bottom)
					(hide yes)
				)
			)
			(property "Datasheet" "https://www.kemet.com/en/us/capacitors/product/C0402C470J5GACTU.html"
				(at 20.32 -15.24 0)
				(effects
					(font
						(size 1.27 1.27)
						(thickness 0.15)
					)
					(justify left bottom)
					(hide yes)
				)
			)
			(property "Description" "SMD Multilayer Ceramic Capacitor, 47 pF, 50 V, 0402 [1005 Metric], ± 5%, C0G / NP0, C Series KEMET"
				(at 0 0 0)
				(effects
					(font
						(size 1.27 1.27)
					)
					(hide yes)
				)
			)
			(property "MPN" "C0402C470J5GACTU"
				(at 20.32 -17.78 0)
				(effects
					(font
						(size 1.27 1.27)
						(thickness 0.15)
					)
					(justify left bottom)
					(hide yes)
				)
			)
			(property "Manufacturer" "KEMET"
				(at 20.32 -20.32 0)
				(effects
					(font
						(size 1.27 1.27)
						(thickness 0.15)
					)
					(justify left bottom)
					(hide yes)
				)
			)
			(property "License" "Apache-2.0"
				(at 20.32 -22.86 0)
				(effects
					(font
						(size 1.27 1.27)
						(thickness 0.15)
					)
					(justify left bottom)
					(hide yes)
				)
			)
			(property "Author" "Antmicro"
				(at 20.32 -25.4 0)
				(effects
					(font
						(size 1.27 1.27)
						(thickness 0.15)
					)
					(justify left bottom)
					(hide yes)
				)
			)
			(property "Val" "47p"
				(at 20.32 -7.62 0)
				(effects
					(font
						(size 1.27 1.27)
						(thickness 0.15)
					)
					(justify left bottom)
				)
			)
			(property "Voltage" ""
				(at 20.32 -27.94 0)
				(effects
					(font
						(size 1.27 1.27)
					)
					(justify left bottom)
					(hide yes)
				)
			)
			(property "Dielectric" "C0G"
				(at 20.32 -30.48 0)
				(effects
					(font
						(size 1.27 1.27)
					)
					(justify left bottom)
					(hide yes)
				)
			)
			(property "Public" "False"
				(at 20.32 -33.02 0)
				(effects
					(font
						(size 1.27 1.27)
					)
					(justify left bottom)
					(hide yes)
				)
			)
			(property "ki_keywords" "0402, SMT, CAPACITOR, PASSIVE, CERAMIC, MLCC"
				(at 0 0 0)
				(effects
					(font
						(size 1.27 1.27)
					)
					(hide yes)
				)
			)
			(symbol "C_47p_0402_0_1"
				(polyline
					(pts
						(xy 2.032 -1.524) (xy 2.032 1.524)
					)
					(stroke
						(width 0.3048)
						(type default)
					)
					(fill
						(type none)
					)
				)
				(polyline
					(pts
						(xy 3.048 -1.524) (xy 3.048 1.524)
					)
					(stroke
						(width 0.3302)
						(type default)
					)
					(fill
						(type none)
					)
				)
			)
			(symbol "C_47p_0402_1_1"
				(pin passive line
					(at 0 0 0)
					(length 2.032)
					(name "~"
						(effects
							(font
								(size 1.27 1.27)
							)
						)
					)
					(number "1"
						(effects
							(font
								(size 1.27 1.27)
							)
						)
					)
				)
				(pin passive line
					(at 5.08 0 180)
					(length 2.032)
					(name "~"
						(effects
							(font
								(size 1.27 1.27)
							)
						)
					)
					(number "2"
						(effects
							(font
								(size 1.27 1.27)
							)
						)
					)
				)
			)
		)
	(symbol "antmicroCapacitors0603:C_22u_16V_0603"
			(pin_numbers
				(hide yes)
			)
			(pin_names
				(hide yes)
			)
			(exclude_from_sim no)
			(in_bom yes)
			(on_board yes)
			(property "Reference" "C"
				(at 20.32 -5.08 0)
				(effects
					(font
						(size 1.27 1.27)
						(thickness 0.15)
					)
					(justify left bottom)
				)
			)
			(property "Value" "C_22u_16V_0603"
				(at 20.32 -10.16 0)
				(effects
					(font
						(size 1.27 1.27)
						(thickness 0.15)
					)
					(justify left bottom)
					(hide yes)
				)
			)
			(property "Footprint" "antmicro-footprints:C_0603_1608Metric"
				(at 20.32 -12.7 0)
				(effects
					(font
						(size 1.27 1.27)
						(thickness 0.15)
					)
					(justify left bottom)
					(hide yes)
				)
			)
			(property "Datasheet" "https://product.samsungsem.com/mlcc/CL10A226MO7JZN.do"
				(at 20.32 -15.24 0)
				(effects
					(font
						(size 1.27 1.27)
						(thickness 0.15)
					)
					(justify left bottom)
					(hide yes)
				)
			)
			(property "Description" "SMD Multilayer Ceramic Capacitor"
				(at 0 0 0)
				(effects
					(font
						(size 1.27 1.27)
					)
					(hide yes)
				)
			)
			(property "MPN" "CL10A226MO7JZNC"
				(at 20.32 -17.78 0)
				(effects
					(font
						(size 1.27 1.27)
						(thickness 0.15)
					)
					(justify left bottom)
					(hide yes)
				)
			)
			(property "Manufacturer" "Samsung Electro-Mechanics"
				(at 20.32 -20.32 0)
				(effects
					(font
						(size 1.27 1.27)
						(thickness 0.15)
					)
					(justify left bottom)
					(hide yes)
				)
			)
			(property "License" "Apache-2.0"
				(at 20.32 -22.86 0)
				(effects
					(font
						(size 1.27 1.27)
						(thickness 0.15)
					)
					(justify left bottom)
					(hide yes)
				)
			)
			(property "Author" "Antmicro"
				(at 20.32 -25.4 0)
				(effects
					(font
						(size 1.27 1.27)
						(thickness 0.15)
					)
					(justify left bottom)
					(hide yes)
				)
			)
			(property "Val" "22u"
				(at 20.32 -7.62 0)
				(effects
					(font
						(size 1.27 1.27)
						(thickness 0.15)
					)
					(justify left bottom)
				)
			)
			(property "Voltage" "16V"
				(at 20.32 -27.94 0)
				(effects
					(font
						(size 1.27 1.27)
					)
					(justify left bottom)
					(hide yes)
				)
			)
			(property "Dielectric" ""
				(at 20.32 -30.48 0)
				(effects
					(font
						(size 1.27 1.27)
					)
					(justify left bottom)
					(hide yes)
				)
			)
			(property "Public" "False"
				(at 20.32 -33.02 0)
				(effects
					(font
						(size 1.27 1.27)
					)
					(justify left bottom)
					(hide yes)
				)
			)
			(property "ki_keywords" "0603, SMT, CAPACITOR, PASSIVE, CERAMIC"
				(at 0 0 0)
				(effects
					(font
						(size 1.27 1.27)
					)
					(hide yes)
				)
			)
			(symbol "C_22u_16V_0603_0_1"
				(polyline
					(pts
						(xy 2.032 -1.524) (xy 2.032 1.524)
					)
					(stroke
						(width 0.3048)
						(type default)
					)
					(fill
						(type none)
					)
				)
				(polyline
					(pts
						(xy 3.048 -1.524) (xy 3.048 1.524)
					)
					(stroke
						(width 0.3302)
						(type default)
					)
					(fill
						(type none)
					)
				)
			)
			(symbol "C_22u_16V_0603_1_1"
				(pin passive line
					(at 0 0 0)
					(length 2.032)
					(name "~"
						(effects
							(font
								(size 1.27 1.27)
							)
						)
					)
					(number "1"
						(effects
							(font
								(size 1.27 1.27)
							)
						)
					)
				)
				(pin passive line
					(at 5.08 0 180)
					(length 2.032)
					(name "~"
						(effects
							(font
								(size 1.27 1.27)
							)
						)
					)
					(number "2"
						(effects
							(font
								(size 1.27 1.27)
							)
						)
					)
				)
			)
		)
	(symbol "antmicroCapacitorsmisc:C_100n_0201_25V"
			(pin_numbers
				(hide yes)
			)
			(pin_names
				(hide yes)
			)
			(exclude_from_sim no)
			(in_bom yes)
			(on_board yes)
			(property "Reference" "C"
				(at 20.32 -5.08 0)
				(effects
					(font
						(size 1.27 1.27)
						(thickness 0.15)
					)
					(justify left bottom)
				)
			)
			(property "Value" "C_100n_0201_25V"
				(at 20.32 -10.16 0)
				(effects
					(font
						(size 1.27 1.27)
						(thickness 0.15)
					)
					(justify left bottom)
					(hide yes)
				)
			)
			(property "Footprint" "antmicro-footprints:C_0201"
				(at 20.32 -12.7 0)
				(effects
					(font
						(size 1.27 1.27)
						(thickness 0.15)
					)
					(justify left bottom)
					(hide yes)
				)
			)
			(property "Datasheet" "https://product.tdk.com/en/search/capacitor/ceramic/mlcc/info?part_no=C0603X5R1E104K030BB"
				(at 20.32 -15.24 0)
				(effects
					(font
						(size 1.27 1.27)
						(thickness 0.15)
					)
					(justify left bottom)
					(hide yes)
				)
			)
			(property "Description" "SMD Multilayer Ceramic Capacitor, 0.1 µF, 25 V, 0201 [0603 Metric], ± 10%, X5R, C"
				(at 0 0 0)
				(effects
					(font
						(size 1.27 1.27)
					)
					(hide yes)
				)
			)
			(property "MPN" "C0603X5R1E104K030BB"
				(at 20.32 -17.78 0)
				(effects
					(font
						(size 1.27 1.27)
						(thickness 0.15)
					)
					(justify left bottom)
					(hide yes)
				)
			)
			(property "Manufacturer" "TDK"
				(at 20.32 -20.32 0)
				(effects
					(font
						(size 1.27 1.27)
						(thickness 0.15)
					)
					(justify left bottom)
					(hide yes)
				)
			)
			(property "License" "Apache-2.0"
				(at 20.32 -22.86 0)
				(effects
					(font
						(size 1.27 1.27)
						(thickness 0.15)
					)
					(justify left bottom)
					(hide yes)
				)
			)
			(property "Author" "Antmicro"
				(at 20.32 -25.4 0)
				(effects
					(font
						(size 1.27 1.27)
						(thickness 0.15)
					)
					(justify left bottom)
					(hide yes)
				)
			)
			(property "Val" "100n"
				(at 20.32 -7.62 0)
				(effects
					(font
						(size 1.27 1.27)
						(thickness 0.15)
					)
					(justify left bottom)
				)
			)
			(property "Voltage" "25V"
				(at 20.32 -27.94 0)
				(effects
					(font
						(size 1.27 1.27)
					)
					(justify left bottom)
					(hide yes)
				)
			)
			(property "Dielectric" ""
				(at 20.32 -30.48 0)
				(effects
					(font
						(size 1.27 1.27)
					)
					(justify left bottom)
					(hide yes)
				)
			)
			(property "Public" "False"
				(at 20.32 -33.02 0)
				(effects
					(font
						(size 1.27 1.27)
					)
					(justify left bottom)
					(hide yes)
				)
			)
			(property "ki_keywords" "0201, SMT, CAPACITOR, PASSIVE, MLCC, CERAMIC"
				(at 0 0 0)
				(effects
					(font
						(size 1.27 1.27)
					)
					(hide yes)
				)
			)
			(symbol "C_100n_0201_25V_0_1"
				(polyline
					(pts
						(xy 2.032 -1.524) (xy 2.032 1.524)
					)
					(stroke
						(width 0.3048)
						(type default)
					)
					(fill
						(type none)
					)
				)
				(polyline
					(pts
						(xy 3.048 -1.524) (xy 3.048 1.524)
					)
					(stroke
						(width 0.3302)
						(type default)
					)
					(fill
						(type none)
					)
				)
			)
			(symbol "C_100n_0201_25V_1_1"
				(pin passive line
					(at 0 0 0)
					(length 2.032)
					(name "~"
						(effects
							(font
								(size 1.27 1.27)
							)
						)
					)
					(number "1"
						(effects
							(font
								(size 1.27 1.27)
							)
						)
					)
				)
				(pin passive line
					(at 5.08 0 180)
					(length 2.032)
					(name "~"
						(effects
							(font
								(size 1.27 1.27)
							)
						)
					)
					(number "2"
						(effects
							(font
								(size 1.27 1.27)
							)
						)
					)
				)
			)
		)
	(symbol "antmicroCapacitorsmisc:C_1n_1210_2kV"
			(pin_numbers
				(hide yes)
			)
			(pin_names
				(hide yes)
			)
			(exclude_from_sim no)
			(in_bom yes)
			(on_board yes)
			(property "Reference" "C"
				(at 20.32 -5.08 0)
				(effects
					(font
						(size 1.27 1.27)
						(thickness 0.15)
					)
					(justify left bottom)
				)
			)
			(property "Value" "C_1n_1210_2kV"
				(at 20.32 -10.16 0)
				(effects
					(font
						(size 1.27 1.27)
						(thickness 0.15)
					)
					(justify left bottom)
					(hide yes)
				)
			)
			(property "Footprint" "antmicro-footprints:C_1210_3225Metric"
				(at 20.32 -12.7 0)
				(effects
					(font
						(size 1.27 1.27)
						(thickness 0.15)
					)
					(justify left bottom)
					(hide yes)
				)
			)
			(property "Datasheet" "https://www.kemet.com/en/us/capacitors/product/C1210C102KGRACTU.html"
				(at 20.32 -15.24 0)
				(effects
					(font
						(size 1.27 1.27)
						(thickness 0.15)
					)
					(justify left bottom)
					(hide yes)
				)
			)
			(property "Description" "SMD Multilayer Ceramic Capacitor, High Voltage, 1000 pF, 2 kV, 1210 [3225 Metric], ± 10%, X7R"
				(at 0 0 0)
				(effects
					(font
						(size 1.27 1.27)
					)
					(hide yes)
				)
			)
			(property "MPN" "C1210C102KGRACTU"
				(at 20.32 -17.78 0)
				(effects
					(font
						(size 1.27 1.27)
						(thickness 0.15)
					)
					(justify left bottom)
					(hide yes)
				)
			)
			(property "Manufacturer" "KEMET"
				(at 20.32 -20.32 0)
				(effects
					(font
						(size 1.27 1.27)
						(thickness 0.15)
					)
					(justify left bottom)
					(hide yes)
				)
			)
			(property "License" "Apache-2.0"
				(at 20.32 -22.86 0)
				(effects
					(font
						(size 1.27 1.27)
						(thickness 0.15)
					)
					(justify left bottom)
					(hide yes)
				)
			)
			(property "Author" "Antmicro"
				(at 20.32 -25.4 0)
				(effects
					(font
						(size 1.27 1.27)
						(thickness 0.15)
					)
					(justify left bottom)
					(hide yes)
				)
			)
			(property "Val" "1n"
				(at 20.32 -7.62 0)
				(effects
					(font
						(size 1.27 1.27)
						(thickness 0.15)
					)
					(justify left bottom)
				)
			)
			(property "Voltage" "2kV"
				(at 20.32 -27.94 0)
				(effects
					(font
						(size 1.27 1.27)
					)
					(justify left bottom)
					(hide yes)
				)
			)
			(property "Dielectric" ""
				(at 20.32 -30.48 0)
				(effects
					(font
						(size 1.27 1.27)
					)
					(justify left bottom)
					(hide yes)
				)
			)
			(property "Public" "False"
				(at 20.32 -33.02 0)
				(effects
					(font
						(size 1.27 1.27)
					)
					(justify left bottom)
					(hide yes)
				)
			)
			(property "ki_keywords" "1210, SMT, CAPACITOR, PASSIVE, CERAMIC, MLCC"
				(at 0 0 0)
				(effects
					(font
						(size 1.27 1.27)
					)
					(hide yes)
				)
			)
			(symbol "C_1n_1210_2kV_0_1"
				(polyline
					(pts
						(xy 2.032 -1.524) (xy 2.032 1.524)
					)
					(stroke
						(width 0.3048)
						(type default)
					)
					(fill
						(type none)
					)
				)
				(polyline
					(pts
						(xy 3.048 -1.524) (xy 3.048 1.524)
					)
					(stroke
						(width 0.3302)
						(type default)
					)
					(fill
						(type none)
					)
				)
			)
			(symbol "C_1n_1210_2kV_1_1"
				(pin passive line
					(at 0 0 0)
					(length 2.032)
					(name "~"
						(effects
							(font
								(size 1.27 1.27)
							)
						)
					)
					(number "1"
						(effects
							(font
								(size 1.27 1.27)
							)
						)
					)
				)
				(pin passive line
					(at 5.08 0 180)
					(length 2.032)
					(name "~"
						(effects
							(font
								(size 1.27 1.27)
							)
						)
					)
					(number "2"
						(effects
							(font
								(size 1.27 1.27)
							)
						)
					)
				)
			)
		)
	(symbol "antmicroCapacitorspol:C_Pol_100u_10V_KEMET-T520-B"
			(pin_numbers
				(hide yes)
			)
			(pin_names
				(hide yes)
			)
			(exclude_from_sim no)
			(in_bom yes)
			(on_board yes)
			(property "Reference" "C"
				(at 13.97 0 0)
				(effects
					(font
						(size 1.27 1.27)
						(thickness 0.15)
					)
					(justify left bottom)
				)
			)
			(property "Value" "C_Pol_100u_10V_KEMET-T520-B"
				(at 13.97 -2.54 0)
				(effects
					(font
						(size 1.27 1.27)
						(thickness 0.15)
					)
					(justify left bottom)
					(hide yes)
				)
			)
			(property "Footprint" "antmicro-footprints:C_Pol_EIA-B"
				(at 13.97 -7.62 0)
				(effects
					(font
						(size 1.27 1.27)
						(thickness 0.15)
					)
					(justify left bottom)
					(hide yes)
				)
			)
			(property "Datasheet" "https://www.kemet.com/en/us/capacitors/product/T520B107M010ATE070.html"
				(at 13.97 -10.16 0)
				(effects
					(font
						(size 1.27 1.27)
						(thickness 0.15)
					)
					(justify left bottom)
					(hide yes)
				)
			)
			(property "Description" "Tantalum Capacitors - Polymer 10V 100uF 1311 20% ESR=70mOhms"
				(at 0 0 0)
				(effects
					(font
						(size 1.27 1.27)
					)
					(hide yes)
				)
			)
			(property "Val" "100u"
				(at 13.97 -5.08 0)
				(effects
					(font
						(size 1.27 1.27)
						(thickness 0.15)
					)
					(justify left bottom)
				)
			)
			(property "MPN" "T520B107M010ATE070"
				(at 13.97 -12.7 0)
				(effects
					(font
						(size 1.27 1.27)
						(thickness 0.15)
					)
					(justify left bottom)
					(hide yes)
				)
			)
			(property "Manufacturer" "KEMET"
				(at 13.97 -15.24 0)
				(effects
					(font
						(size 1.27 1.27)
						(thickness 0.15)
					)
					(justify left bottom)
					(hide yes)
				)
			)
			(property "License" "Apache-2.0"
				(at 13.97 -17.78 0)
				(effects
					(font
						(size 1.27 1.27)
						(thickness 0.15)
					)
					(justify left bottom)
					(hide yes)
				)
			)
			(property "Author" "Antmicro"
				(at 13.97 -20.32 0)
				(effects
					(font
						(size 1.27 1.27)
						(thickness 0.15)
					)
					(justify left bottom)
					(hide yes)
				)
			)
			(property "Voltage" "10V"
				(at 13.97 -22.86 0)
				(effects
					(font
						(size 1.27 1.27)
					)
					(justify left bottom)
				)
			)
			(property "Dielectric" "template_dielectric"
				(at 13.97 -25.4 0)
				(effects
					(font
						(size 1.27 1.27)
					)
					(justify left bottom)
					(hide yes)
				)
			)
			(property "Public" "False"
				(at 13.97 -27.94 0)
				(effects
					(font
						(size 1.27 1.27)
					)
					(justify left bottom)
					(hide yes)
				)
			)
			(property "ki_keywords" "SMT, CAPACITOR, PASSIVE, POLARIZED, TANTALUM"
				(at 0 0 0)
				(effects
					(font
						(size 1.27 1.27)
					)
					(hide yes)
				)
			)
			(symbol "C_Pol_100u_10V_KEMET-T520-B_0_1"
				(polyline
					(pts
						(xy 0.9652 1.27) (xy 0.9652 1.778)
					)
					(stroke
						(width 0)
						(type default)
					)
					(fill
						(type none)
					)
				)
				(polyline
					(pts
						(xy 1.2192 1.524) (xy 0.7112 1.524)
					)
					(stroke
						(width 0)
						(type default)
					)
					(fill
						(type none)
					)
				)
				(rectangle
					(start 1.905 -1.524)
					(end 2.286 1.524)
					(stroke
						(width 0)
						(type default)
					)
					(fill
						(type none)
					)
				)
				(rectangle
					(start 2.921 -1.524)
					(end 3.302 1.524)
					(stroke
						(width 0)
						(type default)
					)
					(fill
						(type outline)
					)
				)
			)
			(symbol "C_Pol_100u_10V_KEMET-T520-B_1_1"
				(pin passive line
					(at 0 0 0)
					(length 1.8542)
					(name "~"
						(effects
							(font
								(size 1.27 1.27)
							)
						)
					)
					(number "1"
						(effects
							(font
								(size 1.27 1.27)
							)
						)
					)
				)
				(pin passive line
					(at 5.08 0 180)
					(length 1.8542)
					(name "~"
						(effects
							(font
								(size 1.27 1.27)
							)
						)
					)
					(number "2"
						(effects
							(font
								(size 1.27 1.27)
							)
						)
					)
				)
			)
		)
	(symbol "antmicroCapacitorspol:C_Pol_68u_16V_Panasonic-TQC-D"
			(pin_numbers
				(hide yes)
			)
			(pin_names
				(hide yes)
			)
			(exclude_from_sim no)
			(in_bom yes)
			(on_board yes)
			(property "Reference" "C"
				(at 15.24 -5.08 0)
				(effects
					(font
						(size 1.27 1.27)
						(thickness 0.15)
					)
					(justify left bottom)
				)
			)
			(property "Value" "C_Pol_68u_16V_Panasonic-TQC-D"
				(at 15.24 -10.16 0)
				(effects
					(font
						(size 1.27 1.27)
						(thickness 0.15)
					)
					(justify left bottom)
					(hide yes)
				)
			)
			(property "Footprint" "antmicro-footprints:C_Pol_EIA-D"
				(at 15.24 -12.7 0)
				(effects
					(font
						(size 1.27 1.27)
						(thickness 0.15)
					)
					(justify left bottom)
					(hide yes)
				)
			)
			(property "Datasheet" "https://industrial.panasonic.com/sa/products/pt/aluminum-cap-smd/models/16TQC68MYF"
				(at 15.24 -15.24 0)
				(effects
					(font
						(size 1.27 1.27)
						(thickness 0.15)
					)
					(justify left bottom)
					(hide yes)
				)
			)
			(property "Description" "Tantalum Capacitors - Polymer 16volts 68uF ESR 50mohm"
				(at 0 0 0)
				(effects
					(font
						(size 1.27 1.27)
					)
					(hide yes)
				)
			)
			(property "Author" "Antmicro"
				(at 15.24 -17.78 0)
				(effects
					(font
						(size 1.27 1.27)
						(thickness 0.15)
					)
					(justify left bottom)
					(hide yes)
				)
			)
			(property "License" "Apache-2.0"
				(at 15.24 -20.32 0)
				(effects
					(font
						(size 1.27 1.27)
						(thickness 0.15)
					)
					(justify left bottom)
					(hide yes)
				)
			)
			(property "MPN" "16TQC68MYF"
				(at 15.24 -22.86 0)
				(effects
					(font
						(size 1.27 1.27)
						(thickness 0.15)
					)
					(justify left bottom)
					(hide yes)
				)
			)
			(property "Manufacturer" "Panasonic"
				(at 15.24 -25.4 0)
				(effects
					(font
						(size 1.27 1.27)
						(thickness 0.15)
					)
					(justify left bottom)
					(hide yes)
				)
			)
			(property "Val" "68u"
				(at 15.24 -7.62 0)
				(effects
					(font
						(size 1.27 1.27)
						(thickness 0.15)
					)
					(justify left bottom)
				)
			)
			(property "Voltage" "16V"
				(at 15.24 -27.94 0)
				(effects
					(font
						(size 1.27 1.27)
						(thickness 0.15)
					)
					(justify left bottom)
				)
			)
			(property "Dielectric" "template_dielectric"
				(at 13.97 -25.4 0)
				(effects
					(font
						(size 1.27 1.27)
					)
					(justify left bottom)
					(hide yes)
				)
			)
			(property "Public" "False"
				(at 13.97 -27.94 0)
				(effects
					(font
						(size 1.27 1.27)
					)
					(justify left bottom)
					(hide yes)
				)
			)
			(property "ki_keywords" "SMT, CAPACITOR, PASSIVE, POLARIZED, TANTALUM"
				(at 0 0 0)
				(effects
					(font
						(size 1.27 1.27)
					)
					(hide yes)
				)
			)
			(symbol "C_Pol_68u_16V_Panasonic-TQC-D_0_1"
				(polyline
					(pts
						(xy 0.9652 1.27) (xy 0.9652 1.778)
					)
					(stroke
						(width 0)
						(type default)
					)
					(fill
						(type none)
					)
				)
				(polyline
					(pts
						(xy 1.2192 1.524) (xy 0.7112 1.524)
					)
					(stroke
						(width 0)
						(type default)
					)
					(fill
						(type none)
					)
				)
				(rectangle
					(start 1.905 -1.524)
					(end 2.286 1.524)
					(stroke
						(width 0)
						(type default)
					)
					(fill
						(type none)
					)
				)
				(rectangle
					(start 2.921 -1.524)
					(end 3.302 1.524)
					(stroke
						(width 0)
						(type default)
					)
					(fill
						(type outline)
					)
				)
			)
			(symbol "C_Pol_68u_16V_Panasonic-TQC-D_1_1"
				(pin passive line
					(at 0 0 0)
					(length 1.8542)
					(name "~"
						(effects
							(font
								(size 1.27 1.27)
							)
						)
					)
					(number "1"
						(effects
							(font
								(size 1.27 1.27)
							)
						)
					)
				)
				(pin passive line
					(at 5.08 0 180)
					(length 1.8542)
					(name "~"
						(effects
							(font
								(size 1.27 1.27)
							)
						)
					)
					(number "2"
						(effects
							(font
								(size 1.27 1.27)
							)
						)
					)
				)
			)
		)
	(symbol "antmicroClockTimingClockGeneratorsPLLsFrequencySynthesizers:9DBL0651CKILF"
			(exclude_from_sim no)
			(in_bom yes)
			(on_board yes)
			(property "Reference" "U"
				(at 45.72 -2.54 0)
				(effects
					(font
						(size 1.27 1.27)
						(thickness 0.15)
					)
					(justify left bottom)
				)
			)
			(property "Value" "9DBL0651CKILF"
				(at 45.72 -10.16 0)
				(effects
					(font
						(size 1.27 1.27)
						(thickness 0.15)
					)
					(justify left bottom)
					(hide yes)
				)
			)
			(property "Footprint" "antmicro-footprints:VFQFPN-40-1EP_5x5mm_P0.4mm_EP3.5x3.5mm"
				(at 45.72 -12.7 0)
				(effects
					(font
						(size 1.27 1.27)
						(thickness 0.15)
					)
					(justify left bottom)
					(hide yes)
				)
			)
			(property "Datasheet" "https://eu.mouser.com/datasheet/2/698/REN_9DBL02x2_9DBL04x2_9DBL06x1_9DBL08x1C_DST_20221-3075841.pdf"
				(at 45.72 -15.24 0)
				(effects
					(font
						(size 1.27 1.27)
						(thickness 0.15)
					)
					(justify left bottom)
					(hide yes)
				)
			)
			(property "Description" "Clock Buffer 9DBL0651C 6 O/P 3.3V PCIE ZDB, ZO=85"
				(at 0 0 0)
				(effects
					(font
						(size 1.27 1.27)
					)
					(hide yes)
				)
			)
			(property "MPN" "9DBL0651CKILF"
				(at 45.72 -5.08 0)
				(effects
					(font
						(size 1.27 1.27)
						(thickness 0.15)
					)
					(justify left bottom)
				)
			)
			(property "Manufacturer" "Renesas"
				(at 45.72 -7.62 0)
				(effects
					(font
						(size 1.27 1.27)
						(thickness 0.15)
					)
					(justify left bottom)
					(hide yes)
				)
			)
			(property "Author" "Antmicro"
				(at 45.72 -17.78 0)
				(effects
					(font
						(size 1.27 1.27)
						(thickness 0.15)
					)
					(justify left bottom)
					(hide yes)
				)
			)
			(property "License" "Apache-2.0"
				(at 45.72 -20.32 0)
				(effects
					(font
						(size 1.27 1.27)
						(thickness 0.15)
					)
					(justify left bottom)
					(hide yes)
				)
			)
			(property "ki_keywords" "SMT, PLL, IC, CLOCK"
				(at 0 0 0)
				(effects
					(font
						(size 1.27 1.27)
					)
					(hide yes)
				)
			)
			(symbol "9DBL0651CKILF_1_1"
				(rectangle
					(start 2.54 2.54)
					(end 27.94 -58.42)
					(stroke
						(width 0.254)
						(type default)
					)
					(fill
						(type background)
					)
				)
				(pin power_in line
					(at 0 0 0)
					(length 2.54)
					(name "VDDIO"
						(effects
							(font
								(size 1.27 1.27)
							)
						)
					)
					(number "12"
						(effects
							(font
								(size 1.27 1.27)
							)
						)
					)
				)
				(pin passive line
					(at 0 0 0)
					(length 2.54)
					(hide yes)
					(name "VDDIO"
						(effects
							(font
								(size 1.27 1.27)
							)
						)
					)
					(number "17"
						(effects
							(font
								(size 1.27 1.27)
							)
						)
					)
				)
				(pin passive line
					(at 0 0 0)
					(length 2.54)
					(hide yes)
					(name "VDDIO"
						(effects
							(font
								(size 1.27 1.27)
							)
						)
					)
					(number "26"
						(effects
							(font
								(size 1.27 1.27)
							)
						)
					)
				)
				(pin passive line
					(at 0 0 0)
					(length 2.54)
					(hide yes)
					(name "VDDIO"
						(effects
							(font
								(size 1.27 1.27)
							)
						)
					)
					(number "32"
						(effects
							(font
								(size 1.27 1.27)
							)
						)
					)
				)
				(pin passive line
					(at 0 0 0)
					(length 2.54)
					(hide yes)
					(name "VDDIO"
						(effects
							(font
								(size 1.27 1.27)
							)
						)
					)
					(number "39"
						(effects
							(font
								(size 1.27 1.27)
							)
						)
					)
				)
				(pin power_in line
					(at 0 -2.54 0)
					(length 2.54)
					(name "VDD3V3"
						(effects
							(font
								(size 1.27 1.27)
							)
						)
					)
					(number "16"
						(effects
							(font
								(size 1.27 1.27)
							)
						)
					)
				)
				(pin passive line
					(at 0 -2.54 0)
					(length 2.54)
					(hide yes)
					(name "VDD3V3"
						(effects
							(font
								(size 1.27 1.27)
							)
						)
					)
					(number "31"
						(effects
							(font
								(size 1.27 1.27)
							)
						)
					)
				)
				(pin power_in line
					(at 0 -5.08 0)
					(length 2.54)
					(name "VDDA3V3"
						(effects
							(font
								(size 1.27 1.27)
							)
						)
					)
					(number "25"
						(effects
							(font
								(size 1.27 1.27)
							)
						)
					)
				)
				(pin power_in line
					(at 0 -7.62 0)
					(length 2.54)
					(name "VDDDIG3V3"
						(effects
							(font
								(size 1.27 1.27)
							)
						)
					)
					(number "11"
						(effects
							(font
								(size 1.27 1.27)
							)
						)
					)
				)
				(pin power_in line
					(at 0 -10.16 0)
					(length 2.54)
					(name "VDDR"
						(effects
							(font
								(size 1.27 1.27)
							)
						)
					)
					(number "5"
						(effects
							(font
								(size 1.27 1.27)
							)
						)
					)
				)
				(pin input line
					(at 0 -15.24 0)
					(length 2.54)
					(name "CLK_IN+"
						(effects
							(font
								(size 1.27 1.27)
							)
						)
					)
					(number "6"
						(effects
							(font
								(size 1.27 1.27)
							)
						)
					)
				)
				(pin input line
					(at 0 -17.78 0)
					(length 2.54)
					(name "CLK_IN-"
						(effects
							(font
								(size 1.27 1.27)
							)
						)
					)
					(number "7"
						(effects
							(font
								(size 1.27 1.27)
							)
						)
					)
				)
				(pin input line
					(at 0 -22.86 0)
					(length 2.54)
					(name "~{OE0}"
						(effects
							(font
								(size 1.27 1.27)
							)
						)
					)
					(number "13"
						(effects
							(font
								(size 1.27 1.27)
							)
						)
					)
				)
				(pin input line
					(at 0 -25.4 0)
					(length 2.54)
					(name "~{OE1}"
						(effects
							(font
								(size 1.27 1.27)
							)
						)
					)
					(number "21"
						(effects
							(font
								(size 1.27 1.27)
							)
						)
					)
				)
				(pin input line
					(at 0 -27.94 0)
					(length 2.54)
					(name "~{OE2}"
						(effects
							(font
								(size 1.27 1.27)
							)
						)
					)
					(number "24"
						(effects
							(font
								(size 1.27 1.27)
							)
						)
					)
				)
				(pin input line
					(at 0 -30.48 0)
					(length 2.54)
					(name "~{OE3}"
						(effects
							(font
								(size 1.27 1.27)
							)
						)
					)
					(number "29"
						(effects
							(font
								(size 1.27 1.27)
							)
						)
					)
				)
				(pin input line
					(at 0 -33.02 0)
					(length 2.54)
					(name "~{OE4}"
						(effects
							(font
								(size 1.27 1.27)
							)
						)
					)
					(number "35"
						(effects
							(font
								(size 1.27 1.27)
							)
						)
					)
				)
				(pin input line
					(at 0 -35.56 0)
					(length 2.54)
					(name "~{OE5}"
						(effects
							(font
								(size 1.27 1.27)
							)
						)
					)
					(number "38"
						(effects
							(font
								(size 1.27 1.27)
							)
						)
					)
				)
				(pin input line
					(at 0 -38.1 0)
					(length 2.54)
					(name "~{CKPWRGD_PD}"
						(effects
							(font
								(size 1.27 1.27)
							)
						)
					)
					(number "40"
						(effects
							(font
								(size 1.27 1.27)
							)
						)
					)
				)
				(pin input line
					(at 0 -40.64 0)
					(length 2.54)
					(name "~{HIBW_BYPM_LOBW}"
						(effects
							(font
								(size 1.27 1.27)
							)
						)
					)
					(number "2"
						(effects
							(font
								(size 1.27 1.27)
							)
						)
					)
				)
				(pin input line
					(at 0 -45.72 0)
					(length 2.54)
					(name "SCLK"
						(effects
							(font
								(size 1.27 1.27)
							)
						)
					)
					(number "9"
						(effects
							(font
								(size 1.27 1.27)
							)
						)
					)
				)
				(pin bidirectional line
					(at 0 -48.26 0)
					(length 2.54)
					(name "SDAT"
						(effects
							(font
								(size 1.27 1.27)
							)
						)
					)
					(number "10"
						(effects
							(font
								(size 1.27 1.27)
							)
						)
					)
				)
				(pin input line
					(at 0 -50.8 0)
					(length 2.54)
					(name "SADR_{TRI}"
						(effects
							(font
								(size 1.27 1.27)
							)
						)
					)
					(number "1"
						(effects
							(font
								(size 1.27 1.27)
							)
						)
					)
				)
				(pin no_connect line
					(at 2.54 -54.61 0)
					(length 2.54)
					(hide yes)
					(name "NC"
						(effects
							(font
								(size 1.27 1.27)
							)
						)
					)
					(number "20"
						(effects
							(font
								(size 1.27 1.27)
							)
						)
					)
				)
				(pin no_connect line
					(at 2.54 -55.88 0)
					(length 2.54)
					(hide yes)
					(name "NC"
						(effects
							(font
								(size 1.27 1.27)
							)
						)
					)
					(number "30"
						(effects
							(font
								(size 1.27 1.27)
							)
						)
					)
				)
				(pin output line
					(at 30.48 0 180)
					(length 2.54)
					(name "DIF0+"
						(effects
							(font
								(size 1.27 1.27)
							)
						)
					)
					(number "14"
						(effects
							(font
								(size 1.27 1.27)
							)
						)
					)
				)
				(pin output line
					(at 30.48 -2.54 180)
					(length 2.54)
					(name "DIF0-"
						(effects
							(font
								(size 1.27 1.27)
							)
						)
					)
					(number "15"
						(effects
							(font
								(size 1.27 1.27)
							)
						)
					)
				)
				(pin output line
					(at 30.48 -7.62 180)
					(length 2.54)
					(name "DIF1+"
						(effects
							(font
								(size 1.27 1.27)
							)
						)
					)
					(number "18"
						(effects
							(font
								(size 1.27 1.27)
							)
						)
					)
				)
				(pin output line
					(at 30.48 -10.16 180)
					(length 2.54)
					(name "DIF1-"
						(effects
							(font
								(size 1.27 1.27)
							)
						)
					)
					(number "19"
						(effects
							(font
								(size 1.27 1.27)
							)
						)
					)
				)
				(pin output line
					(at 30.48 -15.24 180)
					(length 2.54)
					(name "DIF2+"
						(effects
							(font
								(size 1.27 1.27)
							)
						)
					)
					(number "22"
						(effects
							(font
								(size 1.27 1.27)
							)
						)
					)
				)
				(pin output line
					(at 30.48 -17.78 180)
					(length 2.54)
					(name "DIF2-"
						(effects
							(font
								(size 1.27 1.27)
							)
						)
					)
					(number "23"
						(effects
							(font
								(size 1.27 1.27)
							)
						)
					)
				)
				(pin output line
					(at 30.48 -22.86 180)
					(length 2.54)
					(name "DIF3+"
						(effects
							(font
								(size 1.27 1.27)
							)
						)
					)
					(number "27"
						(effects
							(font
								(size 1.27 1.27)
							)
						)
					)
				)
				(pin output line
					(at 30.48 -25.4 180)
					(length 2.54)
					(name "DIF3-"
						(effects
							(font
								(size 1.27 1.27)
							)
						)
					)
					(number "28"
						(effects
							(font
								(size 1.27 1.27)
							)
						)
					)
				)
				(pin output line
					(at 30.48 -30.48 180)
					(length 2.54)
					(name "DIF4+"
						(effects
							(font
								(size 1.27 1.27)
							)
						)
					)
					(number "33"
						(effects
							(font
								(size 1.27 1.27)
							)
						)
					)
				)
				(pin output line
					(at 30.48 -33.02 180)
					(length 2.54)
					(name "DIF4-"
						(effects
							(font
								(size 1.27 1.27)
							)
						)
					)
					(number "34"
						(effects
							(font
								(size 1.27 1.27)
							)
						)
					)
				)
				(pin output line
					(at 30.48 -38.1 180)
					(length 2.54)
					(name "DIF5+"
						(effects
							(font
								(size 1.27 1.27)
							)
						)
					)
					(number "36"
						(effects
							(font
								(size 1.27 1.27)
							)
						)
					)
				)
				(pin output line
					(at 30.48 -40.64 180)
					(length 2.54)
					(name "DIF5-"
						(effects
							(font
								(size 1.27 1.27)
							)
						)
					)
					(number "37"
						(effects
							(font
								(size 1.27 1.27)
							)
						)
					)
				)
				(pin no_connect line
					(at 30.48 -45.72 180)
					(length 2.54)
					(name "FB_DNC+"
						(effects
							(font
								(size 1.27 1.27)
							)
						)
					)
					(number "3"
						(effects
							(font
								(size 1.27 1.27)
							)
						)
					)
				)
				(pin no_connect line
					(at 30.48 -48.26 180)
					(length 2.54)
					(name "FB_DNC-"
						(effects
							(font
								(size 1.27 1.27)
							)
						)
					)
					(number "4"
						(effects
							(font
								(size 1.27 1.27)
							)
						)
					)
				)
				(pin passive line
					(at 30.48 -53.34 180)
					(length 2.54)
					(name "EPAD"
						(effects
							(font
								(size 1.27 1.27)
							)
						)
					)
					(number "41"
						(effects
							(font
								(size 1.27 1.27)
							)
						)
					)
				)
				(pin power_in line
					(at 30.48 -55.88 180)
					(length 2.54)
					(name "GNDDIG"
						(effects
							(font
								(size 1.27 1.27)
							)
						)
					)
					(number "8"
						(effects
							(font
								(size 1.27 1.27)
							)
						)
					)
				)
			)
		)
	(symbol "antmicroCommonModeChokes:Choke_SRF2012A-801Y"
			(pin_names
				(hide yes)
			)
			(exclude_from_sim no)
			(in_bom yes)
			(on_board yes)
			(property "Reference" "T"
				(at 17.78 -3.81 0)
				(effects
					(font
						(size 1.27 1.27)
						(thickness 0.15)
					)
					(justify left bottom)
				)
			)
			(property "Value" "Choke_SRF2012A-801Y"
				(at 17.78 -8.89 0)
				(effects
					(font
						(size 1.27 1.27)
						(thickness 0.15)
					)
					(justify left bottom)
					(hide yes)
				)
			)
			(property "Footprint" "antmicro-footprints:Choke_0805_2012Metric"
				(at 17.78 -11.43 0)
				(effects
					(font
						(size 1.27 1.27)
						(thickness 0.15)
					)
					(justify left bottom)
					(hide yes)
				)
			)
			(property "Datasheet" "https://www.bourns.com/docs/product-datasheets/srf2012a-801y.pdf"
				(at 17.78 -13.97 0)
				(effects
					(font
						(size 1.27 1.27)
						(thickness 0.15)
					)
					(justify left bottom)
					(hide yes)
				)
			)
			(property "Description" "2 Line Common Mode Choke Surface Mount 800 Ohms @ 100 MHz 300mA DCR 880mOhm"
				(at 0 0 0)
				(effects
					(font
						(size 1.27 1.27)
					)
					(hide yes)
				)
			)
			(property "Manufacturer" "Bourns"
				(at 17.78 -16.51 0)
				(effects
					(font
						(size 1.27 1.27)
						(thickness 0.15)
					)
					(justify left bottom)
					(hide yes)
				)
			)
			(property "MPN" "SRF2012A-801Y"
				(at 17.78 -6.35 0)
				(effects
					(font
						(size 1.27 1.27)
						(thickness 0.15)
					)
					(justify left bottom)
				)
			)
			(property "IMax" "0.3 A"
				(at 17.78 -19.05 0)
				(effects
					(font
						(size 1.27 1.27)
						(thickness 0.15)
					)
					(justify left bottom)
					(hide yes)
				)
			)
			(property "Author" "Antmicro"
				(at 17.78 -21.59 0)
				(effects
					(font
						(size 1.27 1.27)
						(thickness 0.15)
					)
					(justify left bottom)
					(hide yes)
				)
			)
			(property "License" "Apache-2.0"
				(at 17.78 -24.13 0)
				(effects
					(font
						(size 1.27 1.27)
						(thickness 0.15)
					)
					(justify left bottom)
					(hide yes)
				)
			)
			(property "Public" "False"
				(at 26.67 -33.02 0)
				(effects
					(font
						(size 1.27 1.27)
					)
					(justify left bottom)
					(hide yes)
				)
			)
			(property "ki_keywords" "CHOKE, PASSIVE"
				(at 0 0 0)
				(effects
					(font
						(size 1.27 1.27)
					)
					(hide yes)
				)
			)
			(property "ki_fp_filters" "IND_ACM9070_TDK"
				(at 0 0 0)
				(effects
					(font
						(size 1.27 1.27)
					)
					(hide yes)
				)
			)
			(symbol "Choke_SRF2012A-801Y_1_1"
				(circle
					(center 2.032 -1.016)
					(radius 0.254)
					(stroke
						(width 0.254)
						(type default)
					)
					(fill
						(type outline)
					)
				)
				(circle
					(center 2.032 -3.81)
					(radius 0.254)
					(stroke
						(width 0.254)
						(type default)
					)
					(fill
						(type outline)
					)
				)
				(polyline
					(pts
						(xy 2.54 -0.508) (xy 2.54 0)
					)
					(stroke
						(width 0)
						(type default)
					)
					(fill
						(type none)
					)
				)
				(polyline
					(pts
						(xy 2.54 -2.032) (xy 7.62 -2.032)
					)
					(stroke
						(width 0.254)
						(type default)
					)
					(fill
						(type none)
					)
				)
				(polyline
					(pts
						(xy 2.54 -4.572) (xy 2.54 -5.08)
					)
					(stroke
						(width 0)
						(type default)
					)
					(fill
						(type none)
					)
				)
				(arc
					(start 3.556 -0.508)
					(mid 3.048 -1.0138)
					(end 2.54 -0.508)
					(stroke
						(width 0)
						(type default)
					)
					(fill
						(type none)
					)
				)
				(arc
					(start 2.54 -4.572)
					(mid 3.048 -4.0662)
					(end 3.556 -4.572)
					(stroke
						(width 0)
						(type default)
					)
					(fill
						(type none)
					)
				)
				(arc
					(start 4.572 -0.508)
					(mid 4.064 -1.0138)
					(end 3.556 -0.508)
					(stroke
						(width 0)
						(type default)
					)
					(fill
						(type none)
					)
				)
				(arc
					(start 3.556 -4.572)
					(mid 4.064 -4.0662)
					(end 4.572 -4.572)
					(stroke
						(width 0)
						(type default)
					)
					(fill
						(type none)
					)
				)
				(arc
					(start 5.588 -0.508)
					(mid 5.08 -1.0138)
					(end 4.572 -0.508)
					(stroke
						(width 0)
						(type default)
					)
					(fill
						(type none)
					)
				)
				(arc
					(start 4.572 -4.572)
					(mid 5.08 -4.0662)
					(end 5.588 -4.572)
					(stroke
						(width 0)
						(type default)
					)
					(fill
						(type none)
					)
				)
				(arc
					(start 6.604 -0.508)
					(mid 6.096 -1.0138)
					(end 5.588 -0.508)
					(stroke
						(width 0)
						(type default)
					)
					(fill
						(type none)
					)
				)
				(arc
					(start 5.588 -4.572)
					(mid 6.096 -4.0662)
					(end 6.604 -4.572)
					(stroke
						(width 0)
						(type default)
					)
					(fill
						(type none)
					)
				)
				(arc
					(start 7.62 -0.508)
					(mid 7.112 -1.0138)
					(end 6.604 -0.508)
					(stroke
						(width 0)
						(type default)
					)
					(fill
						(type none)
					)
				)
				(arc
					(start 6.604 -4.572)
					(mid 7.112 -4.0662)
					(end 7.62 -4.572)
					(stroke
						(width 0)
						(type default)
					)
					(fill
						(type none)
					)
				)
				(polyline
					(pts
						(xy 7.62 0) (xy 7.62 -0.508)
					)
					(stroke
						(width 0)
						(type default)
					)
					(fill
						(type none)
					)
				)
				(polyline
					(pts
						(xy 7.62 -3.048) (xy 2.54 -3.048)
					)
					(stroke
						(width 0.254)
						(type default)
					)
					(fill
						(type none)
					)
				)
				(polyline
					(pts
						(xy 7.62 -4.572) (xy 7.62 -5.08)
					)
					(stroke
						(width 0)
						(type default)
					)
					(fill
						(type none)
					)
				)
				(pin passive line
					(at 0 0 0)
					(length 2.54)
					(name "1"
						(effects
							(font
								(size 1.27 1.27)
							)
						)
					)
					(number "1"
						(effects
							(font
								(size 1.27 1.27)
							)
						)
					)
				)
				(pin passive line
					(at 0 -5.08 0)
					(length 2.54)
					(name "4"
						(effects
							(font
								(size 1.27 1.27)
							)
						)
					)
					(number "4"
						(effects
							(font
								(size 1.27 1.27)
							)
						)
					)
				)
				(pin passive line
					(at 10.16 0 180)
					(length 2.54)
					(name "2"
						(effects
							(font
								(size 1.27 1.27)
							)
						)
					)
					(number "2"
						(effects
							(font
								(size 1.27 1.27)
							)
						)
					)
				)
				(pin passive line
					(at 10.16 -5.08 180)
					(length 2.54)
					(name "3"
						(effects
							(font
								(size 1.27 1.27)
							)
						)
					)
					(number "3"
						(effects
							(font
								(size 1.27 1.27)
							)
						)
					)
				)
			)
		)
	(symbol "antmicroDCDCConverters:TPS564247DRLR"
			(exclude_from_sim no)
			(in_bom yes)
			(on_board yes)
			(property "Reference" "U"
				(at 30.48 -5.08 0)
				(effects
					(font
						(size 1.27 1.27)
						(thickness 0.15)
					)
					(justify left bottom)
				)
			)
			(property "Value" "TPS564247DRLR"
				(at 30.48 -10.16 0)
				(effects
					(font
						(size 1.27 1.27)
						(thickness 0.15)
					)
					(justify left bottom)
					(hide yes)
				)
			)
			(property "Footprint" "antmicro-footprints:SOT-563"
				(at 30.48 -12.7 0)
				(effects
					(font
						(size 1.27 1.27)
						(thickness 0.15)
					)
					(justify left bottom)
					(hide yes)
				)
			)
			(property "Datasheet" "https://www.ti.com/lit/ds/symlink/tps564247.pdf?ts=1713526387938&ref_url=https%253A%252F%252Fwww.mouser.pl%252F"
				(at 30.48 -15.24 0)
				(effects
					(font
						(size 1.27 1.27)
						(thickness 0.15)
					)
					(justify left bottom)
					(hide yes)
				)
			)
			(property "Description" "Switching Voltage Regulators 3-V to 16-V input voltage, 4-A FCCM mode, synchronous buck converter in SOT-563 package 6-SOT-5X3 -40 to 125"
				(at 0 0 0)
				(effects
					(font
						(size 1.27 1.27)
					)
					(hide yes)
				)
			)
			(property "Manufacturer" "Texas Instruments"
				(at 30.48 -17.78 0)
				(effects
					(font
						(size 1.27 1.27)
						(thickness 0.15)
					)
					(justify left bottom)
					(hide yes)
				)
			)
			(property "MPN" "TPS564247DRLR"
				(at 30.48 -7.62 0)
				(effects
					(font
						(size 1.27 1.27)
						(thickness 0.15)
					)
					(justify left bottom)
				)
			)
			(property "Author" "Antmicro"
				(at 30.48 -20.32 0)
				(effects
					(font
						(size 1.27 1.27)
						(thickness 0.15)
					)
					(justify left bottom)
					(hide yes)
				)
			)
			(property "License" "Apache-2.0"
				(at 30.48 -22.86 0)
				(effects
					(font
						(size 1.27 1.27)
						(thickness 0.15)
					)
					(justify left bottom)
					(hide yes)
				)
			)
			(property "ki_keywords" "SMT, PMIC, IC, VOLTAGE"
				(at 0 0 0)
				(effects
					(font
						(size 1.27 1.27)
					)
					(hide yes)
				)
			)
			(symbol "TPS564247DRLR_1_1"
				(rectangle
					(start 2.54 1.27)
					(end 12.7 -11.43)
					(stroke
						(width 0.254)
						(type default)
					)
					(fill
						(type background)
					)
				)
				(pin power_in line
					(at 0 0 0)
					(length 2.54)
					(name "V_{IN}"
						(effects
							(font
								(size 1.27 1.27)
							)
						)
					)
					(number "1"
						(effects
							(font
								(size 1.27 1.27)
							)
						)
					)
				)
				(pin passive line
					(at 0 -5.08 0)
					(length 2.54)
					(name "EN"
						(effects
							(font
								(size 1.27 1.27)
							)
						)
					)
					(number "5"
						(effects
							(font
								(size 1.27 1.27)
							)
						)
					)
				)
				(pin power_in line
					(at 0 -7.62 0)
					(length 2.54)
					(name "AGND"
						(effects
							(font
								(size 1.27 1.27)
							)
						)
					)
					(number "4"
						(effects
							(font
								(size 1.27 1.27)
							)
						)
					)
				)
				(pin power_in line
					(at 0 -10.16 0)
					(length 2.54)
					(name "GND"
						(effects
							(font
								(size 1.27 1.27)
							)
						)
					)
					(number "3"
						(effects
							(font
								(size 1.27 1.27)
							)
						)
					)
				)
				(pin passive line
					(at 15.24 0 180)
					(length 2.54)
					(name "SW"
						(effects
							(font
								(size 1.27 1.27)
							)
						)
					)
					(number "2"
						(effects
							(font
								(size 1.27 1.27)
							)
						)
					)
				)
				(pin passive line
					(at 15.24 -7.62 180)
					(length 2.54)
					(name "FB"
						(effects
							(font
								(size 1.27 1.27)
							)
						)
					)
					(number "6"
						(effects
							(font
								(size 1.27 1.27)
							)
						)
					)
				)
			)
		)
	(symbol "antmicroDCDCConverters:TPS56C230"
			(exclude_from_sim no)
			(in_bom yes)
			(on_board yes)
			(property "Reference" "U"
				(at 33.02 -2.54 0)
				(effects
					(font
						(size 1.27 1.27)
						(thickness 0.15)
					)
					(justify left bottom)
				)
			)
			(property "Value" "TPS56C230"
				(at 33.02 -5.08 0)
				(effects
					(font
						(size 1.27 1.27)
						(thickness 0.15)
					)
					(justify left bottom)
					(hide yes)
				)
			)
			(property "Footprint" "antmicro-footprints:QFN-20-1EP_3x3mm_P0.45mm_TPS56xxxx"
				(at 33.02 -7.62 0)
				(effects
					(font
						(size 1.27 1.27)
						(thickness 0.15)
					)
					(justify left bottom)
					(hide yes)
				)
			)
			(property "Datasheet" "https://www.ti.com/lit/ds/symlink/tps56c230.pdf?ts=1672843259715&ref_url=https%253A%252F%252Fwww.ti.com%252Fproduct%252FTPS56C230"
				(at 33.02 -10.16 0)
				(effects
					(font
						(size 1.27 1.27)
						(thickness 0.15)
					)
					(justify left bottom)
					(hide yes)
				)
			)
			(property "Description" "DC/DC converter"
				(at 0 0 0)
				(effects
					(font
						(size 1.27 1.27)
					)
					(hide yes)
				)
			)
			(property "Manufacturer" "Texas Instruments"
				(at 33.02 -12.7 0)
				(effects
					(font
						(size 1.27 1.27)
						(thickness 0.15)
					)
					(justify left bottom)
					(hide yes)
				)
			)
			(property "MPN" "TPS56C230RJER"
				(at 33.02 -15.24 0)
				(effects
					(font
						(size 1.27 1.27)
						(thickness 0.15)
					)
					(justify left bottom)
				)
			)
			(property "Author" "Antmicro"
				(at 33.02 -17.78 0)
				(effects
					(font
						(size 1.27 1.27)
						(thickness 0.15)
					)
					(justify left bottom)
					(hide yes)
				)
			)
			(property "License" "Apache-2.0"
				(at 33.02 -20.32 0)
				(effects
					(font
						(size 1.27 1.27)
						(thickness 0.15)
					)
					(justify left bottom)
					(hide yes)
				)
			)
			(property "ki_keywords" "SMT, PMIC, IC, SWITCHING, VOLTAGE, REGULATOR, DC-DC"
				(at 0 0 0)
				(effects
					(font
						(size 1.27 1.27)
					)
					(hide yes)
				)
			)
			(symbol "TPS56C230_1_1"
				(rectangle
					(start 2.54 2.54)
					(end 15.24 -25.4)
					(stroke
						(width 0.254)
						(type default)
					)
					(fill
						(type background)
					)
				)
				(pin power_in line
					(at 0 0 0)
					(length 2.54)
					(name "V_{IN}"
						(effects
							(font
								(size 1.27 1.27)
							)
						)
					)
					(number "2"
						(effects
							(font
								(size 1.27 1.27)
							)
						)
					)
				)
				(pin passive line
					(at 0 0 0)
					(length 2.54)
					(hide yes)
					(name "V_{IN}"
						(effects
							(font
								(size 1.27 1.27)
							)
						)
					)
					(number "3"
						(effects
							(font
								(size 1.27 1.27)
							)
						)
					)
				)
				(pin passive line
					(at 0 0 0)
					(length 2.54)
					(hide yes)
					(name "V_{IN}"
						(effects
							(font
								(size 1.27 1.27)
							)
						)
					)
					(number "4"
						(effects
							(font
								(size 1.27 1.27)
							)
						)
					)
				)
				(pin passive line
					(at 0 0 0)
					(length 2.54)
					(hide yes)
					(name "V_{IN}"
						(effects
							(font
								(size 1.27 1.27)
							)
						)
					)
					(number "5"
						(effects
							(font
								(size 1.27 1.27)
							)
						)
					)
				)
				(pin passive line
					(at 0 -5.08 0)
					(length 2.54)
					(name "EN"
						(effects
							(font
								(size 1.27 1.27)
							)
						)
					)
					(number "12"
						(effects
							(font
								(size 1.27 1.27)
							)
						)
					)
				)
				(pin passive line
					(at 0 -10.16 0)
					(length 2.54)
					(name "V_{CC}"
						(effects
							(font
								(size 1.27 1.27)
							)
						)
					)
					(number "17"
						(effects
							(font
								(size 1.27 1.27)
							)
						)
					)
				)
				(pin passive line
					(at 0 -17.78 0)
					(length 2.54)
					(name "PG"
						(effects
							(font
								(size 1.27 1.27)
							)
						)
					)
					(number "9"
						(effects
							(font
								(size 1.27 1.27)
							)
						)
					)
				)
				(pin passive line
					(at 0 -22.86 0)
					(length 2.54)
					(name "MODE"
						(effects
							(font
								(size 1.27 1.27)
							)
						)
					)
					(number "15"
						(effects
							(font
								(size 1.27 1.27)
							)
						)
					)
				)
				(pin no_connect line
					(at 15.24 -12.7 180)
					(length 2.54)
					(hide yes)
					(name "NC"
						(effects
							(font
								(size 1.27 1.27)
							)
						)
					)
					(number "16"
						(effects
							(font
								(size 1.27 1.27)
							)
						)
					)
				)
				(pin no_connect line
					(at 15.24 -17.78 180)
					(length 2.54)
					(hide yes)
					(name "NC"
						(effects
							(font
								(size 1.27 1.27)
							)
						)
					)
					(number "10"
						(effects
							(font
								(size 1.27 1.27)
							)
						)
					)
				)
				(pin passive line
					(at 17.78 0 180)
					(length 2.54)
					(name "BST"
						(effects
							(font
								(size 1.27 1.27)
							)
						)
					)
					(number "1"
						(effects
							(font
								(size 1.27 1.27)
							)
						)
					)
				)
				(pin passive line
					(at 17.78 -5.08 180)
					(length 2.54)
					(name "SW"
						(effects
							(font
								(size 1.27 1.27)
							)
						)
					)
					(number "19"
						(effects
							(font
								(size 1.27 1.27)
							)
						)
					)
				)
				(pin passive line
					(at 17.78 -5.08 180)
					(length 2.54)
					(hide yes)
					(name "SW"
						(effects
							(font
								(size 1.27 1.27)
							)
						)
					)
					(number "20"
						(effects
							(font
								(size 1.27 1.27)
							)
						)
					)
				)
				(pin passive line
					(at 17.78 -5.08 180)
					(length 2.54)
					(hide yes)
					(name "SW"
						(effects
							(font
								(size 1.27 1.27)
							)
						)
					)
					(number "6"
						(effects
							(font
								(size 1.27 1.27)
							)
						)
					)
				)
				(pin passive line
					(at 17.78 -10.16 180)
					(length 2.54)
					(name "FB"
						(effects
							(font
								(size 1.27 1.27)
							)
						)
					)
					(number "14"
						(effects
							(font
								(size 1.27 1.27)
							)
						)
					)
				)
				(pin passive line
					(at 17.78 -15.24 180)
					(length 2.54)
					(name "SS"
						(effects
							(font
								(size 1.27 1.27)
							)
						)
					)
					(number "11"
						(effects
							(font
								(size 1.27 1.27)
							)
						)
					)
				)
				(pin passive line
					(at 17.78 -20.32 180)
					(length 2.54)
					(name "AGND"
						(effects
							(font
								(size 1.27 1.27)
							)
						)
					)
					(number "13"
						(effects
							(font
								(size 1.27 1.27)
							)
						)
					)
				)
				(pin passive line
					(at 17.78 -22.86 180)
					(length 2.54)
					(name "PGND"
						(effects
							(font
								(size 1.27 1.27)
							)
						)
					)
					(number "18"
						(effects
							(font
								(size 1.27 1.27)
							)
						)
					)
				)
				(pin passive line
					(at 17.78 -22.86 180)
					(length 2.54)
					(hide yes)
					(name "PGND"
						(effects
							(font
								(size 1.27 1.27)
							)
						)
					)
					(number "21"
						(effects
							(font
								(size 1.27 1.27)
							)
						)
					)
				)
				(pin passive line
					(at 17.78 -22.86 180)
					(length 2.54)
					(hide yes)
					(name "PGND"
						(effects
							(font
								(size 1.27 1.27)
							)
						)
					)
					(number "7"
						(effects
							(font
								(size 1.27 1.27)
							)
						)
					)
				)
				(pin passive line
					(at 17.78 -22.86 180)
					(length 2.54)
					(hide yes)
					(name "PGND"
						(effects
							(font
								(size 1.27 1.27)
							)
						)
					)
					(number "8"
						(effects
							(font
								(size 1.27 1.27)
							)
						)
					)
				)
			)
		)
	(symbol "antmicroDiodesRectifiersSingle:BAT54C"
			(pin_names
				(hide yes)
			)
			(exclude_from_sim no)
			(in_bom yes)
			(on_board yes)
			(property "Reference" "D"
				(at 22.86 -3.81 0)
				(effects
					(font
						(size 1.27 1.27)
						(thickness 0.15)
					)
					(justify left bottom)
				)
			)
			(property "Value" "BAT54C"
				(at 22.86 -8.89 0)
				(effects
					(font
						(size 1.27 1.27)
						(thickness 0.15)
					)
					(justify left bottom)
					(hide yes)
				)
			)
			(property "Footprint" "antmicro-footprints:SOT-23-3"
				(at 22.86 -11.43 0)
				(effects
					(font
						(size 1.27 1.27)
						(thickness 0.15)
					)
					(justify left bottom)
					(hide yes)
				)
			)
			(property "Datasheet" "https://diotec.com/request/datasheet/bat54.pdf"
				(at 22.86 -13.97 0)
				(effects
					(font
						(size 1.27 1.27)
						(thickness 0.15)
					)
					(justify left bottom)
					(hide yes)
				)
			)
			(property "Description" "Small Signal Schottky Diode, Dual Common Cathode, 30 V, 200 mA, 400 mV, 600 mA, 125 °C"
				(at 0 0 0)
				(effects
					(font
						(size 1.27 1.27)
					)
					(hide yes)
				)
			)
			(property "MPN" "BAT54C"
				(at 22.86 -6.35 0)
				(effects
					(font
						(size 1.27 1.27)
						(thickness 0.15)
					)
					(justify left bottom)
				)
			)
			(property "Manufacturer" "Diotec Semiconductor"
				(at 22.86 -16.51 0)
				(effects
					(font
						(size 1.27 1.27)
						(thickness 0.15)
					)
					(justify left bottom)
					(hide yes)
				)
			)
			(property "Author" "Antmicro"
				(at 22.86 -19.05 0)
				(effects
					(font
						(size 1.27 1.27)
						(thickness 0.15)
					)
					(justify left bottom)
					(hide yes)
				)
			)
			(property "License" "Apache-2.0"
				(at 22.86 -21.59 0)
				(effects
					(font
						(size 1.27 1.27)
						(thickness 0.15)
					)
					(justify left bottom)
					(hide yes)
				)
			)
			(property "ki_keywords" "SMT, SEMICONDUCTOR, DIODE, SCHOTTKY"
				(at 0 0 0)
				(effects
					(font
						(size 1.27 1.27)
					)
					(hide yes)
				)
			)
			(symbol "BAT54C_0_1"
				(polyline
					(pts
						(xy 5.08 0) (xy 2.667 0)
					)
					(stroke
						(width 0.254)
						(type default)
					)
					(fill
						(type none)
					)
				)
				(polyline
					(pts
						(xy 5.08 -5.08) (xy 2.667 -5.08)
					)
					(stroke
						(width 0.254)
						(type default)
					)
					(fill
						(type none)
					)
				)
				(circle
					(center 6.35 -2.54)
					(radius 4.572)
					(stroke
						(width 0)
						(type default)
					)
					(fill
						(type background)
					)
				)
				(polyline
					(pts
						(xy 10.795 -2.54) (xy 8.89 -2.54)
					)
					(stroke
						(width 0.254)
						(type default)
					)
					(fill
						(type none)
					)
				)
			)
			(symbol "BAT54C_1_1"
				(polyline
					(pts
						(xy 5.08 1.27) (xy 5.08 -1.27) (xy 7.62 0) (xy 5.08 1.27)
					)
					(stroke
						(width 0.254)
						(type default)
					)
					(fill
						(type outline)
					)
				)
				(polyline
					(pts
						(xy 5.08 -3.81) (xy 5.08 -6.35) (xy 7.62 -5.08) (xy 5.08 -3.81)
					)
					(stroke
						(width 0.254)
						(type default)
					)
					(fill
						(type outline)
					)
				)
				(polyline
					(pts
						(xy 7.62 0.635) (xy 7.62 -1.27)
					)
					(stroke
						(width 0.254)
						(type default)
					)
					(fill
						(type none)
					)
				)
				(polyline
					(pts
						(xy 7.62 0.635) (xy 7.62 1.27) (xy 8.255 1.27) (xy 8.255 0.635)
					)
					(stroke
						(width 0.254)
						(type default)
					)
					(fill
						(type none)
					)
				)
				(polyline
					(pts
						(xy 7.62 0) (xy 8.89 0) (xy 8.89 -5.08) (xy 7.62 -5.08)
					)
					(stroke
						(width 0.254)
						(type default)
					)
					(fill
						(type none)
					)
				)
				(polyline
					(pts
						(xy 7.62 -0.635) (xy 7.62 -1.27) (xy 6.985 -1.27) (xy 6.985 -0.635)
					)
					(stroke
						(width 0.254)
						(type default)
					)
					(fill
						(type none)
					)
				)
				(polyline
					(pts
						(xy 7.62 -3.81) (xy 7.62 -6.35)
					)
					(stroke
						(width 0.254)
						(type default)
					)
					(fill
						(type none)
					)
				)
				(polyline
					(pts
						(xy 7.62 -4.445) (xy 7.62 -3.81) (xy 8.255 -3.81) (xy 8.255 -4.445)
					)
					(stroke
						(width 0.254)
						(type default)
					)
					(fill
						(type none)
					)
				)
				(polyline
					(pts
						(xy 7.62 -5.715) (xy 7.62 -6.35) (xy 6.985 -6.35) (xy 6.985 -5.715)
					)
					(stroke
						(width 0.254)
						(type default)
					)
					(fill
						(type none)
					)
				)
				(pin passive line
					(at 0 0 0)
					(length 2.54)
					(name "1"
						(effects
							(font
								(size 1.27 1.27)
							)
						)
					)
					(number "1"
						(effects
							(font
								(size 1.27 1.27)
							)
						)
					)
				)
				(pin passive line
					(at 0 -5.08 0)
					(length 2.54)
					(name "2"
						(effects
							(font
								(size 1.27 1.27)
							)
						)
					)
					(number "2"
						(effects
							(font
								(size 1.27 1.27)
							)
						)
					)
				)
				(pin passive line
					(at 12.7 -2.54 180)
					(length 2.54)
					(name "3"
						(effects
							(font
								(size 1.27 1.27)
							)
						)
					)
					(number "3"
						(effects
							(font
								(size 1.27 1.27)
							)
						)
					)
				)
			)
		)
	(symbol "antmicroEdgeConnectors:PCB-Edge_Samtec_HSEC8_2x20_HSEC8-120-01-S-D-EM2"
			(exclude_from_sim no)
			(in_bom no)
			(on_board yes)
			(property "Reference" "J"
				(at 25.4 -2.54 0)
				(effects
					(font
						(size 1.27 1.27)
						(thickness 0.15)
					)
					(justify left bottom)
				)
			)
			(property "Value" "PCB-Edge_Samtec_HSEC8_2x20_HSEC8-120-01-S-D-EM2"
				(at 25.4 -5.08 0)
				(effects
					(font
						(size 1.27 1.27)
						(thickness 0.15)
					)
					(justify left bottom)
				)
			)
			(property "Footprint" "antmicro-footprints:PCB-Edge_Samtec_HSEC8_2x20_HSEC8-120-01-S-D-EM2"
				(at 25.4 -7.62 0)
				(effects
					(font
						(size 1.27 1.27)
						(thickness 0.15)
					)
					(justify left bottom)
					(hide yes)
				)
			)
			(property "Datasheet" "https://suddendocs.samtec.com/prints/hsec8-1xxx-xx-xx-dv-x-xx-footprint.pdf"
				(at 25.4 -10.16 0)
				(effects
					(font
						(size 1.27 1.27)
						(thickness 0.15)
					)
					(justify left bottom)
					(hide yes)
				)
			)
			(property "Description" "0.80 mm High-Speed Edge Card Connector"
				(at 0 0 0)
				(effects
					(font
						(size 1.27 1.27)
					)
					(hide yes)
				)
			)
			(property "Author" "Antmicro"
				(at 25.4 -12.7 0)
				(effects
					(font
						(size 1.27 1.27)
						(thickness 0.15)
					)
					(justify left bottom)
					(hide yes)
				)
			)
			(property "License" "Apache-2.0"
				(at 25.4 -15.24 0)
				(effects
					(font
						(size 1.27 1.27)
						(thickness 0.15)
					)
					(justify left bottom)
					(hide yes)
				)
			)
			(property "Public" "False"
				(at 25.4 -17.78 0)
				(effects
					(font
						(size 1.27 1.27)
					)
					(justify left bottom)
					(hide yes)
				)
			)
			(property "ki_keywords" "HORIZONTAL, EDGE, CONNECTOR"
				(at 0 0 0)
				(effects
					(font
						(size 1.27 1.27)
					)
					(hide yes)
				)
			)
			(symbol "PCB-Edge_Samtec_HSEC8_2x20_HSEC8-120-01-S-D-EM2_1_1"
				(rectangle
					(start 2.54 2.54)
					(end 8.89 -50.8)
					(stroke
						(width 0.254)
						(type default)
					)
					(fill
						(type background)
					)
				)
				(rectangle
					(start 5.08 1.27)
					(end 6.35 -49.53)
					(stroke
						(width 0.254)
						(type default)
					)
					(fill
						(type background)
					)
				)
				(pin passive line
					(at 0 0 0)
					(length 2.54)
					(name "~"
						(effects
							(font
								(size 1.27 1.27)
							)
						)
					)
					(number "1"
						(effects
							(font
								(size 1.27 1.27)
							)
						)
					)
				)
				(pin passive line
					(at 0 -2.54 0)
					(length 2.54)
					(name "~"
						(effects
							(font
								(size 1.27 1.27)
							)
						)
					)
					(number "3"
						(effects
							(font
								(size 1.27 1.27)
							)
						)
					)
				)
				(pin passive line
					(at 0 -5.08 0)
					(length 2.54)
					(name "~"
						(effects
							(font
								(size 1.27 1.27)
							)
						)
					)
					(number "5"
						(effects
							(font
								(size 1.27 1.27)
							)
						)
					)
				)
				(pin passive line
					(at 0 -7.62 0)
					(length 2.54)
					(name "~"
						(effects
							(font
								(size 1.27 1.27)
							)
						)
					)
					(number "7"
						(effects
							(font
								(size 1.27 1.27)
							)
						)
					)
				)
				(pin passive line
					(at 0 -10.16 0)
					(length 2.54)
					(name "~"
						(effects
							(font
								(size 1.27 1.27)
							)
						)
					)
					(number "9"
						(effects
							(font
								(size 1.27 1.27)
							)
						)
					)
				)
				(pin passive line
					(at 0 -12.7 0)
					(length 2.54)
					(name "~"
						(effects
							(font
								(size 1.27 1.27)
							)
						)
					)
					(number "11"
						(effects
							(font
								(size 1.27 1.27)
							)
						)
					)
				)
				(pin passive line
					(at 0 -15.24 0)
					(length 2.54)
					(name "~"
						(effects
							(font
								(size 1.27 1.27)
							)
						)
					)
					(number "13"
						(effects
							(font
								(size 1.27 1.27)
							)
						)
					)
				)
				(pin passive line
					(at 0 -17.78 0)
					(length 2.54)
					(name "~"
						(effects
							(font
								(size 1.27 1.27)
							)
						)
					)
					(number "15"
						(effects
							(font
								(size 1.27 1.27)
							)
						)
					)
				)
				(pin passive line
					(at 0 -20.32 0)
					(length 2.54)
					(name "~"
						(effects
							(font
								(size 1.27 1.27)
							)
						)
					)
					(number "17"
						(effects
							(font
								(size 1.27 1.27)
							)
						)
					)
				)
				(pin passive line
					(at 0 -22.86 0)
					(length 2.54)
					(name "~"
						(effects
							(font
								(size 1.27 1.27)
							)
						)
					)
					(number "19"
						(effects
							(font
								(size 1.27 1.27)
							)
						)
					)
				)
				(pin passive line
					(at 0 -25.4 0)
					(length 2.54)
					(name "~"
						(effects
							(font
								(size 1.27 1.27)
							)
						)
					)
					(number "21"
						(effects
							(font
								(size 1.27 1.27)
							)
						)
					)
				)
				(pin passive line
					(at 0 -27.94 0)
					(length 2.54)
					(name "~"
						(effects
							(font
								(size 1.27 1.27)
							)
						)
					)
					(number "23"
						(effects
							(font
								(size 1.27 1.27)
							)
						)
					)
				)
				(pin passive line
					(at 0 -30.48 0)
					(length 2.54)
					(name "~"
						(effects
							(font
								(size 1.27 1.27)
							)
						)
					)
					(number "25"
						(effects
							(font
								(size 1.27 1.27)
							)
						)
					)
				)
				(pin passive line
					(at 0 -33.02 0)
					(length 2.54)
					(name "~"
						(effects
							(font
								(size 1.27 1.27)
							)
						)
					)
					(number "27"
						(effects
							(font
								(size 1.27 1.27)
							)
						)
					)
				)
				(pin passive line
					(at 0 -35.56 0)
					(length 2.54)
					(name "~"
						(effects
							(font
								(size 1.27 1.27)
							)
						)
					)
					(number "29"
						(effects
							(font
								(size 1.27 1.27)
							)
						)
					)
				)
				(pin passive line
					(at 0 -38.1 0)
					(length 2.54)
					(name "~"
						(effects
							(font
								(size 1.27 1.27)
							)
						)
					)
					(number "31"
						(effects
							(font
								(size 1.27 1.27)
							)
						)
					)
				)
				(pin passive line
					(at 0 -40.64 0)
					(length 2.54)
					(name "~"
						(effects
							(font
								(size 1.27 1.27)
							)
						)
					)
					(number "33"
						(effects
							(font
								(size 1.27 1.27)
							)
						)
					)
				)
				(pin passive line
					(at 0 -43.18 0)
					(length 2.54)
					(name "~"
						(effects
							(font
								(size 1.27 1.27)
							)
						)
					)
					(number "35"
						(effects
							(font
								(size 1.27 1.27)
							)
						)
					)
				)
				(pin passive line
					(at 0 -45.72 0)
					(length 2.54)
					(name "~"
						(effects
							(font
								(size 1.27 1.27)
							)
						)
					)
					(number "37"
						(effects
							(font
								(size 1.27 1.27)
							)
						)
					)
				)
				(pin passive line
					(at 0 -48.26 0)
					(length 2.54)
					(name "~"
						(effects
							(font
								(size 1.27 1.27)
							)
						)
					)
					(number "39"
						(effects
							(font
								(size 1.27 1.27)
							)
						)
					)
				)
				(pin passive line
					(at 11.43 0 180)
					(length 2.54)
					(name "~"
						(effects
							(font
								(size 1.27 1.27)
							)
						)
					)
					(number "2"
						(effects
							(font
								(size 1.27 1.27)
							)
						)
					)
				)
				(pin passive line
					(at 11.43 -2.54 180)
					(length 2.54)
					(name "~"
						(effects
							(font
								(size 1.27 1.27)
							)
						)
					)
					(number "4"
						(effects
							(font
								(size 1.27 1.27)
							)
						)
					)
				)
				(pin passive line
					(at 11.43 -5.08 180)
					(length 2.54)
					(name "~"
						(effects
							(font
								(size 1.27 1.27)
							)
						)
					)
					(number "6"
						(effects
							(font
								(size 1.27 1.27)
							)
						)
					)
				)
				(pin passive line
					(at 11.43 -7.62 180)
					(length 2.54)
					(name "~"
						(effects
							(font
								(size 1.27 1.27)
							)
						)
					)
					(number "8"
						(effects
							(font
								(size 1.27 1.27)
							)
						)
					)
				)
				(pin passive line
					(at 11.43 -10.16 180)
					(length 2.54)
					(name "~"
						(effects
							(font
								(size 1.27 1.27)
							)
						)
					)
					(number "10"
						(effects
							(font
								(size 1.27 1.27)
							)
						)
					)
				)
				(pin passive line
					(at 11.43 -12.7 180)
					(length 2.54)
					(name "~"
						(effects
							(font
								(size 1.27 1.27)
							)
						)
					)
					(number "12"
						(effects
							(font
								(size 1.27 1.27)
							)
						)
					)
				)
				(pin passive line
					(at 11.43 -15.24 180)
					(length 2.54)
					(name "~"
						(effects
							(font
								(size 1.27 1.27)
							)
						)
					)
					(number "14"
						(effects
							(font
								(size 1.27 1.27)
							)
						)
					)
				)
				(pin passive line
					(at 11.43 -17.78 180)
					(length 2.54)
					(name "~"
						(effects
							(font
								(size 1.27 1.27)
							)
						)
					)
					(number "16"
						(effects
							(font
								(size 1.27 1.27)
							)
						)
					)
				)
				(pin passive line
					(at 11.43 -20.32 180)
					(length 2.54)
					(name "~"
						(effects
							(font
								(size 1.27 1.27)
							)
						)
					)
					(number "18"
						(effects
							(font
								(size 1.27 1.27)
							)
						)
					)
				)
				(pin passive line
					(at 11.43 -22.86 180)
					(length 2.54)
					(name "~"
						(effects
							(font
								(size 1.27 1.27)
							)
						)
					)
					(number "20"
						(effects
							(font
								(size 1.27 1.27)
							)
						)
					)
				)
				(pin passive line
					(at 11.43 -25.4 180)
					(length 2.54)
					(name "~"
						(effects
							(font
								(size 1.27 1.27)
							)
						)
					)
					(number "22"
						(effects
							(font
								(size 1.27 1.27)
							)
						)
					)
				)
				(pin passive line
					(at 11.43 -27.94 180)
					(length 2.54)
					(name "~"
						(effects
							(font
								(size 1.27 1.27)
							)
						)
					)
					(number "24"
						(effects
							(font
								(size 1.27 1.27)
							)
						)
					)
				)
				(pin passive line
					(at 11.43 -30.48 180)
					(length 2.54)
					(name "~"
						(effects
							(font
								(size 1.27 1.27)
							)
						)
					)
					(number "26"
						(effects
							(font
								(size 1.27 1.27)
							)
						)
					)
				)
				(pin passive line
					(at 11.43 -33.02 180)
					(length 2.54)
					(name "~"
						(effects
							(font
								(size 1.27 1.27)
							)
						)
					)
					(number "28"
						(effects
							(font
								(size 1.27 1.27)
							)
						)
					)
				)
				(pin passive line
					(at 11.43 -35.56 180)
					(length 2.54)
					(name "~"
						(effects
							(font
								(size 1.27 1.27)
							)
						)
					)
					(number "30"
						(effects
							(font
								(size 1.27 1.27)
							)
						)
					)
				)
				(pin passive line
					(at 11.43 -38.1 180)
					(length 2.54)
					(name "~"
						(effects
							(font
								(size 1.27 1.27)
							)
						)
					)
					(number "32"
						(effects
							(font
								(size 1.27 1.27)
							)
						)
					)
				)
				(pin passive line
					(at 11.43 -40.64 180)
					(length 2.54)
					(name "~"
						(effects
							(font
								(size 1.27 1.27)
							)
						)
					)
					(number "34"
						(effects
							(font
								(size 1.27 1.27)
							)
						)
					)
				)
				(pin passive line
					(at 11.43 -43.18 180)
					(length 2.54)
					(name "~"
						(effects
							(font
								(size 1.27 1.27)
							)
						)
					)
					(number "36"
						(effects
							(font
								(size 1.27 1.27)
							)
						)
					)
				)
				(pin passive line
					(at 11.43 -45.72 180)
					(length 2.54)
					(name "~"
						(effects
							(font
								(size 1.27 1.27)
							)
						)
					)
					(number "38"
						(effects
							(font
								(size 1.27 1.27)
							)
						)
					)
				)
				(pin passive line
					(at 11.43 -48.26 180)
					(length 2.54)
					(name "~"
						(effects
							(font
								(size 1.27 1.27)
							)
						)
					)
					(number "40"
						(effects
							(font
								(size 1.27 1.27)
							)
						)
					)
				)
			)
		)
	(symbol "antmicroFixedInductors:L_1u8_14A_Coilcraft-XAL6030"
			(pin_numbers
				(hide yes)
			)
			(pin_names
				(hide yes)
			)
			(exclude_from_sim no)
			(in_bom yes)
			(on_board yes)
			(property "Reference" "L"
				(at 15.24 -5.08 0)
				(effects
					(font
						(size 1.27 1.27)
						(thickness 0.15)
					)
					(justify left bottom)
				)
			)
			(property "Value" "L_1u8_14A_Coilcraft-XAL6030"
				(at 15.24 -10.16 0)
				(effects
					(font
						(size 1.27 1.27)
						(thickness 0.15)
					)
					(justify left bottom)
					(hide yes)
				)
			)
			(property "Footprint" "antmicro-footprints:L_Coilcraft-XAL6030"
				(at 15.24 -12.7 0)
				(effects
					(font
						(size 1.27 1.27)
						(thickness 0.15)
					)
					(justify left bottom)
					(hide yes)
				)
			)
			(property "Datasheet" "https://www.mouser.com/datasheet/2/597/xal60xx-270658.pdf"
				(at 15.24 -15.24 0)
				(effects
					(font
						(size 1.27 1.27)
						(thickness 0.15)
					)
					(justify left bottom)
					(hide yes)
				)
			)
			(property "Description" "Power Inductor (SMT), 1.8 µH, 14 A, Shielded, 18.2 A, XAL6030"
				(at 0 0 0)
				(effects
					(font
						(size 1.27 1.27)
					)
					(hide yes)
				)
			)
			(property "Manufacturer" "Coilcraft"
				(at 15.24 -17.78 0)
				(effects
					(font
						(size 1.27 1.27)
						(thickness 0.15)
					)
					(justify left bottom)
					(hide yes)
				)
			)
			(property "MPN" "XAL6030-182MEC"
				(at 15.24 -20.32 0)
				(effects
					(font
						(size 1.27 1.27)
						(thickness 0.15)
					)
					(justify left bottom)
					(hide yes)
				)
			)
			(property "ISat" "18.2 A"
				(at 15.24 -22.86 0)
				(effects
					(font
						(size 1.27 1.27)
						(thickness 0.15)
					)
					(justify left bottom)
					(hide yes)
				)
			)
			(property "IMax" "14 A"
				(at 15.24 -25.4 0)
				(effects
					(font
						(size 1.27 1.27)
						(thickness 0.15)
					)
					(justify left bottom)
					(hide yes)
				)
			)
			(property "Size" "6.36x6.56"
				(at 15.24 -27.94 0)
				(effects
					(font
						(size 1.27 1.27)
						(thickness 0.15)
					)
					(justify left bottom)
					(hide yes)
				)
			)
			(property "Val" "1.8u/14A"
				(at 15.24 -7.62 0)
				(effects
					(font
						(size 1.27 1.27)
						(thickness 0.15)
					)
					(justify left bottom)
				)
			)
			(property "Author" "Antmicro"
				(at 15.24 -30.48 0)
				(effects
					(font
						(size 1.27 1.27)
						(thickness 0.15)
					)
					(justify left bottom)
					(hide yes)
				)
			)
			(property "License" "Apache-2.0"
				(at 15.24 -33.02 0)
				(effects
					(font
						(size 1.27 1.27)
						(thickness 0.15)
					)
					(justify left bottom)
					(hide yes)
				)
			)
			(property "Public" "False"
				(at 13.97 -30.48 0)
				(effects
					(font
						(size 1.27 1.27)
					)
					(justify left bottom)
					(hide yes)
				)
			)
			(property "ki_keywords" "SMT, INDUCTOR, PASSIVE"
				(at 0 0 0)
				(effects
					(font
						(size 1.27 1.27)
					)
					(hide yes)
				)
			)
			(symbol "L_1u8_14A_Coilcraft-XAL6030_0_1"
				(arc
					(start 0.508 0)
					(mid 1.016 0.5058)
					(end 1.524 0)
					(stroke
						(width 0)
						(type default)
					)
					(fill
						(type none)
					)
				)
				(arc
					(start 1.524 0)
					(mid 2.032 0.5058)
					(end 2.54 0)
					(stroke
						(width 0)
						(type default)
					)
					(fill
						(type none)
					)
				)
				(arc
					(start 2.54 0)
					(mid 3.048 0.5058)
					(end 3.556 0)
					(stroke
						(width 0)
						(type default)
					)
					(fill
						(type none)
					)
				)
				(arc
					(start 3.556 0)
					(mid 4.064 0.5058)
					(end 4.572 0)
					(stroke
						(width 0)
						(type default)
					)
					(fill
						(type none)
					)
				)
			)
			(symbol "L_1u8_14A_Coilcraft-XAL6030_1_1"
				(pin passive line
					(at 0 0 0)
					(length 0.508)
					(name "~"
						(effects
							(font
								(size 1.27 1.27)
							)
						)
					)
					(number "1"
						(effects
							(font
								(size 1.27 1.27)
							)
						)
					)
				)
				(pin passive line
					(at 5.08 0 180)
					(length 0.508)
					(name "~"
						(effects
							(font
								(size 1.27 1.27)
							)
						)
					)
					(number "2"
						(effects
							(font
								(size 1.27 1.27)
							)
						)
					)
				)
			)
		)
	(symbol "antmicroFixedInductors:L_1u8_6.8A_WE-MAPI-4020"
			(pin_numbers
				(hide yes)
			)
			(pin_names
				(hide yes)
			)
			(exclude_from_sim no)
			(in_bom yes)
			(on_board yes)
			(property "Reference" "L"
				(at 13.97 0 0)
				(effects
					(font
						(size 1.27 1.27)
						(thickness 0.15)
					)
					(justify left bottom)
				)
			)
			(property "Value" "L_1u8_6.8A_WE-MAPI-4020"
				(at 13.97 -2.54 0)
				(effects
					(font
						(size 1.27 1.27)
						(thickness 0.15)
					)
					(justify left bottom)
					(hide yes)
				)
			)
			(property "Footprint" "antmicro-footprints:L_WE-MAPI-4020"
				(at 13.97 -7.62 0)
				(effects
					(font
						(size 1.27 1.27)
						(thickness 0.15)
					)
					(justify left bottom)
					(hide yes)
				)
			)
			(property "Datasheet" "https://www.we-online.com/components/products/datasheet/74438356018.pdf"
				(at 13.97 -10.16 0)
				(effects
					(font
						(size 1.27 1.27)
						(thickness 0.15)
					)
					(justify left bottom)
					(hide yes)
				)
			)
			(property "Description" "Power Inductors - SMD WE-MAPI 1.8uH 4.6A DCR=30mOhms AEC-Q200"
				(at 0 0 0)
				(effects
					(font
						(size 1.27 1.27)
					)
					(hide yes)
				)
			)
			(property "Val" "1u8/6.8A"
				(at 13.97 -5.08 0)
				(effects
					(font
						(size 1.27 1.27)
						(thickness 0.15)
					)
					(justify left bottom)
				)
			)
			(property "Manufacturer" "Würth Elektronik"
				(at 13.97 -12.7 0)
				(effects
					(font
						(size 1.27 1.27)
						(thickness 0.15)
					)
					(justify left bottom)
					(hide yes)
				)
			)
			(property "MPN" "74438356018"
				(at 13.97 -15.24 0)
				(effects
					(font
						(size 1.27 1.27)
						(thickness 0.15)
					)
					(justify left bottom)
					(hide yes)
				)
			)
			(property "ISat" "6.5 A"
				(at 13.97 -16.51 0)
				(effects
					(font
						(size 1.27 1.27)
					)
					(justify left)
					(hide yes)
				)
			)
			(property "IMax" "6.8 A"
				(at 13.97 -20.32 0)
				(effects
					(font
						(size 1.27 1.27)
						(thickness 0.15)
					)
					(justify left bottom)
					(hide yes)
				)
			)
			(property "Size" "4.1x4.1mm"
				(at 13.97 -22.86 0)
				(effects
					(font
						(size 1.27 1.27)
						(thickness 0.15)
					)
					(justify left bottom)
					(hide yes)
				)
			)
			(property "Author" "Antmicro"
				(at 13.97 -25.4 0)
				(effects
					(font
						(size 1.27 1.27)
						(thickness 0.15)
					)
					(justify left bottom)
					(hide yes)
				)
			)
			(property "License" "Apache-2.0"
				(at 13.97 -27.94 0)
				(effects
					(font
						(size 1.27 1.27)
						(thickness 0.15)
					)
					(justify left bottom)
					(hide yes)
				)
			)
			(property "Public" "False"
				(at 13.97 -30.48 0)
				(effects
					(font
						(size 1.27 1.27)
					)
					(justify left bottom)
					(hide yes)
				)
			)
			(property "ki_keywords" "SMT, INDUCTOR, PASSIVE"
				(at 0 0 0)
				(effects
					(font
						(size 1.27 1.27)
					)
					(hide yes)
				)
			)
			(symbol "L_1u8_6.8A_WE-MAPI-4020_0_1"
				(arc
					(start 0.508 0)
					(mid 1.016 0.5058)
					(end 1.524 0)
					(stroke
						(width 0)
						(type default)
					)
					(fill
						(type none)
					)
				)
				(arc
					(start 1.524 0)
					(mid 2.032 0.5058)
					(end 2.54 0)
					(stroke
						(width 0)
						(type default)
					)
					(fill
						(type none)
					)
				)
				(arc
					(start 2.54 0)
					(mid 3.048 0.5058)
					(end 3.556 0)
					(stroke
						(width 0)
						(type default)
					)
					(fill
						(type none)
					)
				)
				(arc
					(start 3.556 0)
					(mid 4.064 0.5058)
					(end 4.572 0)
					(stroke
						(width 0)
						(type default)
					)
					(fill
						(type none)
					)
				)
			)
			(symbol "L_1u8_6.8A_WE-MAPI-4020_1_1"
				(pin passive line
					(at 0 0 0)
					(length 0.508)
					(name "~"
						(effects
							(font
								(size 1.27 1.27)
							)
						)
					)
					(number "1"
						(effects
							(font
								(size 1.27 1.27)
							)
						)
					)
				)
				(pin passive line
					(at 5.08 0 180)
					(length 0.508)
					(name "~"
						(effects
							(font
								(size 1.27 1.27)
							)
						)
					)
					(number "2"
						(effects
							(font
								(size 1.27 1.27)
							)
						)
					)
				)
			)
		)
	(symbol "antmicroFuses:F_12A_1206"
			(pin_numbers
				(hide yes)
			)
			(pin_names
				(hide yes)
			)
			(exclude_from_sim no)
			(in_bom yes)
			(on_board yes)
			(property "Reference" "F"
				(at 21.59 -5.08 0)
				(effects
					(font
						(size 1.27 1.27)
						(thickness 0.15)
					)
					(justify left bottom)
				)
			)
			(property "Value" "F_12A_1206"
				(at 21.59 -7.62 0)
				(effects
					(font
						(size 1.27 1.27)
						(thickness 0.15)
					)
					(justify left bottom)
					(hide yes)
				)
			)
			(property "Footprint" "antmicro-footprints:F_1206_3216Metric"
				(at 21.59 -10.16 0)
				(effects
					(font
						(size 1.27 1.27)
						(thickness 0.15)
					)
					(justify left bottom)
					(hide yes)
				)
			)
			(property "Datasheet" "https://us.schurter.com/pdf/english/typ_UST_1206.pdf"
				(at 21.59 -12.7 0)
				(effects
					(font
						(size 1.27 1.27)
						(thickness 0.15)
					)
					(justify left bottom)
					(hide yes)
				)
			)
			(property "Description" "Fuse, Surface Mount, 12 A, Slow Blow, 32 VAC, 63 VDC, 1206, UST 1206"
				(at 0 0 0)
				(effects
					(font
						(size 1.27 1.27)
					)
					(hide yes)
				)
			)
			(property "Manufacturer" "Schurter"
				(at 21.59 -15.24 0)
				(effects
					(font
						(size 1.27 1.27)
						(thickness 0.15)
					)
					(justify left bottom)
					(hide yes)
				)
			)
			(property "MPN" "3413.0329.22"
				(at 21.59 -17.78 0)
				(effects
					(font
						(size 1.27 1.27)
						(thickness 0.15)
					)
					(justify left bottom)
				)
			)
			(property "Author" "Antmicro"
				(at 21.59 -20.32 0)
				(effects
					(font
						(size 1.27 1.27)
						(thickness 0.15)
					)
					(justify left bottom)
					(hide yes)
				)
			)
			(property "License" "Apache-2.0"
				(at 21.59 -22.86 0)
				(effects
					(font
						(size 1.27 1.27)
						(thickness 0.15)
					)
					(justify left bottom)
					(hide yes)
				)
			)
			(property "ki_keywords" "FUSE, PASSIVE"
				(at 0 0 0)
				(effects
					(font
						(size 1.27 1.27)
					)
					(hide yes)
				)
			)
			(symbol "F_12A_1206_0_1"
				(rectangle
					(start 1.27 0.508)
					(end 3.81 -0.508)
					(stroke
						(width 0)
						(type default)
					)
					(fill
						(type none)
					)
				)
				(polyline
					(pts
						(xy 1.27 0) (xy 3.81 0)
					)
					(stroke
						(width 0)
						(type default)
					)
					(fill
						(type none)
					)
				)
			)
			(symbol "F_12A_1206_1_1"
				(pin passive line
					(at 0 0 0)
					(length 1.27)
					(name "~"
						(effects
							(font
								(size 1.27 1.27)
							)
						)
					)
					(number "1"
						(effects
							(font
								(size 1.27 1.27)
							)
						)
					)
				)
				(pin passive line
					(at 5.08 0 180)
					(length 1.27)
					(name "~"
						(effects
							(font
								(size 1.27 1.27)
							)
						)
					)
					(number "2"
						(effects
							(font
								(size 1.27 1.27)
							)
						)
					)
				)
			)
		)
	(symbol "antmicroFuses:PTC_4.5A_1206"
			(pin_numbers
				(hide yes)
			)
			(pin_names
				(hide yes)
			)
			(exclude_from_sim no)
			(in_bom yes)
			(on_board yes)
			(property "Reference" "F"
				(at 13.97 0 0)
				(effects
					(font
						(size 1.27 1.27)
						(thickness 0.15)
					)
					(justify left bottom)
				)
			)
			(property "Value" "PTC_4.5A_1206"
				(at 13.97 -2.54 0)
				(effects
					(font
						(size 1.27 1.27)
						(thickness 0.15)
					)
					(justify left bottom)
					(hide yes)
				)
			)
			(property "Footprint" "antmicro-footprints:F_1206_3216Metric"
				(at 13.97 -5.08 0)
				(effects
					(font
						(size 1.27 1.27)
						(thickness 0.15)
					)
					(justify left bottom)
					(hide yes)
				)
			)
			(property "Datasheet" "http://www.farnell.com/datasheets/2282556.pdf"
				(at 13.97 -7.62 0)
				(effects
					(font
						(size 1.27 1.27)
						(thickness 0.15)
					)
					(justify left bottom)
					(hide yes)
				)
			)
			(property "Description" "Resettable Fuse, PPTC, 1206 (3216 Metric), PolySwitch Low Rho Series, 6 VDC, 4.5 A, 9 A, 2 s"
				(at 0 0 0)
				(effects
					(font
						(size 1.27 1.27)
					)
					(hide yes)
				)
			)
			(property "MPN" "1206L450SLWR"
				(at 13.97 -10.16 0)
				(effects
					(font
						(size 1.27 1.27)
						(thickness 0.15)
					)
					(justify left bottom)
				)
			)
			(property "Manufacturer" "Littelfuse"
				(at 13.97 -12.7 0)
				(effects
					(font
						(size 1.27 1.27)
						(thickness 0.15)
					)
					(justify left bottom)
					(hide yes)
				)
			)
			(property "Author" "Antmicro"
				(at 13.97 -15.24 0)
				(effects
					(font
						(size 1.27 1.27)
						(thickness 0.15)
					)
					(justify left bottom)
					(hide yes)
				)
			)
			(property "License" "Apache-2.0"
				(at 13.97 -17.78 0)
				(effects
					(font
						(size 1.27 1.27)
						(thickness 0.15)
					)
					(justify left bottom)
					(hide yes)
				)
			)
			(property "ki_keywords" "FUSE, PASSIVE"
				(at 0 0 0)
				(effects
					(font
						(size 1.27 1.27)
					)
					(hide yes)
				)
			)
			(symbol "PTC_4.5A_1206_0_1"
				(rectangle
					(start 1.27 0.508)
					(end 3.81 -0.508)
					(stroke
						(width 0)
						(type default)
					)
					(fill
						(type none)
					)
				)
				(polyline
					(pts
						(xy 1.27 0) (xy 3.81 0)
					)
					(stroke
						(width 0)
						(type default)
					)
					(fill
						(type none)
					)
				)
			)
			(symbol "PTC_4.5A_1206_1_1"
				(pin passive line
					(at 0 0 0)
					(length 1.27)
					(name "~"
						(effects
							(font
								(size 1.27 1.27)
							)
						)
					)
					(number "1"
						(effects
							(font
								(size 1.27 1.27)
							)
						)
					)
				)
				(pin passive line
					(at 5.08 0 180)
					(length 1.27)
					(name "~"
						(effects
							(font
								(size 1.27 1.27)
							)
						)
					)
					(number "2"
						(effects
							(font
								(size 1.27 1.27)
							)
						)
					)
				)
			)
		)
	(symbol "antmicroGenericPinHeaders:PinHeader_1x3_P2.54mm_Drill1.1mm"
			(exclude_from_sim no)
			(in_bom yes)
			(on_board yes)
			(property "Reference" "J"
				(at 20.32 -5.08 0)
				(effects
					(font
						(size 1.27 1.27)
						(thickness 0.15)
					)
					(justify left bottom)
				)
			)
			(property "Value" "PinHeader_1x3_P2.54mm_Drill1.1mm"
				(at 20.32 -10.16 0)
				(effects
					(font
						(size 1.27 1.27)
						(thickness 0.15)
					)
					(justify left bottom)
					(hide yes)
				)
			)
			(property "Footprint" "antmicro-footprints:PinHeader_1x3_P2.54mm_Drill1.1mm"
				(at 20.32 -12.7 0)
				(effects
					(font
						(size 1.27 1.27)
						(thickness 0.15)
					)
					(justify left bottom)
					(hide yes)
				)
			)
			(property "Datasheet" "https://katalog.we-online.de/em/datasheet/6130xx11121.pdf"
				(at 20.32 -15.24 0)
				(effects
					(font
						(size 1.27 1.27)
						(thickness 0.15)
					)
					(justify left bottom)
					(hide yes)
				)
			)
			(property "Description" "Pin Header, Vertical, Board-to-Board, 2.54 mm, 1 Rows, 3 Contacts, Through Hole Straight, WR-PHD"
				(at 0 0 0)
				(effects
					(font
						(size 1.27 1.27)
					)
					(hide yes)
				)
			)
			(property "MPN" "61300311121"
				(at 20.32 -7.62 0)
				(effects
					(font
						(size 1.27 1.27)
						(thickness 0.15)
					)
					(justify left bottom)
				)
			)
			(property "Manufacturer" "Würth Elektronik"
				(at 20.32 -17.78 0)
				(effects
					(font
						(size 1.27 1.27)
						(thickness 0.15)
					)
					(justify left bottom)
					(hide yes)
				)
			)
			(property "Author" "Antmicro"
				(at 20.32 -22.86 0)
				(effects
					(font
						(size 1.27 1.27)
						(thickness 0.15)
					)
					(justify left bottom)
					(hide yes)
				)
			)
			(property "License" "Apache-2.0"
				(at 20.32 -25.4 0)
				(effects
					(font
						(size 1.27 1.27)
						(thickness 0.15)
					)
					(justify left bottom)
					(hide yes)
				)
			)
			(property "ki_keywords" "VERTICAL, THT, HEADER, CONNECTOR, MALE"
				(at 0 0 0)
				(effects
					(font
						(size 1.27 1.27)
					)
					(hide yes)
				)
			)
			(symbol "PinHeader_1x3_P2.54mm_Drill1.1mm_1_1"
				(rectangle
					(start 4.191 -0.254)
					(end 3.683 0.254)
					(stroke
						(width 0.254)
						(type default)
					)
					(fill
						(type none)
					)
				)
				(rectangle
					(start 4.191 -2.794)
					(end 3.683 -2.286)
					(stroke
						(width 0.254)
						(type default)
					)
					(fill
						(type none)
					)
				)
				(rectangle
					(start 4.191 -5.334)
					(end 3.683 -4.826)
					(stroke
						(width 0.254)
						(type default)
					)
					(fill
						(type none)
					)
				)
				(rectangle
					(start 5.08 -6.35)
					(end 2.54 1.27)
					(stroke
						(width 0.254)
						(type default)
					)
					(fill
						(type background)
					)
				)
				(pin passive line
					(at 0 0 0)
					(length 2.54)
					(name "~"
						(effects
							(font
								(size 1.27 1.27)
							)
						)
					)
					(number "1"
						(effects
							(font
								(size 1.27 1.27)
							)
						)
					)
				)
				(pin passive line
					(at 0 -2.54 0)
					(length 2.54)
					(name "~"
						(effects
							(font
								(size 1.27 1.27)
							)
						)
					)
					(number "2"
						(effects
							(font
								(size 1.27 1.27)
							)
						)
					)
				)
				(pin passive line
					(at 0 -5.08 0)
					(length 2.54)
					(name "~"
						(effects
							(font
								(size 1.27 1.27)
							)
						)
					)
					(number "3"
						(effects
							(font
								(size 1.27 1.27)
							)
						)
					)
				)
			)
		)
	(symbol "antmicroInterfaceAnalogSwitchesMultiplexersDemultiplexers:74LVC1G157-Q100H_SOT457"
			(exclude_from_sim no)
			(in_bom yes)
			(on_board yes)
			(property "Reference" "U"
				(at 27.94 -5.08 0)
				(effects
					(font
						(size 1.27 1.27)
						(thickness 0.15)
					)
					(justify left bottom)
				)
			)
			(property "Value" "74LVC1G157-Q100H_SOT457"
				(at 27.94 -15.24 0)
				(effects
					(font
						(size 1.27 1.27)
						(thickness 0.15)
					)
					(justify left bottom)
					(hide yes)
				)
			)
			(property "Footprint" "antmicro-footprints:SC-74-6_1.5x2.9mm_P0.95mm"
				(at 27.94 -10.16 0)
				(effects
					(font
						(size 1.27 1.27)
						(thickness 0.15)
					)
					(justify left bottom)
					(hide yes)
				)
			)
			(property "Datasheet" "https://www.mouser.com/datasheet/2/916/74LVC1G157_Q100-1578792.pdf"
				(at 27.94 -12.7 0)
				(effects
					(font
						(size 1.27 1.27)
						(thickness 0.15)
					)
					(justify left bottom)
					(hide yes)
				)
			)
			(property "Description" "Single 2-input multiplexer"
				(at 0 0 0)
				(effects
					(font
						(size 1.27 1.27)
					)
					(hide yes)
				)
			)
			(property "MPN" "74LVC1G157-Q100H"
				(at 27.94 -7.62 0)
				(effects
					(font
						(size 1.27 1.27)
						(thickness 0.15)
					)
					(justify left bottom)
				)
			)
			(property "Manufacturer" "Nexperia"
				(at 27.94 -17.78 0)
				(effects
					(font
						(size 1.27 1.27)
						(thickness 0.15)
					)
					(justify left bottom)
					(hide yes)
				)
			)
			(property "Author" "Antmicro"
				(at 27.94 -20.32 0)
				(effects
					(font
						(size 1.27 1.27)
						(thickness 0.15)
					)
					(justify left bottom)
					(hide yes)
				)
			)
			(property "License" "Apache-2.0"
				(at 27.94 -22.86 0)
				(effects
					(font
						(size 1.27 1.27)
						(thickness 0.15)
					)
					(justify left bottom)
					(hide yes)
				)
			)
			(property "ki_keywords" "SMT, LOGIC, IC, DECODER, ENCODER, MUX"
				(at 0 0 0)
				(effects
					(font
						(size 1.27 1.27)
					)
					(hide yes)
				)
			)
			(symbol "74LVC1G157-Q100H_SOT457_1_1"
				(rectangle
					(start 2.54 1.27)
					(end 15.24 -8.89)
					(stroke
						(width 0.254)
						(type default)
					)
					(fill
						(type background)
					)
				)
				(polyline
					(pts
						(xy 5.715 -2.54) (xy 7.62 -2.54)
					)
					(stroke
						(width 0.254)
						(type default)
					)
					(fill
						(type none)
					)
				)
				(polyline
					(pts
						(xy 5.715 -5.08) (xy 7.62 -5.08)
					)
					(stroke
						(width 0.254)
						(type default)
					)
					(fill
						(type none)
					)
				)
				(polyline
					(pts
						(xy 5.715 -7.62) (xy 8.89 -7.62) (xy 8.89 -5.715)
					)
					(stroke
						(width 0.254)
						(type default)
					)
					(fill
						(type none)
					)
				)
				(polyline
					(pts
						(xy 7.62 -1.27) (xy 7.62 -6.35) (xy 10.16 -5.08) (xy 10.16 -2.54) (xy 7.62 -1.27)
					)
					(stroke
						(width 0.254)
						(type default)
					)
					(fill
						(type none)
					)
				)
				(polyline
					(pts
						(xy 10.16 -3.81) (xy 12.065 -3.81) (xy 12.065 -2.54) (xy 12.7 -2.54)
					)
					(stroke
						(width 0.254)
						(type default)
					)
					(fill
						(type none)
					)
				)
				(pin power_in line
					(at 0 0 0)
					(length 2.54)
					(name "VCC"
						(effects
							(font
								(size 1.27 1.27)
							)
						)
					)
					(number "5"
						(effects
							(font
								(size 1.27 1.27)
							)
						)
					)
				)
				(pin input line
					(at 0 -2.54 0)
					(length 2.54)
					(name "I0"
						(effects
							(font
								(size 1.27 1.27)
							)
						)
					)
					(number "3"
						(effects
							(font
								(size 1.27 1.27)
							)
						)
					)
				)
				(pin input line
					(at 0 -5.08 0)
					(length 2.54)
					(name "I1"
						(effects
							(font
								(size 1.27 1.27)
							)
						)
					)
					(number "1"
						(effects
							(font
								(size 1.27 1.27)
							)
						)
					)
				)
				(pin input line
					(at 0 -7.62 0)
					(length 2.54)
					(name "S"
						(effects
							(font
								(size 1.27 1.27)
							)
						)
					)
					(number "6"
						(effects
							(font
								(size 1.27 1.27)
							)
						)
					)
				)
				(pin output line
					(at 17.78 -2.54 180)
					(length 2.54)
					(name "Y"
						(effects
							(font
								(size 1.27 1.27)
							)
						)
					)
					(number "4"
						(effects
							(font
								(size 1.27 1.27)
							)
						)
					)
				)
				(pin power_in line
					(at 17.78 -7.62 180)
					(length 2.54)
					(name "GND"
						(effects
							(font
								(size 1.27 1.27)
							)
						)
					)
					(number "2"
						(effects
							(font
								(size 1.27 1.27)
							)
						)
					)
				)
			)
		)
	(symbol "antmicroInterfaceControllers:FT230X_QFN"
			(exclude_from_sim no)
			(in_bom yes)
			(on_board yes)
			(property "Reference" "U"
				(at 39.37 -7.62 0)
				(effects
					(font
						(size 1.27 1.27)
						(thickness 0.15)
					)
					(justify left bottom)
				)
			)
			(property "Value" "FT230X_QFN"
				(at 39.37 -10.16 0)
				(effects
					(font
						(size 1.27 1.27)
						(thickness 0.15)
					)
					(justify left bottom)
					(hide yes)
				)
			)
			(property "Footprint" "antmicro-footprints:QFN-16-1EP_4x4mm_P0.65mm"
				(at 39.37 -12.7 0)
				(effects
					(font
						(size 1.27 1.27)
						(thickness 0.15)
					)
					(justify left bottom)
					(hide yes)
				)
			)
			(property "Datasheet" "https://ftdichip.com/wp-content/uploads/2021/10/DS_FT230X.pdf"
				(at 39.37 -15.24 0)
				(effects
					(font
						(size 1.27 1.27)
						(thickness 0.15)
					)
					(justify left bottom)
					(hide yes)
				)
			)
			(property "Description" "USB Interface, USB-UART Converter, USB 2.0, 2.97 V, 5.5 V, QFN, 16 Pins"
				(at 0 0 0)
				(effects
					(font
						(size 1.27 1.27)
					)
					(hide yes)
				)
			)
			(property "MPN" "FT230XQ-R"
				(at 39.37 -20.32 0)
				(effects
					(font
						(size 1.27 1.27)
						(thickness 0.15)
					)
					(justify left bottom)
				)
			)
			(property "Manufacturer" "FTDI Chip"
				(at 39.37 -17.78 0)
				(effects
					(font
						(size 1.27 1.27)
						(thickness 0.15)
					)
					(justify left bottom)
					(hide yes)
				)
			)
			(property "Author" "Antmicro"
				(at 39.37 -22.86 0)
				(effects
					(font
						(size 1.27 1.27)
						(thickness 0.15)
					)
					(justify left bottom)
					(hide yes)
				)
			)
			(property "License" "Apache-2.0"
				(at 39.37 -25.4 0)
				(effects
					(font
						(size 1.27 1.27)
						(thickness 0.15)
					)
					(justify left bottom)
					(hide yes)
				)
			)
			(property "ki_keywords" "SMT, INTERFACE, IC, CONTROLLER, USB, UART"
				(at 0 0 0)
				(effects
					(font
						(size 1.27 1.27)
					)
					(hide yes)
				)
			)
			(symbol "FT230X_QFN_1_1"
				(rectangle
					(start 2.54 2.54)
					(end 20.32 -22.86)
					(stroke
						(width 0.254)
						(type default)
					)
					(fill
						(type background)
					)
				)
				(pin power_in line
					(at 0 0 0)
					(length 2.54)
					(name "V_{CC}"
						(effects
							(font
								(size 1.27 1.27)
							)
						)
					)
					(number "10"
						(effects
							(font
								(size 1.27 1.27)
							)
						)
					)
				)
				(pin power_in line
					(at 0 -2.54 0)
					(length 2.54)
					(name "V_{CCIO}"
						(effects
							(font
								(size 1.27 1.27)
							)
						)
					)
					(number "1"
						(effects
							(font
								(size 1.27 1.27)
							)
						)
					)
				)
				(pin passive line
					(at 0 -5.08 0)
					(length 2.54)
					(name "3V3_{OUT}"
						(effects
							(font
								(size 1.27 1.27)
							)
						)
					)
					(number "8"
						(effects
							(font
								(size 1.27 1.27)
							)
						)
					)
				)
				(pin input line
					(at 0 -8.89 0)
					(length 2.54)
					(name "D+"
						(effects
							(font
								(size 1.27 1.27)
							)
						)
					)
					(number "6"
						(effects
							(font
								(size 1.27 1.27)
							)
						)
					)
				)
				(pin input line
					(at 0 -11.43 0)
					(length 2.54)
					(name "D-"
						(effects
							(font
								(size 1.27 1.27)
							)
						)
					)
					(number "7"
						(effects
							(font
								(size 1.27 1.27)
							)
						)
					)
				)
				(pin input line
					(at 0 -15.24 0)
					(length 2.54)
					(name "~{RESET}"
						(effects
							(font
								(size 1.27 1.27)
							)
						)
					)
					(number "9"
						(effects
							(font
								(size 1.27 1.27)
							)
						)
					)
				)
				(pin power_in line
					(at 0 -20.32 0)
					(length 2.54)
					(name "GND"
						(effects
							(font
								(size 1.27 1.27)
							)
						)
					)
					(number "13"
						(effects
							(font
								(size 1.27 1.27)
							)
						)
					)
				)
				(pin passive line
					(at 0 -20.32 0)
					(length 2.54)
					(hide yes)
					(name "GND"
						(effects
							(font
								(size 1.27 1.27)
							)
						)
					)
					(number "17"
						(effects
							(font
								(size 1.27 1.27)
							)
						)
					)
				)
				(pin passive line
					(at 0 -20.32 0)
					(length 2.54)
					(hide yes)
					(name "GND"
						(effects
							(font
								(size 1.27 1.27)
							)
						)
					)
					(number "3"
						(effects
							(font
								(size 1.27 1.27)
							)
						)
					)
				)
				(pin output line
					(at 22.86 0 180)
					(length 2.54)
					(name "TXD"
						(effects
							(font
								(size 1.27 1.27)
							)
						)
					)
					(number "15"
						(effects
							(font
								(size 1.27 1.27)
							)
						)
					)
				)
				(pin input line
					(at 22.86 -2.54 180)
					(length 2.54)
					(name "RXD"
						(effects
							(font
								(size 1.27 1.27)
							)
						)
					)
					(number "2"
						(effects
							(font
								(size 1.27 1.27)
							)
						)
					)
				)
				(pin output line
					(at 22.86 -5.08 180)
					(length 2.54)
					(name "~{RTS}"
						(effects
							(font
								(size 1.27 1.27)
							)
						)
					)
					(number "16"
						(effects
							(font
								(size 1.27 1.27)
							)
						)
					)
				)
				(pin input line
					(at 22.86 -7.62 180)
					(length 2.54)
					(name "~{CTS}"
						(effects
							(font
								(size 1.27 1.27)
							)
						)
					)
					(number "4"
						(effects
							(font
								(size 1.27 1.27)
							)
						)
					)
				)
				(pin bidirectional line
					(at 22.86 -12.7 180)
					(length 2.54)
					(name "CBUS0"
						(effects
							(font
								(size 1.27 1.27)
							)
						)
					)
					(number "12"
						(effects
							(font
								(size 1.27 1.27)
							)
						)
					)
				)
				(pin bidirectional line
					(at 22.86 -15.24 180)
					(length 2.54)
					(name "CBUS1"
						(effects
							(font
								(size 1.27 1.27)
							)
						)
					)
					(number "11"
						(effects
							(font
								(size 1.27 1.27)
							)
						)
					)
				)
				(pin bidirectional line
					(at 22.86 -17.78 180)
					(length 2.54)
					(name "CBUS2"
						(effects
							(font
								(size 1.27 1.27)
							)
						)
					)
					(number "5"
						(effects
							(font
								(size 1.27 1.27)
							)
						)
					)
				)
				(pin bidirectional line
					(at 22.86 -20.32 180)
					(length 2.54)
					(name "CBUS3"
						(effects
							(font
								(size 1.27 1.27)
							)
						)
					)
					(number "14"
						(effects
							(font
								(size 1.27 1.27)
							)
						)
					)
				)
			)
		)
	(symbol "antmicroInterfaceControllers:TLK10232CTR"
			(exclude_from_sim no)
			(in_bom yes)
			(on_board yes)
			(property "Reference" "U"
				(at 46.99 0 0)
				(effects
					(font
						(size 1.27 1.27)
						(thickness 0.15)
					)
					(justify left bottom)
				)
			)
			(property "Value" "TLK10232CTR"
				(at 46.99 -7.62 0)
				(effects
					(font
						(size 1.27 1.27)
						(thickness 0.15)
					)
					(justify left bottom)
					(hide yes)
				)
			)
			(property "Footprint" "antmicro-footprints:BGA-144_12x12_13.05x13.05mm_P1.0mm"
				(at 46.99 -10.16 0)
				(effects
					(font
						(size 1.27 1.27)
						(thickness 0.15)
					)
					(justify left bottom)
					(hide yes)
				)
			)
			(property "Datasheet" "https://www.ti.com/lit/ds/symlink/tlk10232.pdf?ts=1712150848075&ref_url=https%253A%252F%252Fwww.mouser.pl%252F"
				(at 46.99 -12.7 0)
				(effects
					(font
						(size 1.27 1.27)
						(thickness 0.15)
					)
					(justify left bottom)
					(hide yes)
				)
			)
			(property "Description" "Dual channel XAUI-to-10GBASE-KR backplane transceiver with crosspoint switch"
				(at 0 0 0)
				(effects
					(font
						(size 1.27 1.27)
					)
					(hide yes)
				)
			)
			(property "MPN" "TLK10232CTR"
				(at 46.99 -2.54 0)
				(effects
					(font
						(size 1.27 1.27)
						(thickness 0.15)
					)
					(justify left bottom)
				)
			)
			(property "Manufacturer" "Texas Instruments"
				(at 46.99 -5.08 0)
				(effects
					(font
						(size 1.27 1.27)
						(thickness 0.15)
					)
					(justify left bottom)
					(hide yes)
				)
			)
			(property "Author" "Antmicro"
				(at 46.99 -15.24 0)
				(effects
					(font
						(size 1.27 1.27)
						(thickness 0.15)
					)
					(justify left bottom)
					(hide yes)
				)
			)
			(property "License" "Apache-2.0"
				(at 46.99 -17.78 0)
				(effects
					(font
						(size 1.27 1.27)
						(thickness 0.15)
					)
					(justify left bottom)
					(hide yes)
				)
			)
			(property "ki_locked" ""
				(at 0 0 0)
				(effects
					(font
						(size 1.27 1.27)
					)
				)
			)
			(property "ki_keywords" "SMT, TRANSCEIVER, IC, ETHERNET, PHY"
				(at 0 0 0)
				(effects
					(font
						(size 1.27 1.27)
					)
					(hide yes)
				)
			)
			(symbol "TLK10232CTR_1_1"
				(rectangle
					(start 3.81 2.54)
					(end 26.67 -55.88)
					(stroke
						(width 0.254)
						(type default)
					)
					(fill
						(type background)
					)
				)
				(text "CH A"
					(at 20.32 0 0)
					(effects
						(font
							(size 1.27 1.27)
							(thickness 0.15)
						)
						(justify left bottom)
					)
				)
				(pin input line
					(at 0 0 0)
					(length 3.81)
					(name "INA3+"
						(effects
							(font
								(size 1.27 1.27)
							)
						)
					)
					(number "D1"
						(effects
							(font
								(size 1.27 1.27)
							)
						)
					)
				)
				(pin input line
					(at 0 -2.54 0)
					(length 3.81)
					(name "INA3-"
						(effects
							(font
								(size 1.27 1.27)
							)
						)
					)
					(number "E1"
						(effects
							(font
								(size 1.27 1.27)
							)
						)
					)
				)
				(pin input line
					(at 0 -5.08 0)
					(length 3.81)
					(name "INA2+"
						(effects
							(font
								(size 1.27 1.27)
							)
						)
					)
					(number "B2"
						(effects
							(font
								(size 1.27 1.27)
							)
						)
					)
				)
				(pin input line
					(at 0 -7.62 0)
					(length 3.81)
					(name "INA2-"
						(effects
							(font
								(size 1.27 1.27)
							)
						)
					)
					(number "C2"
						(effects
							(font
								(size 1.27 1.27)
							)
						)
					)
				)
				(pin input line
					(at 0 -10.16 0)
					(length 3.81)
					(name "INA1+"
						(effects
							(font
								(size 1.27 1.27)
							)
						)
					)
					(number "A1"
						(effects
							(font
								(size 1.27 1.27)
							)
						)
					)
				)
				(pin input line
					(at 0 -12.7 0)
					(length 3.81)
					(name "INA1-"
						(effects
							(font
								(size 1.27 1.27)
							)
						)
					)
					(number "B1"
						(effects
							(font
								(size 1.27 1.27)
							)
						)
					)
				)
				(pin input line
					(at 0 -15.24 0)
					(length 3.81)
					(name "INA0+"
						(effects
							(font
								(size 1.27 1.27)
							)
						)
					)
					(number "A4"
						(effects
							(font
								(size 1.27 1.27)
							)
						)
					)
				)
				(pin input line
					(at 0 -17.78 0)
					(length 3.81)
					(name "INA0-"
						(effects
							(font
								(size 1.27 1.27)
							)
						)
					)
					(number "A3"
						(effects
							(font
								(size 1.27 1.27)
							)
						)
					)
				)
				(pin output line
					(at 0 -22.86 0)
					(length 3.81)
					(name "OUTA3+"
						(effects
							(font
								(size 1.27 1.27)
							)
						)
					)
					(number "F3"
						(effects
							(font
								(size 1.27 1.27)
							)
						)
					)
				)
				(pin output line
					(at 0 -25.4 0)
					(length 3.81)
					(name "OUTA3-"
						(effects
							(font
								(size 1.27 1.27)
							)
						)
					)
					(number "E3"
						(effects
							(font
								(size 1.27 1.27)
							)
						)
					)
				)
				(pin output line
					(at 0 -27.94 0)
					(length 3.81)
					(name "OUTA2+"
						(effects
							(font
								(size 1.27 1.27)
							)
						)
					)
					(number "C4"
						(effects
							(font
								(size 1.27 1.27)
							)
						)
					)
				)
				(pin output line
					(at 0 -30.48 0)
					(length 3.81)
					(name "OUTA2-"
						(effects
							(font
								(size 1.27 1.27)
							)
						)
					)
					(number "C5"
						(effects
							(font
								(size 1.27 1.27)
							)
						)
					)
				)
				(pin output line
					(at 0 -33.02 0)
					(length 3.81)
					(name "OUTA1+"
						(effects
							(font
								(size 1.27 1.27)
							)
						)
					)
					(number "B5"
						(effects
							(font
								(size 1.27 1.27)
							)
						)
					)
				)
				(pin output line
					(at 0 -35.56 0)
					(length 3.81)
					(name "OUTA1-"
						(effects
							(font
								(size 1.27 1.27)
							)
						)
					)
					(number "B6"
						(effects
							(font
								(size 1.27 1.27)
							)
						)
					)
				)
				(pin output line
					(at 0 -38.1 0)
					(length 3.81)
					(name "OUTA0+"
						(effects
							(font
								(size 1.27 1.27)
							)
						)
					)
					(number "A6"
						(effects
							(font
								(size 1.27 1.27)
							)
						)
					)
				)
				(pin output line
					(at 0 -40.64 0)
					(length 3.81)
					(name "OUTA0-"
						(effects
							(font
								(size 1.27 1.27)
							)
						)
					)
					(number "A7"
						(effects
							(font
								(size 1.27 1.27)
							)
						)
					)
				)
				(pin output line
					(at 0 -45.72 0)
					(length 3.81)
					(name "LOSA"
						(effects
							(font
								(size 1.27 1.27)
							)
						)
					)
					(number "E9"
						(effects
							(font
								(size 1.27 1.27)
							)
						)
					)
				)
				(pin input line
					(at 0 -48.26 0)
					(length 3.81)
					(name "LS_OK_{IN_A}"
						(effects
							(font
								(size 1.27 1.27)
							)
						)
					)
					(number "B10"
						(effects
							(font
								(size 1.27 1.27)
							)
						)
					)
				)
				(pin output line
					(at 0 -50.8 0)
					(length 3.81)
					(name "LS_OK_{OUT_A}"
						(effects
							(font
								(size 1.27 1.27)
							)
						)
					)
					(number "D9"
						(effects
							(font
								(size 1.27 1.27)
							)
						)
					)
				)
				(pin input line
					(at 0 -53.34 0)
					(length 3.81)
					(name "~{PDTRXA}"
						(effects
							(font
								(size 1.27 1.27)
							)
						)
					)
					(number "A8"
						(effects
							(font
								(size 1.27 1.27)
							)
						)
					)
				)
				(pin output line
					(at 30.48 -5.08 180)
					(length 3.81)
					(name "HSTXA+"
						(effects
							(font
								(size 1.27 1.27)
							)
						)
					)
					(number "D12"
						(effects
							(font
								(size 1.27 1.27)
							)
						)
					)
				)
				(pin output line
					(at 30.48 -7.62 180)
					(length 3.81)
					(name "HSTXA-"
						(effects
							(font
								(size 1.27 1.27)
							)
						)
					)
					(number "E12"
						(effects
							(font
								(size 1.27 1.27)
							)
						)
					)
				)
				(pin input line
					(at 30.48 -12.7 180)
					(length 3.81)
					(name "HSRXA+"
						(effects
							(font
								(size 1.27 1.27)
							)
						)
					)
					(number "B12"
						(effects
							(font
								(size 1.27 1.27)
							)
						)
					)
				)
				(pin input line
					(at 30.48 -15.24 180)
					(length 3.81)
					(name "HSRXA-"
						(effects
							(font
								(size 1.27 1.27)
							)
						)
					)
					(number "A12"
						(effects
							(font
								(size 1.27 1.27)
							)
						)
					)
				)
			)
			(symbol "TLK10232CTR_2_1"
				(rectangle
					(start 3.81 2.54)
					(end 26.67 -55.88)
					(stroke
						(width 0.254)
						(type default)
					)
					(fill
						(type background)
					)
				)
				(text "CH B\n"
					(at 20.32 0 0)
					(effects
						(font
							(size 1.27 1.27)
							(thickness 0.15)
						)
						(justify left bottom)
					)
				)
				(pin input line
					(at 0 0 0)
					(length 3.81)
					(name "INB3+"
						(effects
							(font
								(size 1.27 1.27)
							)
						)
					)
					(number "M3"
						(effects
							(font
								(size 1.27 1.27)
							)
						)
					)
				)
				(pin input line
					(at 0 -2.54 0)
					(length 3.81)
					(name "INB3-"
						(effects
							(font
								(size 1.27 1.27)
							)
						)
					)
					(number "M4"
						(effects
							(font
								(size 1.27 1.27)
							)
						)
					)
				)
				(pin input line
					(at 0 -5.08 0)
					(length 3.81)
					(name "INB2+"
						(effects
							(font
								(size 1.27 1.27)
							)
						)
					)
					(number "L1"
						(effects
							(font
								(size 1.27 1.27)
							)
						)
					)
				)
				(pin input line
					(at 0 -7.62 0)
					(length 3.81)
					(name "INB2-"
						(effects
							(font
								(size 1.27 1.27)
							)
						)
					)
					(number "M1"
						(effects
							(font
								(size 1.27 1.27)
							)
						)
					)
				)
				(pin input line
					(at 0 -10.16 0)
					(length 3.81)
					(name "INB1+"
						(effects
							(font
								(size 1.27 1.27)
							)
						)
					)
					(number "K2"
						(effects
							(font
								(size 1.27 1.27)
							)
						)
					)
				)
				(pin input line
					(at 0 -12.7 0)
					(length 3.81)
					(name "INB1-"
						(effects
							(font
								(size 1.27 1.27)
							)
						)
					)
					(number "L2"
						(effects
							(font
								(size 1.27 1.27)
							)
						)
					)
				)
				(pin input line
					(at 0 -15.24 0)
					(length 3.81)
					(name "INB0+"
						(effects
							(font
								(size 1.27 1.27)
							)
						)
					)
					(number "H1"
						(effects
							(font
								(size 1.27 1.27)
							)
						)
					)
				)
				(pin input line
					(at 0 -17.78 0)
					(length 3.81)
					(name "INB0-"
						(effects
							(font
								(size 1.27 1.27)
							)
						)
					)
					(number "J1"
						(effects
							(font
								(size 1.27 1.27)
							)
						)
					)
				)
				(pin output line
					(at 0 -22.86 0)
					(length 3.81)
					(name "OUTB3+"
						(effects
							(font
								(size 1.27 1.27)
							)
						)
					)
					(number "M7"
						(effects
							(font
								(size 1.27 1.27)
							)
						)
					)
				)
				(pin output line
					(at 0 -25.4 0)
					(length 3.81)
					(name "OUTB3-"
						(effects
							(font
								(size 1.27 1.27)
							)
						)
					)
					(number "M6"
						(effects
							(font
								(size 1.27 1.27)
							)
						)
					)
				)
				(pin output line
					(at 0 -27.94 0)
					(length 3.81)
					(name "OUTB2+"
						(effects
							(font
								(size 1.27 1.27)
							)
						)
					)
					(number "L6"
						(effects
							(font
								(size 1.27 1.27)
							)
						)
					)
				)
				(pin output line
					(at 0 -30.48 0)
					(length 3.81)
					(name "OUTB2-"
						(effects
							(font
								(size 1.27 1.27)
							)
						)
					)
					(number "L5"
						(effects
							(font
								(size 1.27 1.27)
							)
						)
					)
				)
				(pin output line
					(at 0 -33.02 0)
					(length 3.81)
					(name "OUTB1+"
						(effects
							(font
								(size 1.27 1.27)
							)
						)
					)
					(number "K5"
						(effects
							(font
								(size 1.27 1.27)
							)
						)
					)
				)
				(pin output line
					(at 0 -35.56 0)
					(length 3.81)
					(name "OUTB1-"
						(effects
							(font
								(size 1.27 1.27)
							)
						)
					)
					(number "K4"
						(effects
							(font
								(size 1.27 1.27)
							)
						)
					)
				)
				(pin output line
					(at 0 -38.1 0)
					(length 3.81)
					(name "OUTB0+"
						(effects
							(font
								(size 1.27 1.27)
							)
						)
					)
					(number "J3"
						(effects
							(font
								(size 1.27 1.27)
							)
						)
					)
				)
				(pin output line
					(at 0 -40.64 0)
					(length 3.81)
					(name "OUTB0-"
						(effects
							(font
								(size 1.27 1.27)
							)
						)
					)
					(number "H3"
						(effects
							(font
								(size 1.27 1.27)
							)
						)
					)
				)
				(pin output line
					(at 0 -45.72 0)
					(length 3.81)
					(name "LOSB"
						(effects
							(font
								(size 1.27 1.27)
							)
						)
					)
					(number "K8"
						(effects
							(font
								(size 1.27 1.27)
							)
						)
					)
				)
				(pin input line
					(at 0 -48.26 0)
					(length 3.81)
					(name "LS_OK_{IN_B}"
						(effects
							(font
								(size 1.27 1.27)
							)
						)
					)
					(number "L8"
						(effects
							(font
								(size 1.27 1.27)
							)
						)
					)
				)
				(pin output line
					(at 0 -50.8 0)
					(length 3.81)
					(name "LS_OK_{OUT_B}"
						(effects
							(font
								(size 1.27 1.27)
							)
						)
					)
					(number "H9"
						(effects
							(font
								(size 1.27 1.27)
							)
						)
					)
				)
				(pin input line
					(at 0 -53.34 0)
					(length 3.81)
					(name "~{PDTRXB}"
						(effects
							(font
								(size 1.27 1.27)
							)
						)
					)
					(number "J4"
						(effects
							(font
								(size 1.27 1.27)
							)
						)
					)
				)
				(pin output line
					(at 30.48 -5.08 180)
					(length 3.81)
					(name "HSTXB+"
						(effects
							(font
								(size 1.27 1.27)
							)
						)
					)
					(number "K12"
						(effects
							(font
								(size 1.27 1.27)
							)
						)
					)
				)
				(pin output line
					(at 30.48 -7.62 180)
					(length 3.81)
					(name "HSTXB-"
						(effects
							(font
								(size 1.27 1.27)
							)
						)
					)
					(number "L12"
						(effects
							(font
								(size 1.27 1.27)
							)
						)
					)
				)
				(pin input line
					(at 30.48 -12.7 180)
					(length 3.81)
					(name "HSRXB+"
						(effects
							(font
								(size 1.27 1.27)
							)
						)
					)
					(number "H12"
						(effects
							(font
								(size 1.27 1.27)
							)
						)
					)
				)
				(pin input line
					(at 30.48 -15.24 180)
					(length 3.81)
					(name "HSRXB-"
						(effects
							(font
								(size 1.27 1.27)
							)
						)
					)
					(number "G12"
						(effects
							(font
								(size 1.27 1.27)
							)
						)
					)
				)
			)
			(symbol "TLK10232CTR_3_1"
				(rectangle
					(start 3.81 2.54)
					(end 26.67 -60.96)
					(stroke
						(width 0.254)
						(type default)
					)
					(fill
						(type background)
					)
				)
				(text "MISC"
					(at 20.32 0 0)
					(effects
						(font
							(size 1.27 1.27)
							(thickness 0.15)
						)
						(justify left bottom)
					)
				)
				(pin input line
					(at 0 0 0)
					(length 3.81)
					(name "~{RESET}"
						(effects
							(font
								(size 1.27 1.27)
							)
						)
					)
					(number "H5"
						(effects
							(font
								(size 1.27 1.27)
							)
						)
					)
				)
				(pin input line
					(at 0 -5.08 0)
					(length 3.81)
					(name "REFCLK0+"
						(effects
							(font
								(size 1.27 1.27)
							)
						)
					)
					(number "M10"
						(effects
							(font
								(size 1.27 1.27)
							)
						)
					)
				)
				(pin input line
					(at 0 -7.62 0)
					(length 3.81)
					(name "REFCLK0-"
						(effects
							(font
								(size 1.27 1.27)
							)
						)
					)
					(number "M11"
						(effects
							(font
								(size 1.27 1.27)
							)
						)
					)
				)
				(pin input line
					(at 0 -12.7 0)
					(length 3.81)
					(name "REFCLK1+"
						(effects
							(font
								(size 1.27 1.27)
							)
						)
					)
					(number "K9"
						(effects
							(font
								(size 1.27 1.27)
							)
						)
					)
				)
				(pin input line
					(at 0 -15.24 0)
					(length 3.81)
					(name "REFCLK1-"
						(effects
							(font
								(size 1.27 1.27)
							)
						)
					)
					(number "K10"
						(effects
							(font
								(size 1.27 1.27)
							)
						)
					)
				)
				(pin input line
					(at 0 -20.32 0)
					(length 3.81)
					(name "TDI"
						(effects
							(font
								(size 1.27 1.27)
							)
						)
					)
					(number "C8"
						(effects
							(font
								(size 1.27 1.27)
							)
						)
					)
				)
				(pin output line
					(at 0 -22.86 0)
					(length 3.81)
					(name "TDO"
						(effects
							(font
								(size 1.27 1.27)
							)
						)
					)
					(number "D6"
						(effects
							(font
								(size 1.27 1.27)
							)
						)
					)
				)
				(pin input line
					(at 0 -25.4 0)
					(length 3.81)
					(name "TMS"
						(effects
							(font
								(size 1.27 1.27)
							)
						)
					)
					(number "B8"
						(effects
							(font
								(size 1.27 1.27)
							)
						)
					)
				)
				(pin input line
					(at 0 -27.94 0)
					(length 3.81)
					(name "TCK"
						(effects
							(font
								(size 1.27 1.27)
							)
						)
					)
					(number "D8"
						(effects
							(font
								(size 1.27 1.27)
							)
						)
					)
				)
				(pin input line
					(at 0 -30.48 0)
					(length 3.81)
					(name "~{TRST}"
						(effects
							(font
								(size 1.27 1.27)
							)
						)
					)
					(number "E5"
						(effects
							(font
								(size 1.27 1.27)
							)
						)
					)
				)
				(pin input line
					(at 0 -35.56 0)
					(length 3.81)
					(name "PRBSEN"
						(effects
							(font
								(size 1.27 1.27)
							)
						)
					)
					(number "B9"
						(effects
							(font
								(size 1.27 1.27)
							)
						)
					)
				)
				(pin output line
					(at 0 -38.1 0)
					(length 3.81)
					(name "PRBS_{PASS}"
						(effects
							(font
								(size 1.27 1.27)
							)
						)
					)
					(number "J9"
						(effects
							(font
								(size 1.27 1.27)
							)
						)
					)
				)
				(pin bidirectional line
					(at 0 -43.18 0)
					(length 3.81)
					(name "MDIO"
						(effects
							(font
								(size 1.27 1.27)
							)
						)
					)
					(number "J7"
						(effects
							(font
								(size 1.27 1.27)
							)
						)
					)
				)
				(pin input line
					(at 0 -45.72 0)
					(length 3.81)
					(name "MDC"
						(effects
							(font
								(size 1.27 1.27)
							)
						)
					)
					(number "J8"
						(effects
							(font
								(size 1.27 1.27)
							)
						)
					)
				)
				(pin input line
					(at 0 -50.8 0)
					(length 3.81)
					(name "TESTEN"
						(effects
							(font
								(size 1.27 1.27)
							)
						)
					)
					(number "L10"
						(effects
							(font
								(size 1.27 1.27)
							)
						)
					)
				)
				(pin input line
					(at 0 -53.34 0)
					(length 3.81)
					(name "GPI0"
						(effects
							(font
								(size 1.27 1.27)
							)
						)
					)
					(number "J10"
						(effects
							(font
								(size 1.27 1.27)
							)
						)
					)
				)
				(pin passive line
					(at 0 -55.88 0)
					(length 3.81)
					(name "AMUXA"
						(effects
							(font
								(size 1.27 1.27)
							)
						)
					)
					(number "C11"
						(effects
							(font
								(size 1.27 1.27)
							)
						)
					)
				)
				(pin passive line
					(at 0 -58.42 0)
					(length 3.81)
					(name "AMUXB"
						(effects
							(font
								(size 1.27 1.27)
							)
						)
					)
					(number "D4"
						(effects
							(font
								(size 1.27 1.27)
							)
						)
					)
				)
				(pin output line
					(at 30.48 -5.08 180)
					(length 3.81)
					(name "CLKOUTA+"
						(effects
							(font
								(size 1.27 1.27)
							)
						)
					)
					(number "C9"
						(effects
							(font
								(size 1.27 1.27)
							)
						)
					)
				)
				(pin output line
					(at 30.48 -7.62 180)
					(length 3.81)
					(name "CLKOUTA-"
						(effects
							(font
								(size 1.27 1.27)
							)
						)
					)
					(number "C10"
						(effects
							(font
								(size 1.27 1.27)
							)
						)
					)
				)
				(pin output line
					(at 30.48 -12.7 180)
					(length 3.81)
					(name "CLKOUTB+"
						(effects
							(font
								(size 1.27 1.27)
							)
						)
					)
					(number "A9"
						(effects
							(font
								(size 1.27 1.27)
							)
						)
					)
				)
				(pin output line
					(at 30.48 -15.24 180)
					(length 3.81)
					(name "CLKOUTB-"
						(effects
							(font
								(size 1.27 1.27)
							)
						)
					)
					(number "A10"
						(effects
							(font
								(size 1.27 1.27)
							)
						)
					)
				)
				(pin input line
					(at 30.48 -40.64 180)
					(length 3.81)
					(name "ST"
						(effects
							(font
								(size 1.27 1.27)
							)
						)
					)
					(number "M9"
						(effects
							(font
								(size 1.27 1.27)
							)
						)
					)
				)
				(pin input line
					(at 30.48 -43.18 180)
					(length 3.81)
					(name "MODE_{SEL}"
						(effects
							(font
								(size 1.27 1.27)
							)
						)
					)
					(number "H10"
						(effects
							(font
								(size 1.27 1.27)
							)
						)
					)
				)
				(pin input line
					(at 30.48 -48.26 180)
					(length 3.81)
					(name "PRTAD4"
						(effects
							(font
								(size 1.27 1.27)
							)
						)
					)
					(number "M8"
						(effects
							(font
								(size 1.27 1.27)
							)
						)
					)
				)
				(pin input line
					(at 30.48 -50.8 180)
					(length 3.81)
					(name "PRTAD3"
						(effects
							(font
								(size 1.27 1.27)
							)
						)
					)
					(number "J6"
						(effects
							(font
								(size 1.27 1.27)
							)
						)
					)
				)
				(pin input line
					(at 30.48 -53.34 180)
					(length 3.81)
					(name "PRTAD2"
						(effects
							(font
								(size 1.27 1.27)
							)
						)
					)
					(number "L9"
						(effects
							(font
								(size 1.27 1.27)
							)
						)
					)
				)
				(pin input line
					(at 30.48 -55.88 180)
					(length 3.81)
					(name "PRTAD1"
						(effects
							(font
								(size 1.27 1.27)
							)
						)
					)
					(number "G9"
						(effects
							(font
								(size 1.27 1.27)
							)
						)
					)
				)
				(pin input line
					(at 30.48 -58.42 180)
					(length 3.81)
					(name "PRTAD0"
						(effects
							(font
								(size 1.27 1.27)
							)
						)
					)
					(number "E10"
						(effects
							(font
								(size 1.27 1.27)
							)
						)
					)
				)
			)
			(symbol "TLK10232CTR_4_1"
				(rectangle
					(start 3.81 2.54)
					(end 26.67 -33.02)
					(stroke
						(width 0.254)
						(type default)
					)
					(fill
						(type background)
					)
				)
				(text "POWER"
					(at 19.05 0 0)
					(effects
						(font
							(size 1.27 1.27)
							(thickness 0.15)
						)
						(justify left bottom)
					)
				)
				(pin power_in line
					(at 0 0 0)
					(length 3.81)
					(name "VDDA_{LS/HS}"
						(effects
							(font
								(size 1.27 1.27)
							)
						)
					)
					(number "D2"
						(effects
							(font
								(size 1.27 1.27)
							)
						)
					)
				)
				(pin passive line
					(at 0 0 0)
					(length 3.81)
					(hide yes)
					(name "VDDA_{LS/HS}"
						(effects
							(font
								(size 1.27 1.27)
							)
						)
					)
					(number "F11"
						(effects
							(font
								(size 1.27 1.27)
							)
						)
					)
				)
				(pin passive line
					(at 0 0 0)
					(length 3.81)
					(hide yes)
					(name "VDDA_{LS/HS}"
						(effects
							(font
								(size 1.27 1.27)
							)
						)
					)
					(number "F2"
						(effects
							(font
								(size 1.27 1.27)
							)
						)
					)
				)
				(pin passive line
					(at 0 0 0)
					(length 3.81)
					(hide yes)
					(name "VDDA_{LS/HS}"
						(effects
							(font
								(size 1.27 1.27)
							)
						)
					)
					(number "G10"
						(effects
							(font
								(size 1.27 1.27)
							)
						)
					)
				)
				(pin passive line
					(at 0 0 0)
					(length 3.81)
					(hide yes)
					(name "VDDA_{LS/HS}"
						(effects
							(font
								(size 1.27 1.27)
							)
						)
					)
					(number "G2"
						(effects
							(font
								(size 1.27 1.27)
							)
						)
					)
				)
				(pin passive line
					(at 0 0 0)
					(length 3.81)
					(hide yes)
					(name "VDDA_{LS/HS}"
						(effects
							(font
								(size 1.27 1.27)
							)
						)
					)
					(number "J2"
						(effects
							(font
								(size 1.27 1.27)
							)
						)
					)
				)
				(pin power_in line
					(at 0 -2.54 0)
					(length 3.81)
					(name "VDDT_{LS/HS}"
						(effects
							(font
								(size 1.27 1.27)
							)
						)
					)
					(number "F4"
						(effects
							(font
								(size 1.27 1.27)
							)
						)
					)
				)
				(pin passive line
					(at 0 -2.54 0)
					(length 3.81)
					(hide yes)
					(name "VDDT_{LS/HS}"
						(effects
							(font
								(size 1.27 1.27)
							)
						)
					)
					(number "F9"
						(effects
							(font
								(size 1.27 1.27)
							)
						)
					)
				)
				(pin passive line
					(at 0 -2.54 0)
					(length 3.81)
					(hide yes)
					(name "VDDT_{LS/HS}"
						(effects
							(font
								(size 1.27 1.27)
							)
						)
					)
					(number "G4"
						(effects
							(font
								(size 1.27 1.27)
							)
						)
					)
				)
				(pin power_in line
					(at 0 -7.62 0)
					(length 3.81)
					(name "VDDRA_{LS/HS}"
						(effects
							(font
								(size 1.27 1.27)
							)
						)
					)
					(number "C3"
						(effects
							(font
								(size 1.27 1.27)
							)
						)
					)
				)
				(pin passive line
					(at 0 -7.62 0)
					(length 3.81)
					(hide yes)
					(name "VDDRA_{LS/HS}"
						(effects
							(font
								(size 1.27 1.27)
							)
						)
					)
					(number "E11"
						(effects
							(font
								(size 1.27 1.27)
							)
						)
					)
				)
				(pin power_in line
					(at 0 -10.16 0)
					(length 3.81)
					(name "VDDRB_{LS/HS}"
						(effects
							(font
								(size 1.27 1.27)
							)
						)
					)
					(number "J11"
						(effects
							(font
								(size 1.27 1.27)
							)
						)
					)
				)
				(pin passive line
					(at 0 -10.16 0)
					(length 3.81)
					(hide yes)
					(name "VDDRB_{LS/HS}"
						(effects
							(font
								(size 1.27 1.27)
							)
						)
					)
					(number "K3"
						(effects
							(font
								(size 1.27 1.27)
							)
						)
					)
				)
				(pin power_in line
					(at 0 -15.24 0)
					(length 3.81)
					(name "VDDD"
						(effects
							(font
								(size 1.27 1.27)
							)
						)
					)
					(number "E6"
						(effects
							(font
								(size 1.27 1.27)
							)
						)
					)
				)
				(pin passive line
					(at 0 -15.24 0)
					(length 3.81)
					(hide yes)
					(name "VDDD"
						(effects
							(font
								(size 1.27 1.27)
							)
						)
					)
					(number "E8"
						(effects
							(font
								(size 1.27 1.27)
							)
						)
					)
				)
				(pin passive line
					(at 0 -15.24 0)
					(length 3.81)
					(hide yes)
					(name "VDDD"
						(effects
							(font
								(size 1.27 1.27)
							)
						)
					)
					(number "F6"
						(effects
							(font
								(size 1.27 1.27)
							)
						)
					)
				)
				(pin passive line
					(at 0 -15.24 0)
					(length 3.81)
					(hide yes)
					(name "VDDD"
						(effects
							(font
								(size 1.27 1.27)
							)
						)
					)
					(number "H6"
						(effects
							(font
								(size 1.27 1.27)
							)
						)
					)
				)
				(pin passive line
					(at 0 -15.24 0)
					(length 3.81)
					(hide yes)
					(name "VDDD"
						(effects
							(font
								(size 1.27 1.27)
							)
						)
					)
					(number "H8"
						(effects
							(font
								(size 1.27 1.27)
							)
						)
					)
				)
				(pin power_in line
					(at 0 -17.78 0)
					(length 3.81)
					(name "DVDD"
						(effects
							(font
								(size 1.27 1.27)
							)
						)
					)
					(number "E7"
						(effects
							(font
								(size 1.27 1.27)
							)
						)
					)
				)
				(pin passive line
					(at 0 -17.78 0)
					(length 3.81)
					(hide yes)
					(name "DVDD"
						(effects
							(font
								(size 1.27 1.27)
							)
						)
					)
					(number "F7"
						(effects
							(font
								(size 1.27 1.27)
							)
						)
					)
				)
				(pin passive line
					(at 0 -17.78 0)
					(length 3.81)
					(hide yes)
					(name "DVDD"
						(effects
							(font
								(size 1.27 1.27)
							)
						)
					)
					(number "G6"
						(effects
							(font
								(size 1.27 1.27)
							)
						)
					)
				)
				(pin passive line
					(at 0 -17.78 0)
					(length 3.81)
					(hide yes)
					(name "DVDD"
						(effects
							(font
								(size 1.27 1.27)
							)
						)
					)
					(number "G8"
						(effects
							(font
								(size 1.27 1.27)
							)
						)
					)
				)
				(pin passive line
					(at 0 -17.78 0)
					(length 3.81)
					(hide yes)
					(name "DVDD"
						(effects
							(font
								(size 1.27 1.27)
							)
						)
					)
					(number "H7"
						(effects
							(font
								(size 1.27 1.27)
							)
						)
					)
				)
				(pin power_in line
					(at 0 -20.32 0)
					(length 3.81)
					(name "VPP"
						(effects
							(font
								(size 1.27 1.27)
							)
						)
					)
					(number "D7"
						(effects
							(font
								(size 1.27 1.27)
							)
						)
					)
				)
				(pin power_in line
					(at 0 -25.4 0)
					(length 3.81)
					(name "VDDO1"
						(effects
							(font
								(size 1.27 1.27)
							)
						)
					)
					(number "K7"
						(effects
							(font
								(size 1.27 1.27)
							)
						)
					)
				)
				(pin power_in line
					(at 0 -27.94 0)
					(length 3.81)
					(name "VDDO0"
						(effects
							(font
								(size 1.27 1.27)
							)
						)
					)
					(number "C7"
						(effects
							(font
								(size 1.27 1.27)
							)
						)
					)
				)
				(pin power_in line
					(at 30.48 -30.48 180)
					(length 3.81)
					(name "GND"
						(effects
							(font
								(size 1.27 1.27)
							)
						)
					)
					(number "A11"
						(effects
							(font
								(size 1.27 1.27)
							)
						)
					)
				)
				(pin passive line
					(at 30.48 -30.48 180)
					(length 3.81)
					(hide yes)
					(name "GND"
						(effects
							(font
								(size 1.27 1.27)
							)
						)
					)
					(number "A2"
						(effects
							(font
								(size 1.27 1.27)
							)
						)
					)
				)
				(pin passive line
					(at 30.48 -30.48 180)
					(length 3.81)
					(hide yes)
					(name "GND"
						(effects
							(font
								(size 1.27 1.27)
							)
						)
					)
					(number "A5"
						(effects
							(font
								(size 1.27 1.27)
							)
						)
					)
				)
				(pin passive line
					(at 30.48 -30.48 180)
					(length 3.81)
					(hide yes)
					(name "GND"
						(effects
							(font
								(size 1.27 1.27)
							)
						)
					)
					(number "B11"
						(effects
							(font
								(size 1.27 1.27)
							)
						)
					)
				)
				(pin passive line
					(at 30.48 -30.48 180)
					(length 3.81)
					(hide yes)
					(name "GND"
						(effects
							(font
								(size 1.27 1.27)
							)
						)
					)
					(number "B3"
						(effects
							(font
								(size 1.27 1.27)
							)
						)
					)
				)
				(pin passive line
					(at 30.48 -30.48 180)
					(length 3.81)
					(hide yes)
					(name "GND"
						(effects
							(font
								(size 1.27 1.27)
							)
						)
					)
					(number "B4"
						(effects
							(font
								(size 1.27 1.27)
							)
						)
					)
				)
				(pin passive line
					(at 30.48 -30.48 180)
					(length 3.81)
					(hide yes)
					(name "GND"
						(effects
							(font
								(size 1.27 1.27)
							)
						)
					)
					(number "B7"
						(effects
							(font
								(size 1.27 1.27)
							)
						)
					)
				)
				(pin passive line
					(at 30.48 -30.48 180)
					(length 3.81)
					(hide yes)
					(name "GND"
						(effects
							(font
								(size 1.27 1.27)
							)
						)
					)
					(number "C1"
						(effects
							(font
								(size 1.27 1.27)
							)
						)
					)
				)
				(pin passive line
					(at 30.48 -30.48 180)
					(length 3.81)
					(hide yes)
					(name "GND"
						(effects
							(font
								(size 1.27 1.27)
							)
						)
					)
					(number "C12"
						(effects
							(font
								(size 1.27 1.27)
							)
						)
					)
				)
				(pin passive line
					(at 30.48 -30.48 180)
					(length 3.81)
					(hide yes)
					(name "GND"
						(effects
							(font
								(size 1.27 1.27)
							)
						)
					)
					(number "C6"
						(effects
							(font
								(size 1.27 1.27)
							)
						)
					)
				)
				(pin passive line
					(at 30.48 -30.48 180)
					(length 3.81)
					(hide yes)
					(name "GND"
						(effects
							(font
								(size 1.27 1.27)
							)
						)
					)
					(number "D10"
						(effects
							(font
								(size 1.27 1.27)
							)
						)
					)
				)
				(pin passive line
					(at 30.48 -30.48 180)
					(length 3.81)
					(hide yes)
					(name "GND"
						(effects
							(font
								(size 1.27 1.27)
							)
						)
					)
					(number "D11"
						(effects
							(font
								(size 1.27 1.27)
							)
						)
					)
				)
				(pin passive line
					(at 30.48 -30.48 180)
					(length 3.81)
					(hide yes)
					(name "GND"
						(effects
							(font
								(size 1.27 1.27)
							)
						)
					)
					(number "D3"
						(effects
							(font
								(size 1.27 1.27)
							)
						)
					)
				)
				(pin passive line
					(at 30.48 -30.48 180)
					(length 3.81)
					(hide yes)
					(name "GND"
						(effects
							(font
								(size 1.27 1.27)
							)
						)
					)
					(number "D5"
						(effects
							(font
								(size 1.27 1.27)
							)
						)
					)
				)
				(pin passive line
					(at 30.48 -30.48 180)
					(length 3.81)
					(hide yes)
					(name "GND"
						(effects
							(font
								(size 1.27 1.27)
							)
						)
					)
					(number "E2"
						(effects
							(font
								(size 1.27 1.27)
							)
						)
					)
				)
				(pin passive line
					(at 30.48 -30.48 180)
					(length 3.81)
					(hide yes)
					(name "GND"
						(effects
							(font
								(size 1.27 1.27)
							)
						)
					)
					(number "E4"
						(effects
							(font
								(size 1.27 1.27)
							)
						)
					)
				)
				(pin passive line
					(at 30.48 -30.48 180)
					(length 3.81)
					(hide yes)
					(name "GND"
						(effects
							(font
								(size 1.27 1.27)
							)
						)
					)
					(number "F1"
						(effects
							(font
								(size 1.27 1.27)
							)
						)
					)
				)
				(pin passive line
					(at 30.48 -30.48 180)
					(length 3.81)
					(hide yes)
					(name "GND"
						(effects
							(font
								(size 1.27 1.27)
							)
						)
					)
					(number "F10"
						(effects
							(font
								(size 1.27 1.27)
							)
						)
					)
				)
				(pin passive line
					(at 30.48 -30.48 180)
					(length 3.81)
					(hide yes)
					(name "GND"
						(effects
							(font
								(size 1.27 1.27)
							)
						)
					)
					(number "F12"
						(effects
							(font
								(size 1.27 1.27)
							)
						)
					)
				)
				(pin passive line
					(at 30.48 -30.48 180)
					(length 3.81)
					(hide yes)
					(name "GND"
						(effects
							(font
								(size 1.27 1.27)
							)
						)
					)
					(number "F5"
						(effects
							(font
								(size 1.27 1.27)
							)
						)
					)
				)
				(pin passive line
					(at 30.48 -30.48 180)
					(length 3.81)
					(hide yes)
					(name "GND"
						(effects
							(font
								(size 1.27 1.27)
							)
						)
					)
					(number "F8"
						(effects
							(font
								(size 1.27 1.27)
							)
						)
					)
				)
				(pin passive line
					(at 30.48 -30.48 180)
					(length 3.81)
					(hide yes)
					(name "GND"
						(effects
							(font
								(size 1.27 1.27)
							)
						)
					)
					(number "G1"
						(effects
							(font
								(size 1.27 1.27)
							)
						)
					)
				)
				(pin passive line
					(at 30.48 -30.48 180)
					(length 3.81)
					(hide yes)
					(name "GND"
						(effects
							(font
								(size 1.27 1.27)
							)
						)
					)
					(number "G11"
						(effects
							(font
								(size 1.27 1.27)
							)
						)
					)
				)
				(pin passive line
					(at 30.48 -30.48 180)
					(length 3.81)
					(hide yes)
					(name "GND"
						(effects
							(font
								(size 1.27 1.27)
							)
						)
					)
					(number "G3"
						(effects
							(font
								(size 1.27 1.27)
							)
						)
					)
				)
				(pin passive line
					(at 30.48 -30.48 180)
					(length 3.81)
					(hide yes)
					(name "GND"
						(effects
							(font
								(size 1.27 1.27)
							)
						)
					)
					(number "G5"
						(effects
							(font
								(size 1.27 1.27)
							)
						)
					)
				)
				(pin passive line
					(at 30.48 -30.48 180)
					(length 3.81)
					(hide yes)
					(name "GND"
						(effects
							(font
								(size 1.27 1.27)
							)
						)
					)
					(number "G7"
						(effects
							(font
								(size 1.27 1.27)
							)
						)
					)
				)
				(pin passive line
					(at 30.48 -30.48 180)
					(length 3.81)
					(hide yes)
					(name "GND"
						(effects
							(font
								(size 1.27 1.27)
							)
						)
					)
					(number "H11"
						(effects
							(font
								(size 1.27 1.27)
							)
						)
					)
				)
				(pin passive line
					(at 30.48 -30.48 180)
					(length 3.81)
					(hide yes)
					(name "GND"
						(effects
							(font
								(size 1.27 1.27)
							)
						)
					)
					(number "H2"
						(effects
							(font
								(size 1.27 1.27)
							)
						)
					)
				)
				(pin passive line
					(at 30.48 -30.48 180)
					(length 3.81)
					(hide yes)
					(name "GND"
						(effects
							(font
								(size 1.27 1.27)
							)
						)
					)
					(number "H4"
						(effects
							(font
								(size 1.27 1.27)
							)
						)
					)
				)
				(pin passive line
					(at 30.48 -30.48 180)
					(length 3.81)
					(hide yes)
					(name "GND"
						(effects
							(font
								(size 1.27 1.27)
							)
						)
					)
					(number "J12"
						(effects
							(font
								(size 1.27 1.27)
							)
						)
					)
				)
				(pin passive line
					(at 30.48 -30.48 180)
					(length 3.81)
					(hide yes)
					(name "GND"
						(effects
							(font
								(size 1.27 1.27)
							)
						)
					)
					(number "J5"
						(effects
							(font
								(size 1.27 1.27)
							)
						)
					)
				)
				(pin passive line
					(at 30.48 -30.48 180)
					(length 3.81)
					(hide yes)
					(name "GND"
						(effects
							(font
								(size 1.27 1.27)
							)
						)
					)
					(number "K1"
						(effects
							(font
								(size 1.27 1.27)
							)
						)
					)
				)
				(pin passive line
					(at 30.48 -30.48 180)
					(length 3.81)
					(hide yes)
					(name "GND"
						(effects
							(font
								(size 1.27 1.27)
							)
						)
					)
					(number "K11"
						(effects
							(font
								(size 1.27 1.27)
							)
						)
					)
				)
				(pin passive line
					(at 30.48 -30.48 180)
					(length 3.81)
					(hide yes)
					(name "GND"
						(effects
							(font
								(size 1.27 1.27)
							)
						)
					)
					(number "K6"
						(effects
							(font
								(size 1.27 1.27)
							)
						)
					)
				)
				(pin passive line
					(at 30.48 -30.48 180)
					(length 3.81)
					(hide yes)
					(name "GND"
						(effects
							(font
								(size 1.27 1.27)
							)
						)
					)
					(number "L11"
						(effects
							(font
								(size 1.27 1.27)
							)
						)
					)
				)
				(pin passive line
					(at 30.48 -30.48 180)
					(length 3.81)
					(hide yes)
					(name "GND"
						(effects
							(font
								(size 1.27 1.27)
							)
						)
					)
					(number "L3"
						(effects
							(font
								(size 1.27 1.27)
							)
						)
					)
				)
				(pin passive line
					(at 30.48 -30.48 180)
					(length 3.81)
					(hide yes)
					(name "GND"
						(effects
							(font
								(size 1.27 1.27)
							)
						)
					)
					(number "L4"
						(effects
							(font
								(size 1.27 1.27)
							)
						)
					)
				)
				(pin passive line
					(at 30.48 -30.48 180)
					(length 3.81)
					(hide yes)
					(name "GND"
						(effects
							(font
								(size 1.27 1.27)
							)
						)
					)
					(number "L7"
						(effects
							(font
								(size 1.27 1.27)
							)
						)
					)
				)
				(pin passive line
					(at 30.48 -30.48 180)
					(length 3.81)
					(hide yes)
					(name "GND"
						(effects
							(font
								(size 1.27 1.27)
							)
						)
					)
					(number "M12"
						(effects
							(font
								(size 1.27 1.27)
							)
						)
					)
				)
				(pin passive line
					(at 30.48 -30.48 180)
					(length 3.81)
					(hide yes)
					(name "GND"
						(effects
							(font
								(size 1.27 1.27)
							)
						)
					)
					(number "M2"
						(effects
							(font
								(size 1.27 1.27)
							)
						)
					)
				)
				(pin passive line
					(at 30.48 -30.48 180)
					(length 3.81)
					(hide yes)
					(name "GND"
						(effects
							(font
								(size 1.27 1.27)
							)
						)
					)
					(number "M5"
						(effects
							(font
								(size 1.27 1.27)
							)
						)
					)
				)
			)
		)
	(symbol "antmicroInterfaceDriversReceiversTransceivers:PI3EQX16904GL"
			(exclude_from_sim no)
			(in_bom yes)
			(on_board yes)
			(property "Reference" "U"
				(at 35.56 -2.54 0)
				(effects
					(font
						(size 1.27 1.27)
						(thickness 0.15)
					)
					(justify left bottom)
				)
			)
			(property "Value" "PI3EQX16904GL"
				(at 35.56 -10.16 0)
				(effects
					(font
						(size 1.27 1.27)
						(thickness 0.15)
					)
					(justify left bottom)
					(hide yes)
				)
			)
			(property "Footprint" "antmicro-footprints:WQFN-42-1EP_3.5x9mm_P0.5mm"
				(at 35.56 -12.7 0)
				(effects
					(font
						(size 1.27 1.27)
						(thickness 0.15)
					)
					(justify left bottom)
					(hide yes)
				)
			)
			(property "Datasheet" "https://www.diodes.com/part/view/PI3EQX16904GL"
				(at 35.56 -15.24 0)
				(effects
					(font
						(size 1.27 1.27)
						(thickness 0.15)
					)
					(justify left bottom)
					(hide yes)
				)
			)
			(property "Description" "16Gbps 4-Channel ReDriver with Linear Equalization"
				(at 0 0 0)
				(effects
					(font
						(size 1.27 1.27)
					)
					(hide yes)
				)
			)
			(property "MPN" "PI3EQX16904GLZHEX"
				(at 35.56 -5.08 0)
				(effects
					(font
						(size 1.27 1.27)
						(thickness 0.15)
					)
					(justify left bottom)
				)
			)
			(property "Manufacturer" "Diodes Incorporated"
				(at 35.56 -7.62 0)
				(effects
					(font
						(size 1.27 1.27)
						(thickness 0.15)
					)
					(justify left bottom)
					(hide yes)
				)
			)
			(property "Author" "Antmicro"
				(at 35.56 -17.78 0)
				(effects
					(font
						(size 1.27 1.27)
						(thickness 0.15)
					)
					(justify left bottom)
					(hide yes)
				)
			)
			(property "License" "Apache-2.0"
				(at 35.56 -20.32 0)
				(effects
					(font
						(size 1.27 1.27)
						(thickness 0.15)
					)
					(justify left bottom)
					(hide yes)
				)
			)
			(property "ki_keywords" "SMT, IC"
				(at 0 0 0)
				(effects
					(font
						(size 1.27 1.27)
					)
					(hide yes)
				)
			)
			(symbol "PI3EQX16904GL_1_1"
				(rectangle
					(start 2.54 2.54)
					(end 20.32 -68.58)
					(stroke
						(width 0.254)
						(type default)
					)
					(fill
						(type background)
					)
				)
				(polyline
					(pts
						(xy 2.54 -2.54) (xy 20.32 -2.54)
					)
					(stroke
						(width 0.254)
						(type default)
					)
					(fill
						(type background)
					)
				)
				(polyline
					(pts
						(xy 2.54 -10.16) (xy 20.32 -10.16)
					)
					(stroke
						(width 0.254)
						(type default)
					)
					(fill
						(type background)
					)
				)
				(polyline
					(pts
						(xy 2.54 -17.78) (xy 20.32 -17.78)
					)
					(stroke
						(width 0.254)
						(type default)
					)
					(fill
						(type background)
					)
				)
				(polyline
					(pts
						(xy 2.54 -25.4) (xy 20.32 -25.4)
					)
					(stroke
						(width 0.254)
						(type default)
					)
					(fill
						(type background)
					)
				)
				(polyline
					(pts
						(xy 10.16 -6.35) (xy 12.7 -6.35) (xy 12.065 -5.715) (xy 12.7 -6.35) (xy 12.065 -6.985)
					)
					(stroke
						(width 0.254)
						(type default)
					)
					(fill
						(type background)
					)
				)
				(polyline
					(pts
						(xy 10.16 -13.97) (xy 12.7 -13.97) (xy 12.065 -13.335) (xy 12.7 -13.97) (xy 12.065 -14.605)
					)
					(stroke
						(width 0.254)
						(type default)
					)
					(fill
						(type background)
					)
				)
				(polyline
					(pts
						(xy 10.16 -21.59) (xy 12.7 -21.59) (xy 12.065 -20.955) (xy 12.7 -21.59) (xy 12.065 -22.225)
					)
					(stroke
						(width 0.254)
						(type default)
					)
					(fill
						(type background)
					)
				)
				(polyline
					(pts
						(xy 10.16 -29.21) (xy 12.7 -29.21) (xy 12.065 -28.575) (xy 12.7 -29.21) (xy 12.065 -29.845)
					)
					(stroke
						(width 0.254)
						(type default)
					)
					(fill
						(type background)
					)
				)
				(polyline
					(pts
						(xy 20.32 -33.02) (xy 2.54 -33.02)
					)
					(stroke
						(width 0.254)
						(type default)
					)
					(fill
						(type background)
					)
				)
				(pin power_in line
					(at 0 0 0)
					(length 2.54)
					(name "VCC"
						(effects
							(font
								(size 1.27 1.27)
							)
						)
					)
					(number "12"
						(effects
							(font
								(size 1.27 1.27)
							)
						)
					)
				)
				(pin passive line
					(at 0 0 0)
					(length 2.54)
					(hide yes)
					(name "VCC"
						(effects
							(font
								(size 1.27 1.27)
							)
						)
					)
					(number "15"
						(effects
							(font
								(size 1.27 1.27)
							)
						)
					)
				)
				(pin passive line
					(at 0 0 0)
					(length 2.54)
					(hide yes)
					(name "VCC"
						(effects
							(font
								(size 1.27 1.27)
							)
						)
					)
					(number "24"
						(effects
							(font
								(size 1.27 1.27)
							)
						)
					)
				)
				(pin passive line
					(at 0 0 0)
					(length 2.54)
					(hide yes)
					(name "VCC"
						(effects
							(font
								(size 1.27 1.27)
							)
						)
					)
					(number "27"
						(effects
							(font
								(size 1.27 1.27)
							)
						)
					)
				)
				(pin passive line
					(at 0 0 0)
					(length 2.54)
					(hide yes)
					(name "VCC"
						(effects
							(font
								(size 1.27 1.27)
							)
						)
					)
					(number "3"
						(effects
							(font
								(size 1.27 1.27)
							)
						)
					)
				)
				(pin passive line
					(at 0 0 0)
					(length 2.54)
					(hide yes)
					(name "VCC"
						(effects
							(font
								(size 1.27 1.27)
							)
						)
					)
					(number "30"
						(effects
							(font
								(size 1.27 1.27)
							)
						)
					)
				)
				(pin passive line
					(at 0 0 0)
					(length 2.54)
					(hide yes)
					(name "VCC"
						(effects
							(font
								(size 1.27 1.27)
							)
						)
					)
					(number "33"
						(effects
							(font
								(size 1.27 1.27)
							)
						)
					)
				)
				(pin passive line
					(at 0 0 0)
					(length 2.54)
					(hide yes)
					(name "VCC"
						(effects
							(font
								(size 1.27 1.27)
							)
						)
					)
					(number "36"
						(effects
							(font
								(size 1.27 1.27)
							)
						)
					)
				)
				(pin passive line
					(at 0 0 0)
					(length 2.54)
					(hide yes)
					(name "VCC"
						(effects
							(font
								(size 1.27 1.27)
							)
						)
					)
					(number "6"
						(effects
							(font
								(size 1.27 1.27)
							)
						)
					)
				)
				(pin passive line
					(at 0 0 0)
					(length 2.54)
					(hide yes)
					(name "VCC"
						(effects
							(font
								(size 1.27 1.27)
							)
						)
					)
					(number "9"
						(effects
							(font
								(size 1.27 1.27)
							)
						)
					)
				)
				(pin input line
					(at 0 -5.08 0)
					(length 2.54)
					(name "A0RX+"
						(effects
							(font
								(size 1.27 1.27)
							)
						)
					)
					(number "4"
						(effects
							(font
								(size 1.27 1.27)
							)
						)
					)
				)
				(pin input line
					(at 0 -7.62 0)
					(length 2.54)
					(name "A0RX-"
						(effects
							(font
								(size 1.27 1.27)
							)
						)
					)
					(number "5"
						(effects
							(font
								(size 1.27 1.27)
							)
						)
					)
				)
				(pin input line
					(at 0 -12.7 0)
					(length 2.54)
					(name "A1RX+"
						(effects
							(font
								(size 1.27 1.27)
							)
						)
					)
					(number "7"
						(effects
							(font
								(size 1.27 1.27)
							)
						)
					)
				)
				(pin input line
					(at 0 -15.24 0)
					(length 2.54)
					(name "A1RX-"
						(effects
							(font
								(size 1.27 1.27)
							)
						)
					)
					(number "8"
						(effects
							(font
								(size 1.27 1.27)
							)
						)
					)
				)
				(pin input line
					(at 0 -20.32 0)
					(length 2.54)
					(name "A2RX+"
						(effects
							(font
								(size 1.27 1.27)
							)
						)
					)
					(number "10"
						(effects
							(font
								(size 1.27 1.27)
							)
						)
					)
				)
				(pin input line
					(at 0 -22.86 0)
					(length 2.54)
					(name "A2RX-"
						(effects
							(font
								(size 1.27 1.27)
							)
						)
					)
					(number "11"
						(effects
							(font
								(size 1.27 1.27)
							)
						)
					)
				)
				(pin input line
					(at 0 -27.94 0)
					(length 2.54)
					(name "A3RX+"
						(effects
							(font
								(size 1.27 1.27)
							)
						)
					)
					(number "13"
						(effects
							(font
								(size 1.27 1.27)
							)
						)
					)
				)
				(pin input line
					(at 0 -30.48 0)
					(length 2.54)
					(name "A3RX-"
						(effects
							(font
								(size 1.27 1.27)
							)
						)
					)
					(number "14"
						(effects
							(font
								(size 1.27 1.27)
							)
						)
					)
				)
				(pin open_collector line
					(at 0 -35.56 0)
					(length 2.54)
					(name "SDA"
						(effects
							(font
								(size 1.27 1.27)
							)
						)
					)
					(number "18"
						(effects
							(font
								(size 1.27 1.27)
							)
						)
					)
				)
				(pin open_collector line
					(at 0 -38.1 0)
					(length 2.54)
					(name "SCL"
						(effects
							(font
								(size 1.27 1.27)
							)
						)
					)
					(number "19"
						(effects
							(font
								(size 1.27 1.27)
							)
						)
					)
				)
				(pin input line
					(at 0 -40.64 0)
					(length 2.54)
					(name "EN_{I2C}"
						(effects
							(font
								(size 1.27 1.27)
							)
						)
					)
					(number "21"
						(effects
							(font
								(size 1.27 1.27)
							)
						)
					)
				)
				(pin input line
					(at 0 -43.18 0)
					(length 2.54)
					(name "I2C_{DONE}"
						(effects
							(font
								(size 1.27 1.27)
							)
						)
					)
					(number "22"
						(effects
							(font
								(size 1.27 1.27)
							)
						)
					)
				)
				(pin input line
					(at 0 -45.72 0)
					(length 2.54)
					(name "~{I2C_{RESET}}"
						(effects
							(font
								(size 1.27 1.27)
							)
						)
					)
					(number "16"
						(effects
							(font
								(size 1.27 1.27)
							)
						)
					)
				)
				(pin passive line
					(at 0 -50.8 0)
					(length 2.54)
					(name "EQ0"
						(effects
							(font
								(size 1.27 1.27)
							)
						)
					)
					(number "39"
						(effects
							(font
								(size 1.27 1.27)
							)
						)
					)
				)
				(pin passive line
					(at 0 -53.34 0)
					(length 2.54)
					(name "EQ1"
						(effects
							(font
								(size 1.27 1.27)
							)
						)
					)
					(number "40"
						(effects
							(font
								(size 1.27 1.27)
							)
						)
					)
				)
				(pin passive line
					(at 0 -55.88 0)
					(length 2.54)
					(name "EQ2"
						(effects
							(font
								(size 1.27 1.27)
							)
						)
					)
					(number "1"
						(effects
							(font
								(size 1.27 1.27)
							)
						)
					)
				)
				(pin passive line
					(at 0 -60.96 0)
					(length 2.54)
					(name "FG0"
						(effects
							(font
								(size 1.27 1.27)
							)
						)
					)
					(number "37"
						(effects
							(font
								(size 1.27 1.27)
							)
						)
					)
				)
				(pin passive line
					(at 0 -63.5 0)
					(length 2.54)
					(name "FG1"
						(effects
							(font
								(size 1.27 1.27)
							)
						)
					)
					(number "38"
						(effects
							(font
								(size 1.27 1.27)
							)
						)
					)
				)
				(pin input line
					(at 0 -66.04 0)
					(length 2.54)
					(name "SW1"
						(effects
							(font
								(size 1.27 1.27)
							)
						)
					)
					(number "2"
						(effects
							(font
								(size 1.27 1.27)
							)
						)
					)
				)
				(pin input line
					(at 22.86 -5.08 180)
					(length 2.54)
					(name "A0TX+"
						(effects
							(font
								(size 1.27 1.27)
							)
						)
					)
					(number "35"
						(effects
							(font
								(size 1.27 1.27)
							)
						)
					)
				)
				(pin output line
					(at 22.86 -7.62 180)
					(length 2.54)
					(name "A0TX-"
						(effects
							(font
								(size 1.27 1.27)
							)
						)
					)
					(number "34"
						(effects
							(font
								(size 1.27 1.27)
							)
						)
					)
				)
				(pin input line
					(at 22.86 -12.7 180)
					(length 2.54)
					(name "A1TX+"
						(effects
							(font
								(size 1.27 1.27)
							)
						)
					)
					(number "32"
						(effects
							(font
								(size 1.27 1.27)
							)
						)
					)
				)
				(pin output line
					(at 22.86 -15.24 180)
					(length 2.54)
					(name "A1TX-"
						(effects
							(font
								(size 1.27 1.27)
							)
						)
					)
					(number "31"
						(effects
							(font
								(size 1.27 1.27)
							)
						)
					)
				)
				(pin input line
					(at 22.86 -20.32 180)
					(length 2.54)
					(name "A2TX+"
						(effects
							(font
								(size 1.27 1.27)
							)
						)
					)
					(number "29"
						(effects
							(font
								(size 1.27 1.27)
							)
						)
					)
				)
				(pin output line
					(at 22.86 -22.86 180)
					(length 2.54)
					(name "A2TX-"
						(effects
							(font
								(size 1.27 1.27)
							)
						)
					)
					(number "28"
						(effects
							(font
								(size 1.27 1.27)
							)
						)
					)
				)
				(pin input line
					(at 22.86 -27.94 180)
					(length 2.54)
					(name "A3TX+"
						(effects
							(font
								(size 1.27 1.27)
							)
						)
					)
					(number "26"
						(effects
							(font
								(size 1.27 1.27)
							)
						)
					)
				)
				(pin output line
					(at 22.86 -30.48 180)
					(length 2.54)
					(name "A3TX-"
						(effects
							(font
								(size 1.27 1.27)
							)
						)
					)
					(number "25"
						(effects
							(font
								(size 1.27 1.27)
							)
						)
					)
				)
				(pin input line
					(at 22.86 -35.56 180)
					(length 2.54)
					(name "~{PRSNT}"
						(effects
							(font
								(size 1.27 1.27)
							)
						)
					)
					(number "20"
						(effects
							(font
								(size 1.27 1.27)
							)
						)
					)
				)
				(pin input line
					(at 22.86 -40.64 180)
					(length 2.54)
					(name "RXDET"
						(effects
							(font
								(size 1.27 1.27)
							)
						)
					)
					(number "23"
						(effects
							(font
								(size 1.27 1.27)
							)
						)
					)
				)
				(pin passive line
					(at 22.86 -58.42 180)
					(length 2.54)
					(name "AD1"
						(effects
							(font
								(size 1.27 1.27)
							)
						)
					)
					(number "17"
						(effects
							(font
								(size 1.27 1.27)
							)
						)
					)
				)
				(pin passive line
					(at 22.86 -60.96 180)
					(length 2.54)
					(name "AD2"
						(effects
							(font
								(size 1.27 1.27)
							)
						)
					)
					(number "41"
						(effects
							(font
								(size 1.27 1.27)
							)
						)
					)
				)
				(pin passive line
					(at 22.86 -63.5 180)
					(length 2.54)
					(name "AD3"
						(effects
							(font
								(size 1.27 1.27)
							)
						)
					)
					(number "42"
						(effects
							(font
								(size 1.27 1.27)
							)
						)
					)
				)
				(pin power_in line
					(at 22.86 -66.04 180)
					(length 2.54)
					(name "GND"
						(effects
							(font
								(size 1.27 1.27)
							)
						)
					)
					(number "43"
						(effects
							(font
								(size 1.27 1.27)
							)
						)
					)
				)
			)
		)
	(symbol "antmicroInterfaceDriversReceiversTransceivers:Trans_SM453229-381N7Y"
			(pin_names
				(hide yes)
			)
			(exclude_from_sim no)
			(in_bom yes)
			(on_board yes)
			(property "Reference" "T"
				(at 26.67 -5.08 0)
				(effects
					(font
						(size 1.27 1.27)
						(thickness 0.15)
					)
					(justify left bottom)
				)
			)
			(property "Value" "Trans_SM453229-381N7Y"
				(at 26.67 -12.7 0)
				(effects
					(font
						(size 1.27 1.27)
						(thickness 0.15)
					)
					(justify left bottom)
					(hide yes)
				)
			)
			(property "Footprint" "antmicro-footprints:Trans_Eth_4.7x3.3mm"
				(at 26.67 -15.24 0)
				(effects
					(font
						(size 1.27 1.27)
						(thickness 0.15)
					)
					(justify left bottom)
					(hide yes)
				)
			)
			(property "Datasheet" "https://eu.mouser.com/datasheet/2/54/bourns_02132019_SM453229-381N7Y_datasheet-1532071.pdf"
				(at 26.67 -17.78 0)
				(effects
					(font
						(size 1.27 1.27)
						(thickness 0.15)
					)
					(justify left bottom)
					(hide yes)
				)
			)
			(property "Description" "10/100/1000 Base-T Chip LAN Transformer"
				(at 0 0 0)
				(effects
					(font
						(size 1.27 1.27)
					)
					(hide yes)
				)
			)
			(property "MPN" "SM453229-381N7Y"
				(at 26.67 -7.62 0)
				(effects
					(font
						(size 1.27 1.27)
						(thickness 0.15)
					)
					(justify left bottom)
				)
			)
			(property "Manufacturer" "Bourns"
				(at 26.67 -10.16 0)
				(effects
					(font
						(size 1.27 1.27)
						(thickness 0.15)
					)
					(justify left bottom)
					(hide yes)
				)
			)
			(property "Author" "Antmicro"
				(at 26.67 -20.32 0)
				(effects
					(font
						(size 1.27 1.27)
						(thickness 0.15)
					)
					(justify left bottom)
					(hide yes)
				)
			)
			(property "License" "Apache-2.0"
				(at 26.67 -22.86 0)
				(effects
					(font
						(size 1.27 1.27)
						(thickness 0.15)
					)
					(justify left bottom)
					(hide yes)
				)
			)
			(property "ki_keywords" "SMT, INTERFACE, ETHERNET, TRANSFORMER"
				(at 0 0 0)
				(effects
					(font
						(size 1.27 1.27)
					)
					(hide yes)
				)
			)
			(symbol "Trans_SM453229-381N7Y_1_1"
				(polyline
					(pts
						(xy 1.651 0) (xy 4.191 0)
					)
					(stroke
						(width 0)
						(type default)
					)
					(fill
						(type background)
					)
				)
				(polyline
					(pts
						(xy 1.651 -2.54) (xy 4.191 -2.54)
					)
					(stroke
						(width 0)
						(type default)
					)
					(fill
						(type background)
					)
				)
				(polyline
					(pts
						(xy 1.651 -5.08) (xy 4.191 -5.08)
					)
					(stroke
						(width 0)
						(type default)
					)
					(fill
						(type background)
					)
				)
				(arc
					(start 4.191 0)
					(mid 4.454 -0.635)
					(end 4.191 -1.27)
					(stroke
						(width 0)
						(type default)
					)
					(fill
						(type none)
					)
				)
				(arc
					(start 4.191 -1.27)
					(mid 4.454 -1.905)
					(end 4.191 -2.54)
					(stroke
						(width 0)
						(type default)
					)
					(fill
						(type none)
					)
				)
				(arc
					(start 4.191 -2.54)
					(mid 4.454 -3.175)
					(end 4.191 -3.81)
					(stroke
						(width 0)
						(type default)
					)
					(fill
						(type none)
					)
				)
				(arc
					(start 4.191 -3.81)
					(mid 4.454 -4.445)
					(end 4.191 -5.08)
					(stroke
						(width 0)
						(type default)
					)
					(fill
						(type none)
					)
				)
				(circle
					(center 4.064 -0.254)
					(radius 0.0001)
					(stroke
						(width 0.254)
						(type default)
					)
					(fill
						(type background)
					)
				)
				(polyline
					(pts
						(xy 4.826 -5.08) (xy 4.826 0)
					)
					(stroke
						(width 0.254)
						(type default)
					)
					(fill
						(type background)
					)
				)
				(polyline
					(pts
						(xy 5.334 -5.08) (xy 5.334 0)
					)
					(stroke
						(width 0.254)
						(type default)
					)
					(fill
						(type background)
					)
				)
				(polyline
					(pts
						(xy 5.969 0) (xy 8.509 0)
					)
					(stroke
						(width 0)
						(type default)
					)
					(fill
						(type background)
					)
				)
				(polyline
					(pts
						(xy 5.969 -2.54) (xy 8.509 -2.54)
					)
					(stroke
						(width 0)
						(type default)
					)
					(fill
						(type background)
					)
				)
				(circle
					(center 6.096 -0.254)
					(radius 0.0001)
					(stroke
						(width 0.254)
						(type default)
					)
					(fill
						(type background)
					)
				)
				(arc
					(start 5.969 -1.27)
					(mid 5.706 -0.635)
					(end 5.969 0)
					(stroke
						(width 0)
						(type default)
					)
					(fill
						(type none)
					)
				)
				(arc
					(start 5.969 -2.54)
					(mid 5.706 -1.905)
					(end 5.969 -1.27)
					(stroke
						(width 0)
						(type default)
					)
					(fill
						(type none)
					)
				)
				(arc
					(start 5.969 -3.81)
					(mid 5.706 -3.175)
					(end 5.969 -2.54)
					(stroke
						(width 0)
						(type default)
					)
					(fill
						(type none)
					)
				)
				(arc
					(start 5.969 -5.08)
					(mid 5.706 -4.445)
					(end 5.969 -3.81)
					(stroke
						(width 0)
						(type default)
					)
					(fill
						(type none)
					)
				)
				(polyline
					(pts
						(xy 8.509 -5.08) (xy 5.969 -5.08)
					)
					(stroke
						(width 0)
						(type default)
					)
					(fill
						(type background)
					)
				)
				(pin passive line
					(at 0 0 0)
					(length 2.54)
					(name "1"
						(effects
							(font
								(size 1.27 1.27)
							)
						)
					)
					(number "1"
						(effects
							(font
								(size 1.27 1.27)
							)
						)
					)
				)
				(pin passive line
					(at 0 -2.54 0)
					(length 2.54)
					(name "5"
						(effects
							(font
								(size 1.27 1.27)
							)
						)
					)
					(number "5"
						(effects
							(font
								(size 1.27 1.27)
							)
						)
					)
				)
				(pin passive line
					(at 0 -5.08 0)
					(length 2.54)
					(name "2"
						(effects
							(font
								(size 1.27 1.27)
							)
						)
					)
					(number "2"
						(effects
							(font
								(size 1.27 1.27)
							)
						)
					)
				)
				(pin passive line
					(at 10.16 0 180)
					(length 2.54)
					(name "6"
						(effects
							(font
								(size 1.27 1.27)
							)
						)
					)
					(number "6"
						(effects
							(font
								(size 1.27 1.27)
							)
						)
					)
				)
				(pin passive line
					(at 10.16 -2.54 180)
					(length 2.54)
					(name "3"
						(effects
							(font
								(size 1.27 1.27)
							)
						)
					)
					(number "3"
						(effects
							(font
								(size 1.27 1.27)
							)
						)
					)
				)
				(pin passive line
					(at 10.16 -5.08 180)
					(length 2.54)
					(name "7"
						(effects
							(font
								(size 1.27 1.27)
							)
						)
					)
					(number "7"
						(effects
							(font
								(size 1.27 1.27)
							)
						)
					)
				)
			)
		)
	(symbol "antmicroInterfaceIOExpanders:PCA9539AHF"
			(exclude_from_sim no)
			(in_bom yes)
			(on_board yes)
			(property "Reference" "U"
				(at 36.83 -3.81 0)
				(effects
					(font
						(size 1.27 1.27)
						(thickness 0.15)
					)
					(justify left bottom)
				)
			)
			(property "Value" "PCA9539AHF"
				(at 36.83 -8.89 0)
				(effects
					(font
						(size 1.27 1.27)
						(thickness 0.15)
					)
					(justify left bottom)
					(hide yes)
				)
			)
			(property "Footprint" "antmicro-footprints:QFN-24-1EP_4x4mm_P0.5_EP2.1x2.1mm"
				(at 36.83 -11.43 0)
				(effects
					(font
						(size 1.27 1.27)
						(thickness 0.15)
					)
					(justify left bottom)
					(hide yes)
				)
			)
			(property "Datasheet" "https://www.nxp.com/docs/en/data-sheet/PCA9539A.pdf"
				(at 36.83 -13.97 0)
				(effects
					(font
						(size 1.27 1.27)
						(thickness 0.15)
					)
					(justify left bottom)
					(hide yes)
				)
			)
			(property "Description" "I/O Expanders 16bit I2C IO Port"
				(at 0 0 0)
				(effects
					(font
						(size 1.27 1.27)
					)
					(hide yes)
				)
			)
			(property "MPN" "PCA9539AHF,128"
				(at 36.83 -6.35 0)
				(effects
					(font
						(size 1.27 1.27)
						(thickness 0.15)
					)
					(justify left bottom)
				)
			)
			(property "Manufacturer" "NXP"
				(at 36.83 -16.51 0)
				(effects
					(font
						(size 1.27 1.27)
						(thickness 0.15)
					)
					(justify left bottom)
					(hide yes)
				)
			)
			(property "Author" "Antmicro"
				(at 36.83 -19.05 0)
				(effects
					(font
						(size 1.27 1.27)
						(thickness 0.15)
					)
					(justify left bottom)
					(hide yes)
				)
			)
			(property "License" "Apache-2.0"
				(at 36.83 -21.59 0)
				(effects
					(font
						(size 1.27 1.27)
						(thickness 0.15)
					)
					(justify left bottom)
					(hide yes)
				)
			)
			(property "ki_keywords" "SMT, INTERFACE, IC, I2C"
				(at 0 0 0)
				(effects
					(font
						(size 1.27 1.27)
					)
					(hide yes)
				)
			)
			(property "ki_fp_filters" "VFQFN-16-1EP_3x3mm"
				(at 0 0 0)
				(effects
					(font
						(size 1.27 1.27)
					)
					(hide yes)
				)
			)
			(symbol "PCA9539AHF_1_1"
				(rectangle
					(start 2.54 2.54)
					(end 20.32 -43.18)
					(stroke
						(width 0.254)
						(type default)
					)
					(fill
						(type background)
					)
				)
				(pin power_in line
					(at 0 0 0)
					(length 2.54)
					(name "VDD"
						(effects
							(font
								(size 1.27 1.27)
							)
						)
					)
					(number "21"
						(effects
							(font
								(size 1.27 1.27)
							)
						)
					)
				)
				(pin bidirectional line
					(at 0 -5.08 0)
					(length 2.54)
					(name "SDA"
						(effects
							(font
								(size 1.27 1.27)
							)
						)
					)
					(number "20"
						(effects
							(font
								(size 1.27 1.27)
							)
						)
					)
				)
				(pin input line
					(at 0 -7.62 0)
					(length 2.54)
					(name "SCL"
						(effects
							(font
								(size 1.27 1.27)
							)
						)
					)
					(number "19"
						(effects
							(font
								(size 1.27 1.27)
							)
						)
					)
				)
				(pin output line
					(at 0 -10.16 0)
					(length 2.54)
					(name "~{INT}"
						(effects
							(font
								(size 1.27 1.27)
							)
						)
					)
					(number "22"
						(effects
							(font
								(size 1.27 1.27)
							)
						)
					)
				)
				(pin input line
					(at 0 -22.86 0)
					(length 2.54)
					(name "~{RESET}"
						(effects
							(font
								(size 1.27 1.27)
							)
						)
					)
					(number "24"
						(effects
							(font
								(size 1.27 1.27)
							)
						)
					)
				)
				(pin input line
					(at 0 -35.56 0)
					(length 2.54)
					(name "A0"
						(effects
							(font
								(size 1.27 1.27)
							)
						)
					)
					(number "18"
						(effects
							(font
								(size 1.27 1.27)
							)
						)
					)
				)
				(pin input line
					(at 0 -38.1 0)
					(length 2.54)
					(name "A1"
						(effects
							(font
								(size 1.27 1.27)
							)
						)
					)
					(number "23"
						(effects
							(font
								(size 1.27 1.27)
							)
						)
					)
				)
				(pin passive line
					(at 0 -40.64 0)
					(length 2.54)
					(hide yes)
					(name "GND"
						(effects
							(font
								(size 1.27 1.27)
							)
						)
					)
					(number "25"
						(effects
							(font
								(size 1.27 1.27)
							)
						)
					)
				)
				(pin power_in line
					(at 0 -40.64 0)
					(length 2.54)
					(name "GND"
						(effects
							(font
								(size 1.27 1.27)
							)
						)
					)
					(number "9"
						(effects
							(font
								(size 1.27 1.27)
							)
						)
					)
				)
				(pin bidirectional line
					(at 22.86 0 180)
					(length 2.54)
					(name "IO0_0"
						(effects
							(font
								(size 1.27 1.27)
							)
						)
					)
					(number "1"
						(effects
							(font
								(size 1.27 1.27)
							)
						)
					)
				)
				(pin bidirectional line
					(at 22.86 -2.54 180)
					(length 2.54)
					(name "IO0_1"
						(effects
							(font
								(size 1.27 1.27)
							)
						)
					)
					(number "2"
						(effects
							(font
								(size 1.27 1.27)
							)
						)
					)
				)
				(pin bidirectional line
					(at 22.86 -5.08 180)
					(length 2.54)
					(name "IO0_2"
						(effects
							(font
								(size 1.27 1.27)
							)
						)
					)
					(number "3"
						(effects
							(font
								(size 1.27 1.27)
							)
						)
					)
				)
				(pin bidirectional line
					(at 22.86 -7.62 180)
					(length 2.54)
					(name "IO0_3"
						(effects
							(font
								(size 1.27 1.27)
							)
						)
					)
					(number "4"
						(effects
							(font
								(size 1.27 1.27)
							)
						)
					)
				)
				(pin bidirectional line
					(at 22.86 -10.16 180)
					(length 2.54)
					(name "IO0_4"
						(effects
							(font
								(size 1.27 1.27)
							)
						)
					)
					(number "5"
						(effects
							(font
								(size 1.27 1.27)
							)
						)
					)
				)
				(pin bidirectional line
					(at 22.86 -12.7 180)
					(length 2.54)
					(name "IO0_5"
						(effects
							(font
								(size 1.27 1.27)
							)
						)
					)
					(number "6"
						(effects
							(font
								(size 1.27 1.27)
							)
						)
					)
				)
				(pin bidirectional line
					(at 22.86 -15.24 180)
					(length 2.54)
					(name "IO0_6"
						(effects
							(font
								(size 1.27 1.27)
							)
						)
					)
					(number "7"
						(effects
							(font
								(size 1.27 1.27)
							)
						)
					)
				)
				(pin bidirectional line
					(at 22.86 -17.78 180)
					(length 2.54)
					(name "IO0_7"
						(effects
							(font
								(size 1.27 1.27)
							)
						)
					)
					(number "8"
						(effects
							(font
								(size 1.27 1.27)
							)
						)
					)
				)
				(pin bidirectional line
					(at 22.86 -22.86 180)
					(length 2.54)
					(name "IO1_0"
						(effects
							(font
								(size 1.27 1.27)
							)
						)
					)
					(number "10"
						(effects
							(font
								(size 1.27 1.27)
							)
						)
					)
				)
				(pin bidirectional line
					(at 22.86 -25.4 180)
					(length 2.54)
					(name "IO1_1"
						(effects
							(font
								(size 1.27 1.27)
							)
						)
					)
					(number "11"
						(effects
							(font
								(size 1.27 1.27)
							)
						)
					)
				)
				(pin bidirectional line
					(at 22.86 -27.94 180)
					(length 2.54)
					(name "IO1_2"
						(effects
							(font
								(size 1.27 1.27)
							)
						)
					)
					(number "12"
						(effects
							(font
								(size 1.27 1.27)
							)
						)
					)
				)
				(pin bidirectional line
					(at 22.86 -30.48 180)
					(length 2.54)
					(name "IO1_3"
						(effects
							(font
								(size 1.27 1.27)
							)
						)
					)
					(number "13"
						(effects
							(font
								(size 1.27 1.27)
							)
						)
					)
				)
				(pin bidirectional line
					(at 22.86 -33.02 180)
					(length 2.54)
					(name "IO1_4"
						(effects
							(font
								(size 1.27 1.27)
							)
						)
					)
					(number "14"
						(effects
							(font
								(size 1.27 1.27)
							)
						)
					)
				)
				(pin bidirectional line
					(at 22.86 -35.56 180)
					(length 2.54)
					(name "IO1_5"
						(effects
							(font
								(size 1.27 1.27)
							)
						)
					)
					(number "15"
						(effects
							(font
								(size 1.27 1.27)
							)
						)
					)
				)
				(pin bidirectional line
					(at 22.86 -38.1 180)
					(length 2.54)
					(name "IO1_6"
						(effects
							(font
								(size 1.27 1.27)
							)
						)
					)
					(number "16"
						(effects
							(font
								(size 1.27 1.27)
							)
						)
					)
				)
				(pin bidirectional line
					(at 22.86 -40.64 180)
					(length 2.54)
					(name "IO1_7"
						(effects
							(font
								(size 1.27 1.27)
							)
						)
					)
					(number "17"
						(effects
							(font
								(size 1.27 1.27)
							)
						)
					)
				)
			)
		)
	(symbol "antmicroLEDIndicationDiscrete:LED_G_0603_LTST-C190GKT"
			(pin_numbers
				(hide yes)
			)
			(pin_names
				(hide yes)
			)
			(exclude_from_sim no)
			(in_bom yes)
			(on_board yes)
			(property "Reference" "D"
				(at 22.86 -2.54 0)
				(effects
					(font
						(size 1.27 1.27)
						(thickness 0.15)
					)
					(justify left bottom)
				)
			)
			(property "Value" "LED_G_0603_LTST-C190GKT"
				(at 22.86 -7.62 0)
				(effects
					(font
						(size 1.27 1.27)
						(thickness 0.15)
					)
					(justify left bottom)
					(hide yes)
				)
			)
			(property "Footprint" "antmicro-footprints:LED_0603_1608Metric_G"
				(at 22.86 -10.16 0)
				(effects
					(font
						(size 1.27 1.27)
						(thickness 0.15)
					)
					(justify left bottom)
					(hide yes)
				)
			)
			(property "Datasheet" "https://media.digikey.com/pdf/Data%20Sheets/Lite-On%20PDFs/LTST-C190GKT.pdf"
				(at 22.86 -12.7 0)
				(effects
					(font
						(size 1.27 1.27)
						(thickness 0.15)
					)
					(justify left bottom)
					(hide yes)
				)
			)
			(property "Description" "LED, Green, SMD, 0603, 20 mA, 2.1 V, 569 nm"
				(at 0 0 0)
				(effects
					(font
						(size 1.27 1.27)
					)
					(hide yes)
				)
			)
			(property "MPN" "LTST-C190GKT"
				(at 22.86 -15.24 0)
				(effects
					(font
						(size 1.27 1.27)
						(thickness 0.15)
					)
					(justify left bottom)
					(hide yes)
				)
			)
			(property "Manufacturer" "Lite-On"
				(at 22.86 -17.78 0)
				(effects
					(font
						(size 1.27 1.27)
						(thickness 0.15)
					)
					(justify left bottom)
					(hide yes)
				)
			)
			(property "Public" "False"
				(at 20.32 -17.78 0)
				(effects
					(font
						(size 1.27 1.27)
					)
					(justify left bottom)
					(hide yes)
				)
			)
			(property "Color" "Green"
				(at 22.86 -5.08 0)
				(effects
					(font
						(size 1.27 1.27)
					)
					(justify left bottom)
				)
			)
			(property "Author" "Antmicro"
				(at 22.86 -20.32 0)
				(effects
					(font
						(size 1.27 1.27)
						(thickness 0.15)
					)
					(justify left bottom)
					(hide yes)
				)
			)
			(property "License" "Apache-2.0"
				(at 22.86 -22.86 0)
				(effects
					(font
						(size 1.27 1.27)
						(thickness 0.15)
					)
					(justify left bottom)
					(hide yes)
				)
			)
			(property "ki_keywords" "SMT, DIODE, SEMICONDUCTOR, LED"
				(at 0 0 0)
				(effects
					(font
						(size 1.27 1.27)
					)
					(hide yes)
				)
			)
			(symbol "LED_G_0603_LTST-C190GKT_0_1"
				(polyline
					(pts
						(xy 1.905 0) (xy 0.635 0)
					)
					(stroke
						(width 0)
						(type default)
					)
					(fill
						(type none)
					)
				)
				(polyline
					(pts
						(xy 4.445 0) (xy 3.175 0)
					)
					(stroke
						(width 0)
						(type default)
					)
					(fill
						(type none)
					)
				)
			)
			(symbol "LED_G_0603_LTST-C190GKT_1_1"
				(polyline
					(pts
						(xy 1.143 2.286) (xy 1.143 1.778) (xy 1.143 2.286) (xy 1.651 2.286) (xy 1.143 2.286) (xy 2.159 1.27)
					)
					(stroke
						(width 0.254)
						(type default)
					)
					(fill
						(type none)
					)
				)
				(polyline
					(pts
						(xy 1.778 1.016) (xy 1.778 -1.016)
					)
					(stroke
						(width 0.254)
						(type default)
					)
					(fill
						(type none)
					)
				)
				(polyline
					(pts
						(xy 2.159 2.54) (xy 2.159 2.032) (xy 2.159 2.54) (xy 2.667 2.54) (xy 2.159 2.54) (xy 3.048 1.651)
					)
					(stroke
						(width 0.254)
						(type default)
					)
					(fill
						(type none)
					)
				)
				(polyline
					(pts
						(xy 3.302 1.016) (xy 3.302 -1.016) (xy 1.778 0) (xy 3.302 1.016)
					)
					(stroke
						(width 0.254)
						(type default)
					)
					(fill
						(type outline)
					)
				)
				(pin passive line
					(at 0 0 0)
					(length 0.635)
					(name "C"
						(effects
							(font
								(size 1.27 1.27)
							)
						)
					)
					(number "1"
						(effects
							(font
								(size 1.27 1.27)
							)
						)
					)
				)
				(pin passive line
					(at 5.08 0 180)
					(length 0.635)
					(name "A"
						(effects
							(font
								(size 1.27 1.27)
							)
						)
					)
					(number "2"
						(effects
							(font
								(size 1.27 1.27)
							)
						)
					)
				)
			)
		)
	(symbol "antmicroLEDIndicationDiscrete:LED_RGB_PLCC4_ASMB_MTB1_0A3A2"
			(exclude_from_sim no)
			(in_bom yes)
			(on_board yes)
			(property "Reference" "D"
				(at 27.94 -2.54 0)
				(effects
					(font
						(size 1.27 1.27)
					)
					(justify left bottom)
				)
			)
			(property "Value" "LED_RGB_PLCC4_ASMB_MTB1_0A3A2"
				(at 27.94 -7.62 0)
				(effects
					(font
						(size 1.27 1.27)
					)
					(justify left bottom)
					(hide yes)
				)
			)
			(property "Footprint" "antmicro-footprints:PLCC4_3.2x2.8mm"
				(at 27.94 -10.16 0)
				(effects
					(font
						(size 1.27 1.27)
					)
					(justify left bottom)
					(hide yes)
				)
			)
			(property "Datasheet" "https://docs.broadcom.com/doc/AV02-4194EN"
				(at 27.94 -12.7 0)
				(effects
					(font
						(size 1.27 1.27)
					)
					(justify left bottom)
					(hide yes)
				)
			)
			(property "Description" "LED, RGB, SMD, PLCC-4, R 20 mA, G 20 mA, B 20 mA, R 2.1 V, G 3.1 V, B 3.1 V, Common Anode"
				(at 0 0 0)
				(effects
					(font
						(size 1.27 1.27)
					)
					(hide yes)
				)
			)
			(property "MPN" "ASMB-MTB1-0A3A2"
				(at 27.94 -15.24 0)
				(effects
					(font
						(size 1.27 1.27)
					)
					(justify left bottom)
					(hide yes)
				)
			)
			(property "Manufacturer" "Avago Technologies"
				(at 27.94 -17.78 0)
				(effects
					(font
						(size 1.27 1.27)
					)
					(justify left bottom)
					(hide yes)
				)
			)
			(property "Color" "R, G, B"
				(at 27.94 -5.08 0)
				(effects
					(font
						(size 1.27 1.27)
					)
					(justify left bottom)
				)
			)
			(property "Author" "Antmicro"
				(at 27.94 -20.32 0)
				(effects
					(font
						(size 1.27 1.27)
					)
					(justify left bottom)
					(hide yes)
				)
			)
			(property "License" "Apache-2.0"
				(at 27.94 -22.86 0)
				(effects
					(font
						(size 1.27 1.27)
					)
					(justify left bottom)
					(hide yes)
				)
			)
			(property "ki_keywords" "SMT, DIODE, SEMICONDUCTOR, LED"
				(at 0 0 0)
				(effects
					(font
						(size 1.27 1.27)
					)
					(hide yes)
				)
			)
			(symbol "LED_RGB_PLCC4_ASMB_MTB1_0A3A2_1_1"
				(rectangle
					(start 2.54 -11.43)
					(end 16.51 3.81)
					(stroke
						(width 0.254)
						(type default)
					)
					(fill
						(type background)
					)
				)
				(polyline
					(pts
						(xy 6.35 0) (xy 8.89 0)
					)
					(stroke
						(width 0.254)
						(type default)
					)
					(fill
						(type none)
					)
				)
				(polyline
					(pts
						(xy 6.35 -3.81) (xy 8.89 -3.81)
					)
					(stroke
						(width 0.254)
						(type default)
					)
					(fill
						(type none)
					)
				)
				(polyline
					(pts
						(xy 6.35 -7.62) (xy 8.89 -7.62)
					)
					(stroke
						(width 0.254)
						(type default)
					)
					(fill
						(type none)
					)
				)
				(polyline
					(pts
						(xy 8.128 2.286) (xy 8.128 1.778) (xy 8.128 2.286) (xy 8.636 2.286) (xy 8.128 2.286) (xy 9.144 1.27)
					)
					(stroke
						(width 0.254)
						(type default)
					)
					(fill
						(type none)
					)
				)
				(polyline
					(pts
						(xy 8.128 -1.524) (xy 8.128 -2.032) (xy 8.128 -1.524) (xy 8.636 -1.524) (xy 8.128 -1.524) (xy 9.144 -2.54)
					)
					(stroke
						(width 0.254)
						(type default)
					)
					(fill
						(type none)
					)
				)
				(polyline
					(pts
						(xy 8.128 -5.334) (xy 8.128 -5.842) (xy 8.128 -5.334) (xy 8.636 -5.334) (xy 8.128 -5.334) (xy 9.144 -6.35)
					)
					(stroke
						(width 0.254)
						(type default)
					)
					(fill
						(type none)
					)
				)
				(polyline
					(pts
						(xy 8.763 1.016) (xy 8.763 -1.016)
					)
					(stroke
						(width 0.254)
						(type default)
					)
					(fill
						(type none)
					)
				)
				(polyline
					(pts
						(xy 8.763 -2.794) (xy 8.763 -4.826)
					)
					(stroke
						(width 0.254)
						(type default)
					)
					(fill
						(type none)
					)
				)
				(polyline
					(pts
						(xy 8.763 -6.604) (xy 8.763 -8.636)
					)
					(stroke
						(width 0.254)
						(type default)
					)
					(fill
						(type none)
					)
				)
				(polyline
					(pts
						(xy 9.144 2.54) (xy 9.144 2.032) (xy 9.144 2.54) (xy 9.652 2.54) (xy 9.144 2.54) (xy 10.033 1.651)
					)
					(stroke
						(width 0.254)
						(type default)
					)
					(fill
						(type none)
					)
				)
				(polyline
					(pts
						(xy 9.144 -1.27) (xy 9.144 -1.778) (xy 9.144 -1.27) (xy 9.652 -1.27) (xy 9.144 -1.27) (xy 10.033 -2.159)
					)
					(stroke
						(width 0.254)
						(type default)
					)
					(fill
						(type none)
					)
				)
				(polyline
					(pts
						(xy 9.144 -5.08) (xy 9.144 -5.588) (xy 9.144 -5.08) (xy 9.652 -5.08) (xy 9.144 -5.08) (xy 10.033 -5.969)
					)
					(stroke
						(width 0.254)
						(type default)
					)
					(fill
						(type none)
					)
				)
				(polyline
					(pts
						(xy 10.16 -3.81) (xy 12.7 -3.81) (xy 12.7 0) (xy 10.16 0)
					)
					(stroke
						(width 0.254)
						(type default)
					)
					(fill
						(type none)
					)
				)
				(polyline
					(pts
						(xy 10.287 1.016) (xy 10.287 -1.016) (xy 8.763 0) (xy 10.287 1.016)
					)
					(stroke
						(width 0.254)
						(type default)
					)
					(fill
						(type outline)
					)
				)
				(polyline
					(pts
						(xy 10.287 -2.794) (xy 10.287 -4.826) (xy 8.763 -3.81) (xy 10.287 -2.794)
					)
					(stroke
						(width 0.254)
						(type default)
					)
					(fill
						(type outline)
					)
				)
				(polyline
					(pts
						(xy 10.287 -6.604) (xy 10.287 -8.636) (xy 8.763 -7.62) (xy 10.287 -6.604)
					)
					(stroke
						(width 0.254)
						(type default)
					)
					(fill
						(type outline)
					)
				)
				(polyline
					(pts
						(xy 12.7 -3.81) (xy 13.97 -3.81)
					)
					(stroke
						(width 0.254)
						(type default)
					)
					(fill
						(type none)
					)
				)
				(polyline
					(pts
						(xy 12.7 -3.81) (xy 12.7 -7.62) (xy 10.16 -7.62)
					)
					(stroke
						(width 0.254)
						(type default)
					)
					(fill
						(type none)
					)
				)
				(pin passive line
					(at 0 0 0)
					(length 2.54)
					(name "C_{R}"
						(effects
							(font
								(size 1.27 1.27)
							)
						)
					)
					(number "1"
						(effects
							(font
								(size 1.27 1.27)
							)
						)
					)
				)
				(pin passive line
					(at 0 -3.81 0)
					(length 2.54)
					(name "C_{G}"
						(effects
							(font
								(size 1.27 1.27)
							)
						)
					)
					(number "2"
						(effects
							(font
								(size 1.27 1.27)
							)
						)
					)
				)
				(pin passive line
					(at 0 -7.62 0)
					(length 2.54)
					(name "C_{B}"
						(effects
							(font
								(size 1.27 1.27)
							)
						)
					)
					(number "3"
						(effects
							(font
								(size 1.27 1.27)
							)
						)
					)
				)
				(pin passive line
					(at 19.05 -3.81 180)
					(length 2.54)
					(name "A"
						(effects
							(font
								(size 1.27 1.27)
							)
						)
					)
					(number "4"
						(effects
							(font
								(size 1.27 1.27)
							)
						)
					)
				)
			)
		)
	(symbol "antmicroLEDIndicationDiscrete:LED_Y_0603_LTST-C191KSKT"
			(pin_numbers
				(hide yes)
			)
			(pin_names
				(hide yes)
			)
			(exclude_from_sim no)
			(in_bom yes)
			(on_board yes)
			(property "Reference" "D"
				(at 22.86 -2.54 0)
				(effects
					(font
						(size 1.27 1.27)
						(thickness 0.15)
					)
					(justify left bottom)
				)
			)
			(property "Value" "LED_Y_0603_LTST-C191KSKT"
				(at 22.86 -7.62 0)
				(effects
					(font
						(size 1.27 1.27)
						(thickness 0.15)
					)
					(justify left bottom)
					(hide yes)
				)
			)
			(property "Footprint" "antmicro-footprints:LED_0603_1608Metric_Y"
				(at 22.86 -10.16 0)
				(effects
					(font
						(size 1.27 1.27)
						(thickness 0.15)
					)
					(justify left bottom)
					(hide yes)
				)
			)
			(property "Datasheet" "https://optoelectronics.liteon.com/upload/download/DS22-2000-224/LTST-C191KSKT.PDF"
				(at 22.86 -12.7 0)
				(effects
					(font
						(size 1.27 1.27)
						(thickness 0.15)
					)
					(justify left bottom)
					(hide yes)
				)
			)
			(property "Description" "LED, Yellow, SMD, 0603, 30 mA, 2.1 V, 588 nm"
				(at 0 0 0)
				(effects
					(font
						(size 1.27 1.27)
					)
					(hide yes)
				)
			)
			(property "MPN" "LTST-C191KSKT"
				(at 22.86 -15.24 0)
				(effects
					(font
						(size 1.27 1.27)
						(thickness 0.15)
					)
					(justify left bottom)
					(hide yes)
				)
			)
			(property "Manufacturer" "Lite-On"
				(at 22.86 -17.78 0)
				(effects
					(font
						(size 1.27 1.27)
						(thickness 0.15)
					)
					(justify left bottom)
					(hide yes)
				)
			)
			(property "Color" "Yellow"
				(at 22.86 -5.08 0)
				(effects
					(font
						(size 1.27 1.27)
					)
					(justify left bottom)
				)
			)
			(property "Author" "Antmicro"
				(at 22.86 -20.32 0)
				(effects
					(font
						(size 1.27 1.27)
						(thickness 0.15)
					)
					(justify left bottom)
					(hide yes)
				)
			)
			(property "License" "Apache-2.0"
				(at 22.86 -22.86 0)
				(effects
					(font
						(size 1.27 1.27)
						(thickness 0.15)
					)
					(justify left bottom)
					(hide yes)
				)
			)
			(property "ki_keywords" "SMT, DIODE, SEMICONDUCTOR, LED"
				(at 0 0 0)
				(effects
					(font
						(size 1.27 1.27)
					)
					(hide yes)
				)
			)
			(symbol "LED_Y_0603_LTST-C191KSKT_0_1"
				(polyline
					(pts
						(xy 1.905 0) (xy 0.635 0)
					)
					(stroke
						(width 0)
						(type default)
					)
					(fill
						(type none)
					)
				)
				(polyline
					(pts
						(xy 4.445 0) (xy 3.175 0)
					)
					(stroke
						(width 0)
						(type default)
					)
					(fill
						(type none)
					)
				)
			)
			(symbol "LED_Y_0603_LTST-C191KSKT_1_1"
				(polyline
					(pts
						(xy 1.143 2.286) (xy 1.143 1.778) (xy 1.143 2.286) (xy 1.651 2.286) (xy 1.143 2.286) (xy 2.159 1.27)
					)
					(stroke
						(width 0.254)
						(type default)
					)
					(fill
						(type none)
					)
				)
				(polyline
					(pts
						(xy 1.778 1.016) (xy 1.778 -1.016)
					)
					(stroke
						(width 0.254)
						(type default)
					)
					(fill
						(type none)
					)
				)
				(polyline
					(pts
						(xy 2.159 2.54) (xy 2.159 2.032) (xy 2.159 2.54) (xy 2.667 2.54) (xy 2.159 2.54) (xy 3.048 1.651)
					)
					(stroke
						(width 0.254)
						(type default)
					)
					(fill
						(type none)
					)
				)
				(polyline
					(pts
						(xy 3.302 1.016) (xy 3.302 -1.016) (xy 1.778 0) (xy 3.302 1.016)
					)
					(stroke
						(width 0.254)
						(type default)
					)
					(fill
						(type outline)
					)
				)
				(pin passive line
					(at 0 0 0)
					(length 0.635)
					(name "C"
						(effects
							(font
								(size 1.27 1.27)
							)
						)
					)
					(number "1"
						(effects
							(font
								(size 1.27 1.27)
							)
						)
					)
				)
				(pin passive line
					(at 5.08 0 180)
					(length 0.635)
					(name "A"
						(effects
							(font
								(size 1.27 1.27)
							)
						)
					)
					(number "2"
						(effects
							(font
								(size 1.27 1.27)
							)
						)
					)
				)
			)
		)
	(symbol "antmicroLogicGatesandInverters:74AUP2G132"
			(exclude_from_sim no)
			(in_bom yes)
			(on_board yes)
			(property "Reference" "U"
				(at 45.72 -5.08 0)
				(effects
					(font
						(size 1.27 1.27)
						(thickness 0.15)
					)
					(justify left bottom)
				)
			)
			(property "Value" "74AUP2G132"
				(at 45.72 -10.16 0)
				(effects
					(font
						(size 1.27 1.27)
						(thickness 0.15)
					)
					(justify left bottom)
					(hide yes)
				)
			)
			(property "Footprint" "antmicro-footprints:VSSOP-8_2.3x2mm_P0.5mm"
				(at 45.72 -12.7 0)
				(effects
					(font
						(size 1.27 1.27)
						(thickness 0.15)
					)
					(justify left bottom)
					(hide yes)
				)
			)
			(property "Datasheet" "https://assets.nexperia.com/documents/data-sheet/74AUP2G132.pdf"
				(at 45.72 -15.24 0)
				(effects
					(font
						(size 1.27 1.27)
						(thickness 0.15)
					)
					(justify left bottom)
					(hide yes)
				)
			)
			(property "Description" "Low-power dual 2-input NAND Schmitt trigger"
				(at 0 0 0)
				(effects
					(font
						(size 1.27 1.27)
					)
					(hide yes)
				)
			)
			(property "Manufacturer" "Nexperia"
				(at 45.72 -17.78 0)
				(effects
					(font
						(size 1.27 1.27)
						(thickness 0.15)
					)
					(justify left bottom)
					(hide yes)
				)
			)
			(property "MPN" "74AUP2G132"
				(at 45.72 -7.62 0)
				(effects
					(font
						(size 1.27 1.27)
						(thickness 0.15)
					)
					(justify left bottom)
				)
			)
			(property "Author" "Antmicro"
				(at 45.72 -20.32 0)
				(effects
					(font
						(size 1.27 1.27)
						(thickness 0.15)
					)
					(justify left bottom)
					(hide yes)
				)
			)
			(property "License" "Apache-2.0"
				(at 45.72 -22.86 0)
				(effects
					(font
						(size 1.27 1.27)
						(thickness 0.15)
					)
					(justify left bottom)
					(hide yes)
				)
			)
			(property "ki_keywords" "SMT, LOGIC, IC, GATE"
				(at 0 0 0)
				(effects
					(font
						(size 1.27 1.27)
					)
					(hide yes)
				)
			)
			(symbol "74AUP2G132_1_1"
				(rectangle
					(start 2.54 1.27)
					(end 15.24 -13.97)
					(stroke
						(width 0.254)
						(type default)
					)
					(fill
						(type background)
					)
				)
				(polyline
					(pts
						(xy 6.985 -3.048) (xy 6.477 -3.048)
					)
					(stroke
						(width 0.254)
						(type default)
					)
					(fill
						(type background)
					)
				)
				(polyline
					(pts
						(xy 6.985 -5.08) (xy 6.477 -5.08)
					)
					(stroke
						(width 0.254)
						(type default)
					)
					(fill
						(type background)
					)
				)
				(polyline
					(pts
						(xy 6.985 -8.128) (xy 6.477 -8.128)
					)
					(stroke
						(width 0.254)
						(type default)
					)
					(fill
						(type background)
					)
				)
				(polyline
					(pts
						(xy 6.985 -10.16) (xy 6.477 -10.16)
					)
					(stroke
						(width 0.254)
						(type default)
					)
					(fill
						(type background)
					)
				)
				(polyline
					(pts
						(xy 8.128 -3.429) (xy 8.128 -4.699)
					)
					(stroke
						(width 0.254)
						(type default)
					)
					(fill
						(type background)
					)
				)
				(polyline
					(pts
						(xy 8.128 -8.509) (xy 8.128 -9.779)
					)
					(stroke
						(width 0.254)
						(type default)
					)
					(fill
						(type background)
					)
				)
				(arc
					(start 10.0415 -4.0555)
					(mid 9.5919 -5.1386)
					(end 8.509 -5.588)
					(stroke
						(width 0.254)
						(type default)
					)
					(fill
						(type background)
					)
				)
				(arc
					(start 10.0415 -9.1355)
					(mid 9.5919 -10.2186)
					(end 8.509 -10.668)
					(stroke
						(width 0.254)
						(type default)
					)
					(fill
						(type background)
					)
				)
				(arc
					(start 8.509 -2.54)
					(mid 9.5859 -2.9835)
					(end 10.0415 -4.0555)
					(stroke
						(width 0.254)
						(type default)
					)
					(fill
						(type background)
					)
				)
				(arc
					(start 8.509 -7.62)
					(mid 9.5861 -8.0632)
					(end 10.0415 -9.1355)
					(stroke
						(width 0.254)
						(type default)
					)
					(fill
						(type background)
					)
				)
				(polyline
					(pts
						(xy 8.509 -2.54) (xy 6.985 -2.54) (xy 6.985 -5.588) (xy 8.509 -5.588)
					)
					(stroke
						(width 0.254)
						(type default)
					)
					(fill
						(type background)
					)
				)
				(polyline
					(pts
						(xy 8.509 -3.429) (xy 8.509 -4.699)
					)
					(stroke
						(width 0.254)
						(type default)
					)
					(fill
						(type background)
					)
				)
				(polyline
					(pts
						(xy 8.509 -4.699) (xy 7.62 -4.699)
					)
					(stroke
						(width 0.254)
						(type default)
					)
					(fill
						(type background)
					)
				)
				(polyline
					(pts
						(xy 8.509 -7.62) (xy 6.985 -7.62) (xy 6.985 -10.668) (xy 8.509 -10.668)
					)
					(stroke
						(width 0.254)
						(type default)
					)
					(fill
						(type background)
					)
				)
				(polyline
					(pts
						(xy 8.509 -8.509) (xy 8.509 -9.779)
					)
					(stroke
						(width 0.254)
						(type default)
					)
					(fill
						(type background)
					)
				)
				(polyline
					(pts
						(xy 8.509 -9.779) (xy 7.62 -9.779)
					)
					(stroke
						(width 0.254)
						(type default)
					)
					(fill
						(type background)
					)
				)
				(polyline
					(pts
						(xy 9.017 -3.429) (xy 8.128 -3.429)
					)
					(stroke
						(width 0.254)
						(type default)
					)
					(fill
						(type background)
					)
				)
				(polyline
					(pts
						(xy 9.017 -8.509) (xy 8.128 -8.509)
					)
					(stroke
						(width 0.254)
						(type default)
					)
					(fill
						(type background)
					)
				)
				(circle
					(center 10.287 -4.064)
					(radius 0.254)
					(stroke
						(width 0.254)
						(type default)
					)
					(fill
						(type background)
					)
				)
				(circle
					(center 10.287 -9.144)
					(radius 0.254)
					(stroke
						(width 0.254)
						(type default)
					)
					(fill
						(type background)
					)
				)
				(polyline
					(pts
						(xy 10.541 -9.144) (xy 11.176 -9.144) (xy 11.176 -7.874) (xy 11.557 -7.874)
					)
					(stroke
						(width 0.254)
						(type default)
					)
					(fill
						(type background)
					)
				)
				(polyline
					(pts
						(xy 10.668 -4.064) (xy 11.303 -4.064) (xy 11.303 -2.794) (xy 11.684 -2.794)
					)
					(stroke
						(width 0.254)
						(type default)
					)
					(fill
						(type background)
					)
				)
				(text ""
					(at 2.54 -3.048 0)
					(effects
						(font
							(size 1.27 1.27)
							(thickness 0.15)
						)
						(justify left bottom)
					)
				)
				(pin power_in line
					(at 0 0 0)
					(length 2.54)
					(name "VCC"
						(effects
							(font
								(size 1.27 1.27)
							)
						)
					)
					(number "8"
						(effects
							(font
								(size 1.27 1.27)
							)
						)
					)
				)
				(pin input line
					(at 0 -2.54 0)
					(length 2.54)
					(name "1A"
						(effects
							(font
								(size 1.27 1.27)
							)
						)
					)
					(number "1"
						(effects
							(font
								(size 1.27 1.27)
							)
						)
					)
				)
				(pin input line
					(at 0 -5.08 0)
					(length 2.54)
					(name "1B"
						(effects
							(font
								(size 1.27 1.27)
							)
						)
					)
					(number "2"
						(effects
							(font
								(size 1.27 1.27)
							)
						)
					)
				)
				(pin input line
					(at 0 -7.62 0)
					(length 2.54)
					(name "2A"
						(effects
							(font
								(size 1.27 1.27)
							)
						)
					)
					(number "5"
						(effects
							(font
								(size 1.27 1.27)
							)
						)
					)
				)
				(pin input line
					(at 0 -10.16 0)
					(length 2.54)
					(name "2B"
						(effects
							(font
								(size 1.27 1.27)
							)
						)
					)
					(number "6"
						(effects
							(font
								(size 1.27 1.27)
							)
						)
					)
				)
				(pin power_in line
					(at 0 -12.7 0)
					(length 2.54)
					(name "GND"
						(effects
							(font
								(size 1.27 1.27)
							)
						)
					)
					(number "4"
						(effects
							(font
								(size 1.27 1.27)
							)
						)
					)
				)
				(pin output line
					(at 17.78 -2.54 180)
					(length 2.54)
					(name "1Y"
						(effects
							(font
								(size 1.27 1.27)
							)
						)
					)
					(number "7"
						(effects
							(font
								(size 1.27 1.27)
							)
						)
					)
				)
				(pin output line
					(at 17.78 -7.62 180)
					(length 2.54)
					(name "2Y"
						(effects
							(font
								(size 1.27 1.27)
							)
						)
					)
					(number "3"
						(effects
							(font
								(size 1.27 1.27)
							)
						)
					)
				)
			)
		)
	(symbol "antmicroLogicTranslatorsLevelShifters:NTS0102_TSSOP"
			(exclude_from_sim no)
			(in_bom yes)
			(on_board yes)
			(property "Reference" "U"
				(at 35.56 -3.81 0)
				(effects
					(font
						(size 1.27 1.27)
						(thickness 0.15)
					)
					(justify left bottom)
				)
			)
			(property "Value" "NTS0102_TSSOP"
				(at 35.56 -6.35 0)
				(effects
					(font
						(size 1.27 1.27)
						(thickness 0.15)
					)
					(justify left bottom)
					(hide yes)
				)
			)
			(property "Footprint" "antmicro-footprints:TSSOP-8_3x3mm_P0.65mm"
				(at 35.56 -8.89 0)
				(effects
					(font
						(size 1.27 1.27)
						(thickness 0.15)
					)
					(justify left bottom)
					(hide yes)
				)
			)
			(property "Datasheet" "https://www.mouser.com/datasheet/2/302/NTS0102-1127324.pdf"
				(at 35.56 -11.43 0)
				(effects
					(font
						(size 1.27 1.27)
						(thickness 0.15)
					)
					(justify left bottom)
					(hide yes)
				)
			)
			(property "Description" "Transceiver, 1.65 V to 3.6 V, TSSOP-8"
				(at 0 0 0)
				(effects
					(font
						(size 1.27 1.27)
					)
					(hide yes)
				)
			)
			(property "MPN" "NTS0102DP"
				(at 35.56 -13.97 0)
				(effects
					(font
						(size 1.27 1.27)
						(thickness 0.15)
					)
					(justify left bottom)
				)
			)
			(property "Manufacturer" "NXP"
				(at 35.56 -16.51 0)
				(effects
					(font
						(size 1.27 1.27)
						(thickness 0.15)
					)
					(justify left bottom)
					(hide yes)
				)
			)
			(property "Author" "Antmicro"
				(at 35.56 -19.05 0)
				(effects
					(font
						(size 1.27 1.27)
						(thickness 0.15)
					)
					(justify left bottom)
					(hide yes)
				)
			)
			(property "License" "Apache-2.0"
				(at 35.56 -21.59 0)
				(effects
					(font
						(size 1.27 1.27)
						(thickness 0.15)
					)
					(justify left bottom)
					(hide yes)
				)
			)
			(property "ki_keywords" "SMT, LEVEL-SHIFTER, IC, LOGIC"
				(at 0 0 0)
				(effects
					(font
						(size 1.27 1.27)
					)
					(hide yes)
				)
			)
			(symbol "NTS0102_TSSOP_1_1"
				(rectangle
					(start 2.54 2.54)
					(end 17.78 -10.16)
					(stroke
						(width 0.254)
						(type default)
					)
					(fill
						(type background)
					)
				)
				(pin power_in line
					(at 0 0 0)
					(length 2.54)
					(name "VCC_{A}"
						(effects
							(font
								(size 1.27 1.27)
							)
						)
					)
					(number "3"
						(effects
							(font
								(size 1.27 1.27)
							)
						)
					)
				)
				(pin bidirectional line
					(at 0 -2.54 0)
					(length 2.54)
					(name "A_{1}"
						(effects
							(font
								(size 1.27 1.27)
							)
						)
					)
					(number "5"
						(effects
							(font
								(size 1.27 1.27)
							)
						)
					)
				)
				(pin bidirectional line
					(at 0 -5.08 0)
					(length 2.54)
					(name "A_{2}"
						(effects
							(font
								(size 1.27 1.27)
							)
						)
					)
					(number "4"
						(effects
							(font
								(size 1.27 1.27)
							)
						)
					)
				)
				(pin input line
					(at 0 -7.62 0)
					(length 2.54)
					(name "OE"
						(effects
							(font
								(size 1.27 1.27)
							)
						)
					)
					(number "6"
						(effects
							(font
								(size 1.27 1.27)
							)
						)
					)
				)
				(pin power_in line
					(at 20.32 0 180)
					(length 2.54)
					(name "VCC_{B}"
						(effects
							(font
								(size 1.27 1.27)
							)
						)
					)
					(number "7"
						(effects
							(font
								(size 1.27 1.27)
							)
						)
					)
				)
				(pin bidirectional line
					(at 20.32 -2.54 180)
					(length 2.54)
					(name "B_{1}"
						(effects
							(font
								(size 1.27 1.27)
							)
						)
					)
					(number "8"
						(effects
							(font
								(size 1.27 1.27)
							)
						)
					)
				)
				(pin bidirectional line
					(at 20.32 -5.08 180)
					(length 2.54)
					(name "B_{2}"
						(effects
							(font
								(size 1.27 1.27)
							)
						)
					)
					(number "1"
						(effects
							(font
								(size 1.27 1.27)
							)
						)
					)
				)
				(pin power_in line
					(at 20.32 -7.62 180)
					(length 2.54)
					(name "GND"
						(effects
							(font
								(size 1.27 1.27)
							)
						)
					)
					(number "2"
						(effects
							(font
								(size 1.27 1.27)
							)
						)
					)
				)
			)
		)
	(symbol "antmicroMechanicalParts:Lightpipe_Bivar_SLP3-300-250-F"
			(pin_names
				(hide yes)
			)
			(exclude_from_sim no)
			(in_bom yes)
			(on_board yes)
			(property "Reference" "H"
				(at 11.76 -2.235 0)
				(effects
					(font
						(size 1.27 1.27)
						(thickness 0.15)
					)
					(justify left bottom)
				)
			)
			(property "Value" "Lightpipe_Bivar_SLP3-300-250-F"
				(at 11.76 -7.315 0)
				(effects
					(font
						(size 1.27 1.27)
						(thickness 0.15)
					)
					(justify left bottom)
					(hide yes)
				)
			)
			(property "Footprint" "antmicro-footprints:Mech_Lightpipe_Bivar_SLP3-300-250-F"
				(at 11.76 -9.855 0)
				(effects
					(font
						(size 1.27 1.27)
						(thickness 0.15)
					)
					(justify left bottom)
					(hide yes)
				)
			)
			(property "Datasheet" "https://www.bivar.com/parts_content/Datasheets/SLP3-XXX-XXX-X.pdf"
				(at 11.76 -12.395 0)
				(effects
					(font
						(size 1.27 1.27)
						(thickness 0.15)
					)
					(justify left bottom)
					(hide yes)
				)
			)
			(property "Description" "LED Light Pipe, Rigid Board, Horizontal"
				(at 0 0 0)
				(effects
					(font
						(size 1.27 1.27)
					)
					(hide yes)
				)
			)
			(property "Manufacturer" "BIVAR"
				(at 11.76 -14.935 0)
				(effects
					(font
						(size 1.27 1.27)
						(thickness 0.15)
					)
					(justify left bottom)
					(hide yes)
				)
			)
			(property "MPN" "SLP3-150-300-F"
				(at 11.76 -4.775 0)
				(effects
					(font
						(size 1.27 1.27)
						(thickness 0.15)
					)
					(justify left bottom)
				)
			)
			(property "Author" "Antmicro"
				(at 11.76 -17.475 0)
				(effects
					(font
						(size 1.27 1.27)
						(thickness 0.15)
					)
					(justify left bottom)
					(hide yes)
				)
			)
			(property "License" "Apache-2.0"
				(at 11.76 -20.015 0)
				(effects
					(font
						(size 1.27 1.27)
						(thickness 0.15)
					)
					(justify left bottom)
					(hide yes)
				)
			)
			(property "ki_keywords" "HORIZONTAL, THT, MECHANICAL"
				(at 0 0 0)
				(effects
					(font
						(size 1.27 1.27)
					)
					(hide yes)
				)
			)
			(symbol "Lightpipe_Bivar_SLP3-300-250-F_1_1"
				(rectangle
					(start 5.08 -2.794)
					(end -5.08 3.556)
					(stroke
						(width 0.254)
						(type default)
					)
					(fill
						(type background)
					)
				)
				(text "Horizontal"
					(at -5.08 1.27 0)
					(effects
						(font
							(size 1.27 1.27)
							(thickness 0.15)
						)
						(justify left bottom)
					)
				)
				(text "lightguide"
					(at -4.826 -0.762 0)
					(effects
						(font
							(size 1.27 1.27)
							(thickness 0.15)
						)
						(justify left bottom)
					)
				)
				(text "1x1"
					(at -1.905 -2.794 0)
					(effects
						(font
							(size 1.27 1.27)
							(thickness 0.15)
						)
						(justify left bottom)
					)
				)
			)
		)
	(symbol "antmicroMechanicalParts:Spacer_Drill3.7mm_H2.5mm_9774025151R"
			(exclude_from_sim no)
			(in_bom yes)
			(on_board yes)
			(property "Reference" "H"
				(at 22.86 -2.54 0)
				(effects
					(font
						(size 1.27 1.27)
						(thickness 0.15)
					)
					(justify left bottom)
				)
			)
			(property "Value" "Spacer_Drill3.7mm_H2.5mm_9774025151R"
				(at 22.86 -5.08 0)
				(effects
					(font
						(size 1.27 1.27)
						(thickness 0.15)
					)
					(justify left bottom)
				)
			)
			(property "Footprint" "antmicro-footprints:Spacer_Drill3.7mm_H2.5mm_9774025151R"
				(at 22.86 -7.62 0)
				(effects
					(font
						(size 1.27 1.27)
						(thickness 0.15)
					)
					(justify left bottom)
					(hide yes)
				)
			)
			(property "Datasheet" "https://www.we-online.com/components/products/datasheet/9774025151R.pdf"
				(at 22.86 -10.16 0)
				(effects
					(font
						(size 1.27 1.27)
						(thickness 0.15)
					)
					(justify left bottom)
					(hide yes)
				)
			)
			(property "Description" "Spacer, SMT, Non Stop, Steel, Swage Round, 5.1 mm x 2.5 mm, M2.5 Thread, WA-SMSI Series"
				(at 0 0 0)
				(effects
					(font
						(size 1.27 1.27)
					)
					(hide yes)
				)
			)
			(property "Manufacturer" "Würth Elektronik"
				(at 22.86 -12.7 0)
				(effects
					(font
						(size 1.27 1.27)
						(thickness 0.15)
					)
					(justify left bottom)
					(hide yes)
				)
			)
			(property "MPN" "9774025151R"
				(at 22.86 -15.24 0)
				(effects
					(font
						(size 1.27 1.27)
						(thickness 0.15)
					)
					(justify left bottom)
					(hide yes)
				)
			)
			(property "Author" "Antmicro"
				(at 22.86 -17.78 0)
				(effects
					(font
						(size 1.27 1.27)
						(thickness 0.15)
					)
					(justify left bottom)
					(hide yes)
				)
			)
			(property "Public" "False"
				(at 22.86 -12.7 0)
				(effects
					(font
						(size 1.27 1.27)
					)
					(justify left bottom)
					(hide yes)
				)
			)
			(property "License" "Apache-2.0"
				(at 22.86 -20.32 0)
				(effects
					(font
						(size 1.27 1.27)
						(thickness 0.15)
					)
					(justify left bottom)
					(hide yes)
				)
			)
			(property "ki_keywords" "MECHANICAL, SPACER"
				(at 0 0 0)
				(effects
					(font
						(size 1.27 1.27)
					)
					(hide yes)
				)
			)
			(symbol "Spacer_Drill3.7mm_H2.5mm_9774025151R_1_1"
				(rectangle
					(start 2.54 -2.54)
					(end 7.62 2.54)
					(stroke
						(width 0.254)
						(type default)
					)
					(fill
						(type background)
					)
				)
				(rectangle
					(start 3.81 -1.27)
					(end 6.35 1.27)
					(stroke
						(width 0.254)
						(type default)
					)
					(fill
						(type background)
					)
				)
				(pin passive line
					(at 0 0 0)
					(length 2.54)
					(name "~"
						(effects
							(font
								(size 1.27 1.27)
							)
						)
					)
					(number "1"
						(effects
							(font
								(size 1.27 1.27)
							)
						)
					)
				)
			)
		)
	(symbol "antmicroMechanicalParts:Spacer_Drill3.7mm_H5mm_9774050151R"
			(exclude_from_sim no)
			(in_bom yes)
			(on_board yes)
			(property "Reference" "H"
				(at 22.86 -2.54 0)
				(effects
					(font
						(size 1.27 1.27)
						(thickness 0.15)
					)
					(justify left bottom)
				)
			)
			(property "Value" "Spacer_Drill3.7mm_H5mm_9774050151R"
				(at 22.86 -5.08 0)
				(effects
					(font
						(size 1.27 1.27)
						(thickness 0.15)
					)
					(justify left bottom)
				)
			)
			(property "Footprint" "antmicro-footprints:Spacer_Drill3.7mm_H5mm_9774050151R"
				(at 22.86 -7.62 0)
				(effects
					(font
						(size 1.27 1.27)
						(thickness 0.15)
					)
					(justify left bottom)
					(hide yes)
				)
			)
			(property "Datasheet" "https://www.we-online.com/catalog/datasheet/9774050151.pdf"
				(at 22.86 -10.16 0)
				(effects
					(font
						(size 1.27 1.27)
						(thickness 0.15)
					)
					(justify left bottom)
					(hide yes)
				)
			)
			(property "Description" "Spacer, SMT, Non Stop, Steel, Swage Round, 5.1 mm x 5 mm, M2.5 Thread, WA-SMSI Series"
				(at 0 0 0)
				(effects
					(font
						(size 1.27 1.27)
					)
					(hide yes)
				)
			)
			(property "Manufacturer" "Würth Elektronik"
				(at 22.86 -12.7 0)
				(effects
					(font
						(size 1.27 1.27)
						(thickness 0.15)
					)
					(justify left bottom)
					(hide yes)
				)
			)
			(property "MPN" "9774050151R"
				(at 22.86 -15.24 0)
				(effects
					(font
						(size 1.27 1.27)
						(thickness 0.15)
					)
					(justify left bottom)
					(hide yes)
				)
			)
			(property "Author" "Antmicro"
				(at 22.86 -17.78 0)
				(effects
					(font
						(size 1.27 1.27)
						(thickness 0.15)
					)
					(justify left bottom)
					(hide yes)
				)
			)
			(property "License" "Apache-2.0"
				(at 22.86 -20.32 0)
				(effects
					(font
						(size 1.27 1.27)
						(thickness 0.15)
					)
					(justify left bottom)
					(hide yes)
				)
			)
			(property "ki_keywords" "SPACER"
				(at 0 0 0)
				(effects
					(font
						(size 1.27 1.27)
					)
					(hide yes)
				)
			)
			(symbol "Spacer_Drill3.7mm_H5mm_9774050151R_1_1"
				(rectangle
					(start 2.54 -2.54)
					(end 7.62 2.54)
					(stroke
						(width 0.254)
						(type default)
					)
					(fill
						(type background)
					)
				)
				(rectangle
					(start 3.81 -1.27)
					(end 6.35 1.27)
					(stroke
						(width 0.254)
						(type default)
					)
					(fill
						(type background)
					)
				)
				(pin passive line
					(at 0 0 0)
					(length 2.54)
					(name "~"
						(effects
							(font
								(size 1.27 1.27)
							)
						)
					)
					(number "1"
						(effects
							(font
								(size 1.27 1.27)
							)
						)
					)
				)
			)
		)
	(symbol "antmicroMemory:M24C64-F_DFN8"
			(exclude_from_sim no)
			(in_bom yes)
			(on_board yes)
			(property "Reference" "U"
				(at 38.1 -2.54 0)
				(effects
					(font
						(size 1.27 1.27)
						(thickness 0.15)
					)
					(justify left bottom)
				)
			)
			(property "Value" "M24C64-F_DFN8"
				(at 38.1 -15.24 0)
				(effects
					(font
						(size 1.27 1.27)
						(thickness 0.15)
					)
					(justify left bottom)
					(hide yes)
				)
			)
			(property "Footprint" "antmicro-footprints:DFN-8-1EP_3x2mm_P0.5mm_EP1.36x1.46mm"
				(at 38.1 -7.62 0)
				(effects
					(font
						(size 1.27 1.27)
						(thickness 0.15)
					)
					(justify left bottom)
					(hide yes)
				)
			)
			(property "Datasheet" "https://eu.mouser.com/datasheet/2/389/cd00259166-1797197.pdf"
				(at 38.1 -10.16 0)
				(effects
					(font
						(size 1.27 1.27)
						(thickness 0.15)
					)
					(justify left bottom)
					(hide yes)
				)
			)
			(property "Description" "EEPROM, 8K x 8bit, Serial I2C (2-Wire), 1 MHz, UFDFPN, 8 Pins"
				(at 0 0 0)
				(effects
					(font
						(size 1.27 1.27)
					)
					(hide yes)
				)
			)
			(property "Manufacturer" "STMicroelectronics"
				(at 38.1 -12.7 0)
				(effects
					(font
						(size 1.27 1.27)
						(thickness 0.15)
					)
					(justify left bottom)
					(hide yes)
				)
			)
			(property "MPN" "M24C64-FMC6TG"
				(at 38.1 -5.08 0)
				(effects
					(font
						(size 1.27 1.27)
						(thickness 0.15)
					)
					(justify left bottom)
				)
			)
			(property "Author" "Antmicro"
				(at 38.1 -17.78 0)
				(effects
					(font
						(size 1.27 1.27)
						(thickness 0.15)
					)
					(justify left bottom)
					(hide yes)
				)
			)
			(property "License" "Apache-2.0"
				(at 38.1 -20.32 0)
				(effects
					(font
						(size 1.27 1.27)
						(thickness 0.15)
					)
					(justify left bottom)
					(hide yes)
				)
			)
			(property "ki_keywords" "SMT, MEMORY, IC, STORAGE, I2C"
				(at 0 0 0)
				(effects
					(font
						(size 1.27 1.27)
					)
					(hide yes)
				)
			)
			(property "ki_fp_filters" "UFDFPN8DFN8_2X3_STM UFDFPN8DFN8_2X3_STM-M UFDFPN8DFN8_2X3_STM-L"
				(at 0 0 0)
				(effects
					(font
						(size 1.27 1.27)
					)
					(hide yes)
				)
			)
			(symbol "M24C64-F_DFN8_1_1"
				(rectangle
					(start 2.54 2.54)
					(end 12.7 -13.97)
					(stroke
						(width 0.254)
						(type default)
					)
					(fill
						(type background)
					)
				)
				(pin input line
					(at 0 0 0)
					(length 2.54)
					(name "SCL"
						(effects
							(font
								(size 1.27 1.27)
							)
						)
					)
					(number "6"
						(effects
							(font
								(size 1.27 1.27)
							)
						)
					)
				)
				(pin bidirectional line
					(at 0 -2.54 0)
					(length 2.54)
					(name "SDA"
						(effects
							(font
								(size 1.27 1.27)
							)
						)
					)
					(number "5"
						(effects
							(font
								(size 1.27 1.27)
							)
						)
					)
				)
				(pin input line
					(at 0 -6.35 0)
					(length 2.54)
					(name "E0"
						(effects
							(font
								(size 1.27 1.27)
							)
						)
					)
					(number "1"
						(effects
							(font
								(size 1.27 1.27)
							)
						)
					)
				)
				(pin input line
					(at 0 -8.89 0)
					(length 2.54)
					(name "E1"
						(effects
							(font
								(size 1.27 1.27)
							)
						)
					)
					(number "2"
						(effects
							(font
								(size 1.27 1.27)
							)
						)
					)
				)
				(pin input line
					(at 0 -11.43 0)
					(length 2.54)
					(name "E2"
						(effects
							(font
								(size 1.27 1.27)
							)
						)
					)
					(number "3"
						(effects
							(font
								(size 1.27 1.27)
							)
						)
					)
				)
				(pin power_in line
					(at 15.24 0 180)
					(length 2.54)
					(name "VCC"
						(effects
							(font
								(size 1.27 1.27)
							)
						)
					)
					(number "8"
						(effects
							(font
								(size 1.27 1.27)
							)
						)
					)
				)
				(pin input line
					(at 15.24 -5.08 180)
					(length 2.54)
					(name "~{WC}"
						(effects
							(font
								(size 1.27 1.27)
							)
						)
					)
					(number "7"
						(effects
							(font
								(size 1.27 1.27)
							)
						)
					)
				)
				(pin power_in line
					(at 15.24 -11.43 180)
					(length 2.54)
					(name "VSS"
						(effects
							(font
								(size 1.27 1.27)
							)
						)
					)
					(number "4"
						(effects
							(font
								(size 1.27 1.27)
							)
						)
					)
				)
				(pin passive line
					(at 15.24 -11.43 180)
					(length 2.54)
					(hide yes)
					(name "VSS"
						(effects
							(font
								(size 1.27 1.27)
							)
						)
					)
					(number "9"
						(effects
							(font
								(size 1.27 1.27)
							)
						)
					)
				)
			)
		)
	(symbol "antmicroMemory:W25Q32FV_SOIC-8"
			(exclude_from_sim no)
			(in_bom yes)
			(on_board yes)
			(property "Reference" "U"
				(at 41.91 -3.81 0)
				(effects
					(font
						(size 1.27 1.27)
						(thickness 0.15)
					)
					(justify left bottom)
				)
			)
			(property "Value" "W25Q32FV_SOIC-8"
				(at 41.91 -6.35 0)
				(effects
					(font
						(size 1.27 1.27)
						(thickness 0.15)
					)
					(justify left bottom)
					(hide yes)
				)
			)
			(property "Footprint" "antmicro-footprints:SOIC-8_5.3x5.3x2mm_P1.27mm"
				(at 41.91 -8.89 0)
				(effects
					(font
						(size 1.27 1.27)
						(thickness 0.15)
					)
					(justify left bottom)
					(hide yes)
				)
			)
			(property "Datasheet" "https://media.digikey.com/pdf/Data%20Sheets/Winbond%20PDFs/W25Q32FV.pdf"
				(at 41.91 -11.43 0)
				(effects
					(font
						(size 1.27 1.27)
						(thickness 0.15)
					)
					(justify left bottom)
					(hide yes)
				)
			)
			(property "Description" "FLASH - NOR Memory IC 32Mbit SPI - Quad I/O, QPI 104 MHz 8-SOIC"
				(at 0 0 0)
				(effects
					(font
						(size 1.27 1.27)
					)
					(hide yes)
				)
			)
			(property "Manufacturer" "Winbond"
				(at 41.91 -13.97 0)
				(effects
					(font
						(size 1.27 1.27)
						(thickness 0.15)
					)
					(justify left bottom)
					(hide yes)
				)
			)
			(property "MPN" "W25Q32FVSSIG"
				(at 41.91 -16.51 0)
				(effects
					(font
						(size 1.27 1.27)
						(thickness 0.15)
					)
					(justify left bottom)
				)
			)
			(property "Author" "Antmicro"
				(at 41.91 -19.05 0)
				(effects
					(font
						(size 1.27 1.27)
						(thickness 0.15)
					)
					(justify left bottom)
					(hide yes)
				)
			)
			(property "License" "Apache-2.0"
				(at 41.91 -21.59 0)
				(effects
					(font
						(size 1.27 1.27)
						(thickness 0.15)
					)
					(justify left bottom)
					(hide yes)
				)
			)
			(property "ki_keywords" "SMT, MEMORY, IC, FLASH"
				(at 0 0 0)
				(effects
					(font
						(size 1.27 1.27)
					)
					(hide yes)
				)
			)
			(symbol "W25Q32FV_SOIC-8_1_1"
				(rectangle
					(start 2.54 2.54)
					(end 16.51 -15.24)
					(stroke
						(width 0.254)
						(type default)
					)
					(fill
						(type background)
					)
				)
				(pin bidirectional line
					(at 0 0 0)
					(length 2.54)
					(name "SI(D0)"
						(effects
							(font
								(size 1.27 1.27)
							)
						)
					)
					(number "5"
						(effects
							(font
								(size 1.27 1.27)
							)
						)
					)
				)
				(pin bidirectional line
					(at 0 -2.54 0)
					(length 2.54)
					(name "SO(D1)"
						(effects
							(font
								(size 1.27 1.27)
							)
						)
					)
					(number "2"
						(effects
							(font
								(size 1.27 1.27)
							)
						)
					)
				)
				(pin bidirectional line
					(at 0 -5.08 0)
					(length 2.54)
					(name "~{WP}(D2)"
						(effects
							(font
								(size 1.27 1.27)
							)
						)
					)
					(number "3"
						(effects
							(font
								(size 1.27 1.27)
							)
						)
					)
				)
				(pin bidirectional line
					(at 0 -7.62 0)
					(length 2.54)
					(name "~{HOLD}(D3)"
						(effects
							(font
								(size 1.27 1.27)
							)
						)
					)
					(number "7"
						(effects
							(font
								(size 1.27 1.27)
							)
						)
					)
				)
				(pin input line
					(at 0 -10.16 0)
					(length 2.54)
					(name "SCK"
						(effects
							(font
								(size 1.27 1.27)
							)
						)
					)
					(number "6"
						(effects
							(font
								(size 1.27 1.27)
							)
						)
					)
				)
				(pin input line
					(at 0 -12.7 0)
					(length 2.54)
					(name "~{CS}"
						(effects
							(font
								(size 1.27 1.27)
							)
						)
					)
					(number "1"
						(effects
							(font
								(size 1.27 1.27)
							)
						)
					)
				)
				(pin power_in line
					(at 19.05 0 180)
					(length 2.54)
					(name "VCC"
						(effects
							(font
								(size 1.27 1.27)
							)
						)
					)
					(number "8"
						(effects
							(font
								(size 1.27 1.27)
							)
						)
					)
				)
				(pin power_in line
					(at 19.05 -12.7 180)
					(length 2.54)
					(name "GND"
						(effects
							(font
								(size 1.27 1.27)
							)
						)
					)
					(number "4"
						(effects
							(font
								(size 1.27 1.27)
							)
						)
					)
				)
			)
		)
	(symbol "antmicroMemoryConnectorsPCCardSockets:MicroSD_693071020811"
			(exclude_from_sim no)
			(in_bom yes)
			(on_board yes)
			(property "Reference" "J"
				(at 55.88 -2.54 0)
				(effects
					(font
						(size 1.27 1.27)
						(thickness 0.15)
					)
					(justify left bottom)
				)
			)
			(property "Value" "MicroSD_693071020811"
				(at 55.88 -5.08 0)
				(effects
					(font
						(size 1.27 1.27)
						(thickness 0.15)
					)
					(justify left bottom)
					(hide yes)
				)
			)
			(property "Footprint" "antmicro-footprints:MicroSD_Wurth_693071020811"
				(at 55.88 -7.62 0)
				(effects
					(font
						(size 1.27 1.27)
						(thickness 0.15)
					)
					(justify left bottom)
					(hide yes)
				)
			)
			(property "Datasheet" "https://www.we-online.com/catalog/datasheet/693071020811.pdf"
				(at 55.88 -10.16 0)
				(effects
					(font
						(size 1.27 1.27)
						(thickness 0.15)
					)
					(justify left bottom)
					(hide yes)
				)
			)
			(property "Description" "Memory Card Connector, MicroSD, Push-Push, 8 Contacts, Copper Alloy, Gold Plated Contacts, WR-CRD"
				(at 0 0 0)
				(effects
					(font
						(size 1.27 1.27)
					)
					(hide yes)
				)
			)
			(property "Manufacturer" "Würth Elektronik"
				(at 55.88 -12.7 0)
				(effects
					(font
						(size 1.27 1.27)
						(thickness 0.15)
					)
					(justify left bottom)
					(hide yes)
				)
			)
			(property "MPN" "693071020811"
				(at 55.88 -15.24 0)
				(effects
					(font
						(size 1.27 1.27)
						(thickness 0.15)
					)
					(justify left bottom)
				)
			)
			(property "Author" "Antmicro"
				(at 55.88 -17.78 0)
				(effects
					(font
						(size 1.27 1.27)
						(thickness 0.15)
					)
					(justify left bottom)
					(hide yes)
				)
			)
			(property "License" "Apache-2.0"
				(at 55.88 -20.32 0)
				(effects
					(font
						(size 1.27 1.27)
						(thickness 0.15)
					)
					(justify left bottom)
					(hide yes)
				)
			)
			(property "ki_keywords" "HORIZONTAL, SMT, MEMORY, CONNECTOR"
				(at 0 0 0)
				(effects
					(font
						(size 1.27 1.27)
					)
					(hide yes)
				)
			)
			(symbol "MicroSD_693071020811_1_1"
				(polyline
					(pts
						(xy 12.7 -21.59) (xy 12.7 -1.27) (xy 20.32 -1.27) (xy 24.13 2.54) (xy 25.4 2.54) (xy 25.4 1.27)
						(xy 27.94 1.27) (xy 29.21 2.54) (xy 41.91 2.54) (xy 41.91 -21.59) (xy 12.7 -21.59)
					)
					(stroke
						(width 0.254)
						(type default)
					)
					(fill
						(type background)
					)
				)
				(rectangle
					(start 13.97 -1.905)
					(end 16.51 -3.175)
					(stroke
						(width 0.254)
						(type default)
					)
					(fill
						(type outline)
					)
				)
				(rectangle
					(start 13.97 -4.445)
					(end 16.51 -5.715)
					(stroke
						(width 0.254)
						(type default)
					)
					(fill
						(type outline)
					)
				)
				(rectangle
					(start 13.97 -6.985)
					(end 16.51 -8.255)
					(stroke
						(width 0.254)
						(type default)
					)
					(fill
						(type outline)
					)
				)
				(rectangle
					(start 13.97 -9.525)
					(end 16.51 -10.795)
					(stroke
						(width 0.254)
						(type default)
					)
					(fill
						(type outline)
					)
				)
				(rectangle
					(start 13.97 -12.065)
					(end 16.51 -13.335)
					(stroke
						(width 0.254)
						(type default)
					)
					(fill
						(type outline)
					)
				)
				(rectangle
					(start 13.97 -14.605)
					(end 16.51 -15.875)
					(stroke
						(width 0.254)
						(type default)
					)
					(fill
						(type outline)
					)
				)
				(rectangle
					(start 13.97 -17.145)
					(end 16.51 -18.415)
					(stroke
						(width 0.254)
						(type default)
					)
					(fill
						(type outline)
					)
				)
				(rectangle
					(start 13.97 -19.685)
					(end 16.51 -20.955)
					(stroke
						(width 0.254)
						(type default)
					)
					(fill
						(type outline)
					)
				)
				(polyline
					(pts
						(xy 38.1 2.54) (xy 38.1 3.81) (xy 2.54 3.81) (xy 2.54 -29.21) (xy 38.1 -29.21) (xy 38.1 -21.59)
					)
					(stroke
						(width 0.254)
						(type default)
					)
					(fill
						(type background)
					)
				)
				(pin power_in line
					(at 0 0 0)
					(length 2.54)
					(name "VDD"
						(effects
							(font
								(size 1.27 1.27)
							)
						)
					)
					(number "4"
						(effects
							(font
								(size 1.27 1.27)
							)
						)
					)
				)
				(pin bidirectional line
					(at 0 -5.08 0)
					(length 2.54)
					(name "DAT2"
						(effects
							(font
								(size 1.27 1.27)
							)
						)
					)
					(number "1"
						(effects
							(font
								(size 1.27 1.27)
							)
						)
					)
				)
				(pin bidirectional line
					(at 0 -7.62 0)
					(length 2.54)
					(name "DAT3/CD"
						(effects
							(font
								(size 1.27 1.27)
							)
						)
					)
					(number "2"
						(effects
							(font
								(size 1.27 1.27)
							)
						)
					)
				)
				(pin input line
					(at 0 -10.16 0)
					(length 2.54)
					(name "CMD"
						(effects
							(font
								(size 1.27 1.27)
							)
						)
					)
					(number "3"
						(effects
							(font
								(size 1.27 1.27)
							)
						)
					)
				)
				(pin input line
					(at 0 -12.7 0)
					(length 2.54)
					(name "CLK"
						(effects
							(font
								(size 1.27 1.27)
							)
						)
					)
					(number "5"
						(effects
							(font
								(size 1.27 1.27)
							)
						)
					)
				)
				(pin input line
					(at 0 -15.24 0)
					(length 2.54)
					(name "DAT0"
						(effects
							(font
								(size 1.27 1.27)
							)
						)
					)
					(number "7"
						(effects
							(font
								(size 1.27 1.27)
							)
						)
					)
				)
				(pin input line
					(at 0 -17.78 0)
					(length 2.54)
					(name "DAT1"
						(effects
							(font
								(size 1.27 1.27)
							)
						)
					)
					(number "8"
						(effects
							(font
								(size 1.27 1.27)
							)
						)
					)
				)
				(pin passive line
					(at 0 -20.32 0)
					(length 2.54)
					(name "CD_SW1"
						(effects
							(font
								(size 1.27 1.27)
							)
						)
					)
					(number "9"
						(effects
							(font
								(size 1.27 1.27)
							)
						)
					)
				)
				(pin passive line
					(at 0 -26.67 0)
					(length 2.54)
					(name "VSS"
						(effects
							(font
								(size 1.27 1.27)
							)
						)
					)
					(number "6"
						(effects
							(font
								(size 1.27 1.27)
							)
						)
					)
				)
				(pin passive line
					(at 40.64 -26.67 180)
					(length 2.54)
					(name "SH"
						(effects
							(font
								(size 1.27 1.27)
							)
						)
					)
					(number "SH"
						(effects
							(font
								(size 1.27 1.27)
							)
						)
					)
				)
			)
		)
	(symbol "antmicroModularConnectorsJacks:Amphenol_RJE361882415"
			(exclude_from_sim no)
			(in_bom yes)
			(on_board yes)
			(property "Reference" "J"
				(at 39.37 -2.54 0)
				(effects
					(font
						(size 1.27 1.27)
						(thickness 0.15)
					)
					(justify left bottom)
				)
			)
			(property "Value" "Amphenol_RJE361882415"
				(at 39.37 -10.16 0)
				(effects
					(font
						(size 1.27 1.27)
						(thickness 0.15)
					)
					(justify left bottom)
					(hide yes)
				)
			)
			(property "Footprint" "antmicro-footprints:RJ45_RJE361882415"
				(at 39.37 -12.7 0)
				(effects
					(font
						(size 1.27 1.27)
						(thickness 0.15)
					)
					(justify left bottom)
					(hide yes)
				)
			)
			(property "Datasheet" "https://cdn.amphenol-cs.com/media/wysiwyg/files/drawing/p-rje36-188-2xx5.pdf"
				(at 39.37 -15.24 0)
				(effects
					(font
						(size 1.27 1.27)
						(thickness 0.15)
					)
					(justify left bottom)
					(hide yes)
				)
			)
			(property "Description" "Modular Connectors / Ethernet Connectors MODULAR JACK"
				(at 0 0 0)
				(effects
					(font
						(size 1.27 1.27)
					)
					(hide yes)
				)
			)
			(property "MPN" "RJE361882415"
				(at 39.37 -5.08 0)
				(effects
					(font
						(size 1.27 1.27)
						(thickness 0.15)
					)
					(justify left bottom)
				)
			)
			(property "Manufacturer" "Amphenol"
				(at 39.37 -17.78 0)
				(effects
					(font
						(size 1.27 1.27)
						(thickness 0.15)
					)
					(justify left bottom)
					(hide yes)
				)
			)
			(property "Author" "Antmicro"
				(at 39.37 -20.32 0)
				(effects
					(font
						(size 1.27 1.27)
						(thickness 0.15)
					)
					(justify left bottom)
					(hide yes)
				)
			)
			(property "License" "Apache-2.0"
				(at 39.37 -22.86 0)
				(effects
					(font
						(size 1.27 1.27)
						(thickness 0.15)
					)
					(justify left bottom)
					(hide yes)
				)
			)
			(property "ki_locked" ""
				(at 0 0 0)
				(effects
					(font
						(size 1.27 1.27)
					)
				)
			)
			(property "ki_keywords" "THT, CONNECTOR"
				(at 0 0 0)
				(effects
					(font
						(size 1.27 1.27)
					)
					(hide yes)
				)
			)
			(symbol "Amphenol_RJE361882415_1_1"
				(rectangle
					(start 3.81 2.54)
					(end 21.59 -25.4)
					(stroke
						(width 0.254)
						(type default)
					)
					(fill
						(type background)
					)
				)
				(rectangle
					(start 7.62 -4.445)
					(end 19.05 -18.415)
					(stroke
						(width 0.254)
						(type default)
					)
					(fill
						(type background)
					)
				)
				(polyline
					(pts
						(xy 8.89 -5.715) (xy 15.24 -5.715)
					)
					(stroke
						(width 0.254)
						(type default)
					)
					(fill
						(type background)
					)
				)
				(polyline
					(pts
						(xy 8.89 -17.145) (xy 8.89 -5.715)
					)
					(stroke
						(width 0.254)
						(type default)
					)
					(fill
						(type background)
					)
				)
				(polyline
					(pts
						(xy 15.24 -5.715) (xy 15.24 -6.985)
					)
					(stroke
						(width 0.254)
						(type default)
					)
					(fill
						(type background)
					)
				)
				(polyline
					(pts
						(xy 15.24 -6.985) (xy 16.51 -6.985)
					)
					(stroke
						(width 0.254)
						(type default)
					)
					(fill
						(type background)
					)
				)
				(polyline
					(pts
						(xy 15.24 -15.875) (xy 16.51 -15.875)
					)
					(stroke
						(width 0.254)
						(type default)
					)
					(fill
						(type background)
					)
				)
				(polyline
					(pts
						(xy 15.24 -17.145) (xy 8.89 -17.145)
					)
					(stroke
						(width 0.254)
						(type default)
					)
					(fill
						(type background)
					)
				)
				(polyline
					(pts
						(xy 15.24 -17.145) (xy 15.24 -15.875)
					)
					(stroke
						(width 0.254)
						(type default)
					)
					(fill
						(type background)
					)
				)
				(polyline
					(pts
						(xy 16.51 -6.985) (xy 16.51 -8.255)
					)
					(stroke
						(width 0.254)
						(type default)
					)
					(fill
						(type background)
					)
				)
				(polyline
					(pts
						(xy 16.51 -8.255) (xy 17.78 -8.255)
					)
					(stroke
						(width 0.254)
						(type default)
					)
					(fill
						(type background)
					)
				)
				(polyline
					(pts
						(xy 16.51 -14.605) (xy 17.78 -14.605)
					)
					(stroke
						(width 0.254)
						(type default)
					)
					(fill
						(type background)
					)
				)
				(polyline
					(pts
						(xy 16.51 -15.875) (xy 16.51 -14.605)
					)
					(stroke
						(width 0.254)
						(type default)
					)
					(fill
						(type background)
					)
				)
				(polyline
					(pts
						(xy 17.78 -8.255) (xy 17.78 -14.605)
					)
					(stroke
						(width 0.254)
						(type default)
					)
					(fill
						(type background)
					)
				)
				(pin bidirectional line
					(at 0 0 0)
					(length 3.81)
					(name "1"
						(effects
							(font
								(size 1.27 1.27)
							)
						)
					)
					(number "1"
						(effects
							(font
								(size 1.27 1.27)
							)
						)
					)
				)
				(pin bidirectional line
					(at 0 -2.54 0)
					(length 3.81)
					(name "2"
						(effects
							(font
								(size 1.27 1.27)
							)
						)
					)
					(number "2"
						(effects
							(font
								(size 1.27 1.27)
							)
						)
					)
				)
				(pin bidirectional line
					(at 0 -5.08 0)
					(length 3.81)
					(name "3"
						(effects
							(font
								(size 1.27 1.27)
							)
						)
					)
					(number "3"
						(effects
							(font
								(size 1.27 1.27)
							)
						)
					)
				)
				(pin bidirectional line
					(at 0 -7.62 0)
					(length 3.81)
					(name "4"
						(effects
							(font
								(size 1.27 1.27)
							)
						)
					)
					(number "4"
						(effects
							(font
								(size 1.27 1.27)
							)
						)
					)
				)
				(pin bidirectional line
					(at 0 -10.16 0)
					(length 3.81)
					(name "5"
						(effects
							(font
								(size 1.27 1.27)
							)
						)
					)
					(number "5"
						(effects
							(font
								(size 1.27 1.27)
							)
						)
					)
				)
				(pin bidirectional line
					(at 0 -12.7 0)
					(length 3.81)
					(name "6"
						(effects
							(font
								(size 1.27 1.27)
							)
						)
					)
					(number "6"
						(effects
							(font
								(size 1.27 1.27)
							)
						)
					)
				)
				(pin bidirectional line
					(at 0 -15.24 0)
					(length 3.81)
					(name "7"
						(effects
							(font
								(size 1.27 1.27)
							)
						)
					)
					(number "7"
						(effects
							(font
								(size 1.27 1.27)
							)
						)
					)
				)
				(pin bidirectional line
					(at 0 -17.78 0)
					(length 3.81)
					(name "8"
						(effects
							(font
								(size 1.27 1.27)
							)
						)
					)
					(number "8"
						(effects
							(font
								(size 1.27 1.27)
							)
						)
					)
				)
				(pin bidirectional line
					(at 0 -22.86 0)
					(length 3.81)
					(name "MP"
						(effects
							(font
								(size 1.27 1.27)
							)
						)
					)
					(number "MP"
						(effects
							(font
								(size 1.27 1.27)
							)
						)
					)
				)
				(pin passive line
					(at 25.4 0 180)
					(length 3.81)
					(name "LED_D1"
						(effects
							(font
								(size 1.27 1.27)
							)
						)
					)
					(number "D1"
						(effects
							(font
								(size 1.27 1.27)
							)
						)
					)
				)
				(pin passive line
					(at 25.4 -2.54 180)
					(length 3.81)
					(name "LED_D2"
						(effects
							(font
								(size 1.27 1.27)
							)
						)
					)
					(number "D2"
						(effects
							(font
								(size 1.27 1.27)
							)
						)
					)
				)
				(pin passive line
					(at 25.4 -20.32 180)
					(length 3.81)
					(name "LED_D3"
						(effects
							(font
								(size 1.27 1.27)
							)
						)
					)
					(number "D3"
						(effects
							(font
								(size 1.27 1.27)
							)
						)
					)
				)
				(pin passive line
					(at 25.4 -22.86 180)
					(length 3.81)
					(name "LED_D4"
						(effects
							(font
								(size 1.27 1.27)
							)
						)
					)
					(number "D4"
						(effects
							(font
								(size 1.27 1.27)
							)
						)
					)
				)
			)
			(symbol "Amphenol_RJE361882415_2_1"
				(rectangle
					(start 3.81 2.54)
					(end 20.32 -24.13)
					(stroke
						(width 0.254)
						(type default)
					)
					(fill
						(type background)
					)
				)
				(circle
					(center 12.065 -5.08)
					(radius 0.381)
					(stroke
						(width 0.254)
						(type default)
					)
					(fill
						(type outline)
					)
				)
				(polyline
					(pts
						(xy 12.7 -3.81) (xy 13.97 -3.81) (xy 13.335 -2.54) (xy 12.7 -3.81)
					)
					(stroke
						(width 0.254)
						(type default)
					)
					(fill
						(type outline)
					)
				)
				(polyline
					(pts
						(xy 13.335 -6.35) (xy 13.335 -3.81)
					)
					(stroke
						(width 0.254)
						(type default)
					)
					(fill
						(type background)
					)
				)
				(polyline
					(pts
						(xy 13.335 -6.985) (xy 13.335 -6.35) (xy 14.605 -5.715) (xy 14.605 -4.445)
					)
					(stroke
						(width 0.254)
						(type default)
					)
					(fill
						(type background)
					)
				)
				(polyline
					(pts
						(xy 13.335 -7.62) (xy 13.335 -6.985) (xy 12.065 -5.715) (xy 12.065 -5.08)
					)
					(stroke
						(width 0.254)
						(type default)
					)
					(fill
						(type background)
					)
				)
				(circle
					(center 13.335 -8.255)
					(radius 0.635)
					(stroke
						(width 0.254)
						(type default)
					)
					(fill
						(type outline)
					)
				)
				(rectangle
					(start 14.224 -4.191)
					(end 14.986 -4.953)
					(stroke
						(width 0.254)
						(type default)
					)
					(fill
						(type outline)
					)
				)
				(rectangle
					(start 16.256 -3.81)
					(end 18.034 -8.382)
					(stroke
						(width 0.254)
						(type default)
					)
					(fill
						(type background)
					)
				)
				(rectangle
					(start 17.018 -4.318)
					(end 17.653 -7.874)
					(stroke
						(width 0.254)
						(type default)
					)
					(fill
						(type outline)
					)
				)
				(text "PORT 1"
					(at 12.7 0 0)
					(effects
						(font
							(size 1.27 1.27)
							(thickness 0.15)
						)
						(justify left bottom)
					)
				)
				(pin passive line
					(at 0 0 0)
					(length 3.81)
					(name "VBUS"
						(effects
							(font
								(size 1.27 1.27)
							)
						)
					)
					(number "U1"
						(effects
							(font
								(size 1.27 1.27)
							)
						)
					)
				)
				(pin bidirectional line
					(at 0 -3.81 0)
					(length 3.81)
					(name "D+"
						(effects
							(font
								(size 1.27 1.27)
							)
						)
					)
					(number "U3"
						(effects
							(font
								(size 1.27 1.27)
							)
						)
					)
				)
				(pin bidirectional line
					(at 0 -6.35 0)
					(length 3.81)
					(name "D-"
						(effects
							(font
								(size 1.27 1.27)
							)
						)
					)
					(number "U2"
						(effects
							(font
								(size 1.27 1.27)
							)
						)
					)
				)
				(pin bidirectional line
					(at 0 -8.89 0)
					(length 3.81)
					(name "SSRX+"
						(effects
							(font
								(size 1.27 1.27)
							)
						)
					)
					(number "U6"
						(effects
							(font
								(size 1.27 1.27)
							)
						)
					)
				)
				(pin bidirectional line
					(at 0 -11.43 0)
					(length 3.81)
					(name "SSRX-"
						(effects
							(font
								(size 1.27 1.27)
							)
						)
					)
					(number "U5"
						(effects
							(font
								(size 1.27 1.27)
							)
						)
					)
				)
				(pin bidirectional line
					(at 0 -13.97 0)
					(length 3.81)
					(name "SSTX+"
						(effects
							(font
								(size 1.27 1.27)
							)
						)
					)
					(number "U9"
						(effects
							(font
								(size 1.27 1.27)
							)
						)
					)
				)
				(pin bidirectional line
					(at 0 -16.51 0)
					(length 3.81)
					(name "SSTX-"
						(effects
							(font
								(size 1.27 1.27)
							)
						)
					)
					(number "U8"
						(effects
							(font
								(size 1.27 1.27)
							)
						)
					)
				)
				(pin power_in line
					(at 0 -19.05 0)
					(length 3.81)
					(name "GND"
						(effects
							(font
								(size 1.27 1.27)
							)
						)
					)
					(number "U4"
						(effects
							(font
								(size 1.27 1.27)
							)
						)
					)
				)
				(pin power_in line
					(at 0 -21.59 0)
					(length 3.81)
					(name "GND_DRAIN"
						(effects
							(font
								(size 1.27 1.27)
							)
						)
					)
					(number "U7"
						(effects
							(font
								(size 1.27 1.27)
							)
						)
					)
				)
			)
			(symbol "Amphenol_RJE361882415_3_1"
				(rectangle
					(start 3.81 2.54)
					(end 20.32 -24.13)
					(stroke
						(width 0.254)
						(type default)
					)
					(fill
						(type background)
					)
				)
				(circle
					(center 12.065 -5.08)
					(radius 0.381)
					(stroke
						(width 0.254)
						(type default)
					)
					(fill
						(type outline)
					)
				)
				(polyline
					(pts
						(xy 12.7 -3.81) (xy 13.97 -3.81) (xy 13.335 -2.54) (xy 12.7 -3.81)
					)
					(stroke
						(width 0.254)
						(type default)
					)
					(fill
						(type outline)
					)
				)
				(polyline
					(pts
						(xy 13.335 -6.35) (xy 13.335 -3.81)
					)
					(stroke
						(width 0.254)
						(type default)
					)
					(fill
						(type background)
					)
				)
				(polyline
					(pts
						(xy 13.335 -6.985) (xy 13.335 -6.35) (xy 14.605 -5.715) (xy 14.605 -4.445)
					)
					(stroke
						(width 0.254)
						(type default)
					)
					(fill
						(type background)
					)
				)
				(polyline
					(pts
						(xy 13.335 -7.62) (xy 13.335 -6.985) (xy 12.065 -5.715) (xy 12.065 -5.08)
					)
					(stroke
						(width 0.254)
						(type default)
					)
					(fill
						(type background)
					)
				)
				(circle
					(center 13.335 -8.255)
					(radius 0.635)
					(stroke
						(width 0.254)
						(type default)
					)
					(fill
						(type outline)
					)
				)
				(rectangle
					(start 14.224 -4.191)
					(end 14.986 -4.953)
					(stroke
						(width 0.254)
						(type default)
					)
					(fill
						(type outline)
					)
				)
				(rectangle
					(start 16.256 -3.81)
					(end 18.034 -8.382)
					(stroke
						(width 0.254)
						(type default)
					)
					(fill
						(type background)
					)
				)
				(rectangle
					(start 17.018 -4.318)
					(end 17.653 -7.874)
					(stroke
						(width 0.254)
						(type default)
					)
					(fill
						(type outline)
					)
				)
				(text "PORT 2"
					(at 12.7 0 0)
					(effects
						(font
							(size 1.27 1.27)
							(thickness 0.15)
						)
						(justify left bottom)
					)
				)
				(pin passive line
					(at 0 0 0)
					(length 3.81)
					(name "VBUS"
						(effects
							(font
								(size 1.27 1.27)
							)
						)
					)
					(number "U10"
						(effects
							(font
								(size 1.27 1.27)
							)
						)
					)
				)
				(pin bidirectional line
					(at 0 -3.81 0)
					(length 3.81)
					(name "D+"
						(effects
							(font
								(size 1.27 1.27)
							)
						)
					)
					(number "U12"
						(effects
							(font
								(size 1.27 1.27)
							)
						)
					)
				)
				(pin bidirectional line
					(at 0 -6.35 0)
					(length 3.81)
					(name "D-"
						(effects
							(font
								(size 1.27 1.27)
							)
						)
					)
					(number "U11"
						(effects
							(font
								(size 1.27 1.27)
							)
						)
					)
				)
				(pin bidirectional line
					(at 0 -8.89 0)
					(length 3.81)
					(name "SSRX+"
						(effects
							(font
								(size 1.27 1.27)
							)
						)
					)
					(number "U15"
						(effects
							(font
								(size 1.27 1.27)
							)
						)
					)
				)
				(pin bidirectional line
					(at 0 -11.43 0)
					(length 3.81)
					(name "SSRX-"
						(effects
							(font
								(size 1.27 1.27)
							)
						)
					)
					(number "U14"
						(effects
							(font
								(size 1.27 1.27)
							)
						)
					)
				)
				(pin bidirectional line
					(at 0 -13.97 0)
					(length 3.81)
					(name "SSTX+"
						(effects
							(font
								(size 1.27 1.27)
							)
						)
					)
					(number "U18"
						(effects
							(font
								(size 1.27 1.27)
							)
						)
					)
				)
				(pin bidirectional line
					(at 0 -16.51 0)
					(length 3.81)
					(name "SSTX-"
						(effects
							(font
								(size 1.27 1.27)
							)
						)
					)
					(number "U17"
						(effects
							(font
								(size 1.27 1.27)
							)
						)
					)
				)
				(pin power_in line
					(at 0 -19.05 0)
					(length 3.81)
					(name "GND"
						(effects
							(font
								(size 1.27 1.27)
							)
						)
					)
					(number "U13"
						(effects
							(font
								(size 1.27 1.27)
							)
						)
					)
				)
				(pin power_in line
					(at 0 -21.59 0)
					(length 3.81)
					(name "GND_DRAIN"
						(effects
							(font
								(size 1.27 1.27)
							)
						)
					)
					(number "U16"
						(effects
							(font
								(size 1.27 1.27)
							)
						)
					)
				)
			)
		)
	(symbol "antmicroModules:Mech_M2_2230_H2.5mm"
			(exclude_from_sim no)
			(in_bom no)
			(on_board yes)
			(property "Reference" "A"
				(at 25.4 0 0)
				(effects
					(font
						(size 1.27 1.27)
						(thickness 0.15)
					)
					(justify left bottom)
				)
			)
			(property "Value" "Mech_M2_2230_H2.5mm"
				(at 25.4 -2.54 0)
				(effects
					(font
						(size 1.27 1.27)
						(thickness 0.15)
					)
					(justify left bottom)
				)
			)
			(property "Footprint" "antmicro-footprints:Mech_M2_2230_H2.5mm"
				(at 25.4 -5.08 0)
				(effects
					(font
						(size 1.27 1.27)
						(thickness 0.15)
					)
					(justify left bottom)
					(hide yes)
				)
			)
			(property "Datasheet" ""
				(at 25.4 -7.62 0)
				(effects
					(font
						(size 1.27 1.27)
						(thickness 0.15)
					)
					(justify left bottom)
					(hide yes)
				)
			)
			(property "Description" "Mechanical model for M2 2230 2.5mm module"
				(at 0 0 0)
				(effects
					(font
						(size 1.27 1.27)
					)
					(hide yes)
				)
			)
			(property "MPN" ""
				(at 0 0 0)
				(effects
					(font
						(size 1.27 1.27)
					)
				)
			)
			(property "Manufacturer" ""
				(at 0 0 0)
				(effects
					(font
						(size 1.27 1.27)
					)
					(hide yes)
				)
			)
			(property "Author" "Antmicro"
				(at 25.4 -10.16 0)
				(effects
					(font
						(size 1.27 1.27)
						(thickness 0.15)
					)
					(justify left bottom)
					(hide yes)
				)
			)
			(property "License" "Apache-2.0"
				(at 25.4 -12.7 0)
				(effects
					(font
						(size 1.27 1.27)
						(thickness 0.15)
					)
					(justify left bottom)
					(hide yes)
				)
			)
			(property "Public" "False"
				(at 25.4 -15.24 0)
				(effects
					(font
						(size 1.27 1.27)
					)
					(justify left bottom)
					(hide yes)
				)
			)
			(property "ki_keywords" "MODULE"
				(at 0 0 0)
				(effects
					(font
						(size 1.27 1.27)
					)
					(hide yes)
				)
			)
			(symbol "Mech_M2_2230_H2.5mm_1_1"
				(rectangle
					(start 10.16 -6.35)
					(end 0 0)
					(stroke
						(width 0.254)
						(type default)
					)
					(fill
						(type background)
					)
				)
			)
		)
	(symbol "antmicroModules:Mech_M2_2280_H2.5mm"
			(exclude_from_sim no)
			(in_bom no)
			(on_board yes)
			(property "Reference" "A"
				(at 25.4 0 0)
				(effects
					(font
						(size 1.27 1.27)
						(thickness 0.15)
					)
					(justify left bottom)
				)
			)
			(property "Value" "Mech_M2_2280_H2.5mm"
				(at 25.4 -2.54 0)
				(effects
					(font
						(size 1.27 1.27)
						(thickness 0.15)
					)
					(justify left bottom)
				)
			)
			(property "Footprint" "antmicro-footprints:Mech_M2_2280_H2.5mm"
				(at 25.4 -5.08 0)
				(effects
					(font
						(size 1.27 1.27)
						(thickness 0.15)
					)
					(justify left bottom)
					(hide yes)
				)
			)
			(property "Datasheet" ""
				(at 25.4 -7.62 0)
				(effects
					(font
						(size 1.27 1.27)
						(thickness 0.15)
					)
					(justify left bottom)
					(hide yes)
				)
			)
			(property "Description" "Mechanical model for M2 2280 2.5mm module"
				(at 0 0 0)
				(effects
					(font
						(size 1.27 1.27)
					)
					(hide yes)
				)
			)
			(property "Manufacturer" ""
				(at 0 0 0)
				(effects
					(font
						(size 1.27 1.27)
					)
					(hide yes)
				)
			)
			(property "MPN" ""
				(at 0 0 0)
				(effects
					(font
						(size 1.27 1.27)
					)
				)
			)
			(property "Author" "Antmicro"
				(at 25.4 -10.16 0)
				(effects
					(font
						(size 1.27 1.27)
						(thickness 0.15)
					)
					(justify left bottom)
					(hide yes)
				)
			)
			(property "License" "Apache-2.0"
				(at 25.4 -12.7 0)
				(effects
					(font
						(size 1.27 1.27)
						(thickness 0.15)
					)
					(justify left bottom)
					(hide yes)
				)
			)
			(property "Public" "False"
				(at 25.4 -15.24 0)
				(effects
					(font
						(size 1.27 1.27)
					)
					(justify left bottom)
					(hide yes)
				)
			)
			(property "ki_keywords" "MODULE"
				(at 0 0 0)
				(effects
					(font
						(size 1.27 1.27)
					)
					(hide yes)
				)
			)
			(symbol "Mech_M2_2280_H2.5mm_1_1"
				(rectangle
					(start 10.16 -6.35)
					(end 0 0)
					(stroke
						(width 0.254)
						(type default)
					)
					(fill
						(type background)
					)
				)
			)
		)
	(symbol "antmicroModules:Mech_SolidRun_LX2160A-CEX7"
			(exclude_from_sim no)
			(in_bom no)
			(on_board yes)
			(property "Reference" "A"
				(at 13.97 -1.27 0)
				(effects
					(font
						(size 1.27 1.27)
						(thickness 0.15)
					)
					(justify left bottom)
				)
			)
			(property "Value" "Mech_SolidRun_LX2160A-CEX7"
				(at 13.97 -3.81 0)
				(effects
					(font
						(size 1.27 1.27)
						(thickness 0.15)
					)
					(justify left bottom)
					(hide yes)
				)
			)
			(property "Footprint" "antmicro-footprints:Mech_SolidRun_LX2160A-CEX7"
				(at 13.97 -6.35 0)
				(effects
					(font
						(size 1.27 1.27)
						(thickness 0.15)
					)
					(justify left bottom)
					(hide yes)
				)
			)
			(property "Datasheet" "https://www.solid-run.com/embedded-networking/nxp-lx2160a-family/cex7-lx2160/#documentation"
				(at 13.97 -8.89 0)
				(effects
					(font
						(size 1.27 1.27)
						(thickness 0.15)
					)
					(justify left bottom)
					(hide yes)
				)
			)
			(property "Description" "LX2160A-CEX7 Computer on Module, 2GHz Frequency, 16 Core, Dual Channel 64GB DDR4 RAM, ARM Cortex-A72"
				(at 0 0 0)
				(effects
					(font
						(size 1.27 1.27)
					)
					(hide yes)
				)
			)
			(property "MPN" "SRX2160S01D00GE064V21C0"
				(at 13.97 -11.43 0)
				(effects
					(font
						(size 1.27 1.27)
						(thickness 0.15)
					)
					(justify left bottom)
				)
			)
			(property "Manufacturer" "SolidRun"
				(at 13.97 -13.97 0)
				(effects
					(font
						(size 1.27 1.27)
						(thickness 0.15)
					)
					(justify left bottom)
					(hide yes)
				)
			)
			(property "Author" "Antmicro"
				(at 13.97 -16.51 0)
				(effects
					(font
						(size 1.27 1.27)
						(thickness 0.15)
					)
					(justify left bottom)
					(hide yes)
				)
			)
			(property "License" "Apache-2.0"
				(at 13.97 -19.05 0)
				(effects
					(font
						(size 1.27 1.27)
						(thickness 0.15)
					)
					(justify left bottom)
					(hide yes)
				)
			)
			(property "Displayed name" "LX2160A-CEX7"
				(at 13.97 -21.59 0)
				(effects
					(font
						(size 1.27 1.27)
					)
					(justify left bottom)
				)
			)
			(property "ki_keywords" "MODULE, B2B"
				(at 0 0 0)
				(effects
					(font
						(size 1.27 1.27)
					)
					(hide yes)
				)
			)
			(symbol "Mech_SolidRun_LX2160A-CEX7_1_1"
				(rectangle
					(start 10.16 -6.35)
					(end 0 0)
					(stroke
						(width 0.254)
						(type default)
					)
					(fill
						(type background)
					)
				)
			)
		)
	(symbol "antmicroOscillators:Oscillator_156.25MHz_SG3225EEN"
			(exclude_from_sim no)
			(in_bom yes)
			(on_board yes)
			(property "Reference" "Y"
				(at 20.32 -10.16 0)
				(effects
					(font
						(size 1.27 1.27)
						(thickness 0.15)
					)
					(justify left bottom)
				)
			)
			(property "Value" "Oscillator_156.25MHz_SG3225EEN"
				(at 20.32 -20.32 0)
				(effects
					(font
						(size 1.27 1.27)
						(thickness 0.15)
					)
					(justify left bottom)
					(hide yes)
				)
			)
			(property "Footprint" "antmicro-footprints:Oscillator_SMD_Epson_SG3225EEN_3.2x2.5x1.2mm"
				(at 20.32 -22.86 0)
				(effects
					(font
						(size 1.27 1.27)
						(thickness 0.15)
					)
					(justify left bottom)
					(hide yes)
				)
			)
			(property "Datasheet" "https://support.epson.biz/td/api/doc_check.php?dl=brief_SG3225EEN&lang=en"
				(at 20.32 -25.4 0)
				(effects
					(font
						(size 1.27 1.27)
						(thickness 0.15)
					)
					(justify left bottom)
					(hide yes)
				)
			)
			(property "Description" "156.25 MHz XO (Standard) LVPECL Oscillator 3.3V Enable/Disable 6-SMD, No Lead"
				(at 0 0 0)
				(effects
					(font
						(size 1.27 1.27)
					)
					(hide yes)
				)
			)
			(property "MPN" "SG3225EEN_156.250000M-CDGA3"
				(at 20.32 -12.7 0)
				(effects
					(font
						(size 1.27 1.27)
						(thickness 0.15)
					)
					(justify left bottom)
				)
			)
			(property "Manufacturer" "Epson"
				(at 20.32 -17.78 0)
				(effects
					(font
						(size 1.27 1.27)
						(thickness 0.15)
					)
					(justify left bottom)
					(hide yes)
				)
			)
			(property "Val" "156.25MHz"
				(at 20.32 -15.24 0)
				(effects
					(font
						(size 1.27 1.27)
						(thickness 0.15)
					)
					(justify left bottom)
				)
			)
			(property "Author" "Antmicro"
				(at 20.32 -27.94 0)
				(effects
					(font
						(size 1.27 1.27)
						(thickness 0.15)
					)
					(justify left bottom)
					(hide yes)
				)
			)
			(property "License" "Apache-2.0"
				(at 20.32 -30.48 0)
				(effects
					(font
						(size 1.27 1.27)
						(thickness 0.15)
					)
					(justify left bottom)
					(hide yes)
				)
			)
			(property "Public" "False"
				(at 34.29 -24.13 0)
				(effects
					(font
						(size 1.27 1.27)
					)
					(justify left bottom)
					(hide yes)
				)
			)
			(property "ki_keywords" "OSCILLATOR, LVDS"
				(at 0 0 0)
				(effects
					(font
						(size 1.27 1.27)
					)
					(hide yes)
				)
			)
			(symbol "Oscillator_156.25MHz_SG3225EEN_1_1"
				(rectangle
					(start 2.54 2.54)
					(end 16.51 -7.62)
					(stroke
						(width 0.254)
						(type default)
					)
					(fill
						(type background)
					)
				)
				(polyline
					(pts
						(xy 7.62 -1.27) (xy 8.255 -1.27) (xy 8.255 0) (xy 8.89 0) (xy 8.89 -1.27) (xy 9.525 -1.27) (xy 9.525 0)
						(xy 10.16 0) (xy 10.16 -1.27)
					)
					(stroke
						(width 0.254)
						(type default)
					)
					(fill
						(type background)
					)
				)
				(pin power_in line
					(at 0 0 0)
					(length 2.54)
					(name "VCC"
						(effects
							(font
								(size 1.27 1.27)
							)
						)
					)
					(number "6"
						(effects
							(font
								(size 1.27 1.27)
							)
						)
					)
				)
				(pin input line
					(at 0 -2.54 0)
					(length 2.54)
					(name "EN"
						(effects
							(font
								(size 1.27 1.27)
							)
						)
					)
					(number "1"
						(effects
							(font
								(size 1.27 1.27)
							)
						)
					)
				)
				(pin power_in line
					(at 0 -5.08 0)
					(length 2.54)
					(name "GND"
						(effects
							(font
								(size 1.27 1.27)
							)
						)
					)
					(number "3"
						(effects
							(font
								(size 1.27 1.27)
							)
						)
					)
				)
				(pin no_connect line
					(at 16.51 -5.08 180)
					(length 2.54)
					(hide yes)
					(name "NC"
						(effects
							(font
								(size 1.27 1.27)
							)
						)
					)
					(number "2"
						(effects
							(font
								(size 1.27 1.27)
							)
						)
					)
				)
				(pin output line
					(at 19.05 0 180)
					(length 2.54)
					(name "OUT+"
						(effects
							(font
								(size 1.27 1.27)
							)
						)
					)
					(number "4"
						(effects
							(font
								(size 1.27 1.27)
							)
						)
					)
				)
				(pin output line
					(at 19.05 -2.54 180)
					(length 2.54)
					(name "OUT-"
						(effects
							(font
								(size 1.27 1.27)
							)
						)
					)
					(number "5"
						(effects
							(font
								(size 1.27 1.27)
							)
						)
					)
				)
			)
		)
	(symbol "antmicroOscillators:Oscillator_32.768kHz_ECS_2520MV"
			(exclude_from_sim no)
			(in_bom yes)
			(on_board yes)
			(property "Reference" "Y"
				(at 26.035 -2.54 0)
				(effects
					(font
						(size 1.27 1.27)
						(thickness 0.15)
					)
					(justify left bottom)
				)
			)
			(property "Value" "Oscillator_32.768kHz_ECS_2520MV"
				(at 26.035 -12.7 0)
				(effects
					(font
						(size 1.27 1.27)
						(thickness 0.15)
					)
					(justify left bottom)
					(hide yes)
				)
			)
			(property "Footprint" "antmicro-footprints:Oscillator_SMD_ECS_2520MV_2.5x2mm"
				(at 26.035 -15.24 0)
				(effects
					(font
						(size 1.27 1.27)
						(thickness 0.15)
					)
					(justify left bottom)
					(hide yes)
				)
			)
			(property "Datasheet" "https://ecsxtal.com/store/pdf/ECS-327MVATX.pdf"
				(at 26.035 -17.78 0)
				(effects
					(font
						(size 1.27 1.27)
						(thickness 0.15)
					)
					(justify left bottom)
					(hide yes)
				)
			)
			(property "Description" "32.768 kHz XO (Standard) CMOS Oscillator 1.6V ~ 3.6V Enable/Disable 4-SMD, No Lead"
				(at 0 0 0)
				(effects
					(font
						(size 1.27 1.27)
					)
					(hide yes)
				)
			)
			(property "Manufacturer" "ECS Inc. International"
				(at 26.035 -7.62 0)
				(effects
					(font
						(size 1.27 1.27)
						(thickness 0.15)
					)
					(justify left bottom)
					(hide yes)
				)
			)
			(property "MPN" "ECS-327MVATX-2-CN-TR3"
				(at 26.035 -5.08 0)
				(effects
					(font
						(size 1.27 1.27)
						(thickness 0.15)
					)
					(justify left bottom)
				)
			)
			(property "Val" "32.768 kHz"
				(at 26.035 -10.16 0)
				(effects
					(font
						(size 1.27 1.27)
						(thickness 0.15)
					)
					(justify left bottom)
				)
			)
			(property "Author" "Antmicro"
				(at 26.035 -20.32 0)
				(effects
					(font
						(size 1.27 1.27)
						(thickness 0.15)
					)
					(justify left bottom)
					(hide yes)
				)
			)
			(property "License" "Apache-2.0"
				(at 26.035 -22.86 0)
				(effects
					(font
						(size 1.27 1.27)
						(thickness 0.15)
					)
					(justify left bottom)
					(hide yes)
				)
			)
			(property "Public" "False"
				(at 31.75 -24.13 0)
				(effects
					(font
						(size 1.27 1.27)
					)
					(justify left bottom)
					(hide yes)
				)
			)
			(property "ki_keywords" "OSCILLATOR"
				(at 0 0 0)
				(effects
					(font
						(size 1.27 1.27)
					)
					(hide yes)
				)
			)
			(symbol "Oscillator_32.768kHz_ECS_2520MV_1_1"
				(rectangle
					(start 2.54 2.54)
					(end 16.51 -7.62)
					(stroke
						(width 0.254)
						(type default)
					)
					(fill
						(type background)
					)
				)
				(polyline
					(pts
						(xy 7.62 -1.27) (xy 8.255 -1.27) (xy 8.255 0) (xy 8.89 0) (xy 8.89 -1.27) (xy 9.525 -1.27) (xy 9.525 0)
						(xy 10.16 0) (xy 10.16 -1.27)
					)
					(stroke
						(width 0.254)
						(type default)
					)
					(fill
						(type background)
					)
				)
				(pin power_in line
					(at 0 0 0)
					(length 2.54)
					(name "VDD"
						(effects
							(font
								(size 1.27 1.27)
							)
						)
					)
					(number "4"
						(effects
							(font
								(size 1.27 1.27)
							)
						)
					)
				)
				(pin input line
					(at 0 -2.54 0)
					(length 2.54)
					(name "EN"
						(effects
							(font
								(size 1.27 1.27)
							)
						)
					)
					(number "1"
						(effects
							(font
								(size 1.27 1.27)
							)
						)
					)
				)
				(pin power_in line
					(at 0 -5.08 0)
					(length 2.54)
					(name "GND"
						(effects
							(font
								(size 1.27 1.27)
							)
						)
					)
					(number "2"
						(effects
							(font
								(size 1.27 1.27)
							)
						)
					)
				)
				(pin output line
					(at 19.05 0 180)
					(length 2.54)
					(name "OUT"
						(effects
							(font
								(size 1.27 1.27)
							)
						)
					)
					(number "3"
						(effects
							(font
								(size 1.27 1.27)
							)
						)
					)
				)
			)
		)
	(symbol "antmicroPMICPowerDistributionSwitchesLoadDrivers:AP22615A_TSOT26"
			(exclude_from_sim no)
			(in_bom yes)
			(on_board yes)
			(property "Reference" "U"
				(at 30.48 -2.54 0)
				(effects
					(font
						(size 1.27 1.27)
						(thickness 0.15)
					)
					(justify left bottom)
				)
			)
			(property "Value" "AP22615A_TSOT26"
				(at 30.48 -5.08 0)
				(effects
					(font
						(size 1.27 1.27)
						(thickness 0.15)
					)
					(justify left bottom)
					(hide yes)
				)
			)
			(property "Footprint" "antmicro-footprints:TSOT23-6"
				(at 30.48 -7.62 0)
				(effects
					(font
						(size 1.27 1.27)
						(thickness 0.15)
					)
					(justify left bottom)
					(hide yes)
				)
			)
			(property "Datasheet" "https://www.mouser.com/datasheet/2/115/DIOD_S_A0008958405_1-2543193.pdf"
				(at 30.48 -10.16 0)
				(effects
					(font
						(size 1.27 1.27)
						(thickness 0.15)
					)
					(justify left bottom)
					(hide yes)
				)
			)
			(property "Description" "Power Load Distribution Switch, High Side, Active High, 1 Output, 5.5 V, 3.6 A, 0.04 ohm, TSOT-26-6"
				(at 0 0 0)
				(effects
					(font
						(size 1.27 1.27)
					)
					(hide yes)
				)
			)
			(property "MPN" "AP22615AWU-7"
				(at 30.48 -12.7 0)
				(effects
					(font
						(size 1.27 1.27)
						(thickness 0.15)
					)
					(justify left bottom)
				)
			)
			(property "Manufacturer" "Diodes Incorporated"
				(at 30.48 -15.24 0)
				(effects
					(font
						(size 1.27 1.27)
						(thickness 0.15)
					)
					(justify left bottom)
					(hide yes)
				)
			)
			(property "Author" "Antmicro"
				(at 30.48 -17.78 0)
				(effects
					(font
						(size 1.27 1.27)
						(thickness 0.15)
					)
					(justify left bottom)
					(hide yes)
				)
			)
			(property "License" "Apache-2.0"
				(at 30.48 -20.32 0)
				(effects
					(font
						(size 1.27 1.27)
						(thickness 0.15)
					)
					(justify left bottom)
					(hide yes)
				)
			)
			(property "ki_keywords" "SMT, PMIC, IC, VOLTAGE"
				(at 0 0 0)
				(effects
					(font
						(size 1.27 1.27)
					)
					(hide yes)
				)
			)
			(symbol "AP22615A_TSOT26_1_1"
				(rectangle
					(start 2.54 2.54)
					(end 12.7 -7.62)
					(stroke
						(width 0.254)
						(type default)
					)
					(fill
						(type background)
					)
				)
				(pin power_in line
					(at 0 0 0)
					(length 2.54)
					(name "IN"
						(effects
							(font
								(size 1.27 1.27)
							)
						)
					)
					(number "6"
						(effects
							(font
								(size 1.27 1.27)
							)
						)
					)
				)
				(pin output line
					(at 0 -2.54 0)
					(length 2.54)
					(name "FLG"
						(effects
							(font
								(size 1.27 1.27)
							)
						)
					)
					(number "3"
						(effects
							(font
								(size 1.27 1.27)
							)
						)
					)
				)
				(pin input line
					(at 0 -5.08 0)
					(length 2.54)
					(name "EN"
						(effects
							(font
								(size 1.27 1.27)
							)
						)
					)
					(number "4"
						(effects
							(font
								(size 1.27 1.27)
							)
						)
					)
				)
				(pin power_out line
					(at 15.24 0 180)
					(length 2.54)
					(name "OUT"
						(effects
							(font
								(size 1.27 1.27)
							)
						)
					)
					(number "1"
						(effects
							(font
								(size 1.27 1.27)
							)
						)
					)
				)
				(pin passive line
					(at 15.24 -2.54 180)
					(length 2.54)
					(name "ISET"
						(effects
							(font
								(size 1.27 1.27)
							)
						)
					)
					(number "5"
						(effects
							(font
								(size 1.27 1.27)
							)
						)
					)
				)
				(pin power_in line
					(at 15.24 -5.08 180)
					(length 2.54)
					(name "GND"
						(effects
							(font
								(size 1.27 1.27)
							)
						)
					)
					(number "2"
						(effects
							(font
								(size 1.27 1.27)
							)
						)
					)
				)
			)
		)
	(symbol "antmicroPMICPowerSequencers:LTC2950CTS8-1"
			(exclude_from_sim no)
			(in_bom yes)
			(on_board yes)
			(property "Reference" "U"
				(at 35.56 -2.54 0)
				(effects
					(font
						(size 1.27 1.27)
						(thickness 0.15)
					)
					(justify left bottom)
				)
			)
			(property "Value" "LTC2950CTS8-1"
				(at 35.56 -7.62 0)
				(effects
					(font
						(size 1.27 1.27)
						(thickness 0.15)
					)
					(justify left bottom)
					(hide yes)
				)
			)
			(property "Footprint" "antmicro-footprints:SOT-23-8"
				(at 35.56 -10.16 0)
				(effects
					(font
						(size 1.27 1.27)
						(thickness 0.15)
					)
					(justify left bottom)
					(hide yes)
				)
			)
			(property "Datasheet" "https://www.analog.com/media/en/technical-documentation/data-sheets/295012fd.pdf"
				(at 35.56 -12.7 0)
				(effects
					(font
						(size 1.27 1.27)
						(thickness 0.15)
					)
					(justify left bottom)
					(hide yes)
				)
			)
			(property "Description" "Pushbutton On/Off Controller"
				(at 0 0 0)
				(effects
					(font
						(size 1.27 1.27)
					)
					(hide yes)
				)
			)
			(property "MPN" "LTC2950CTS8-1"
				(at 35.56 -5.08 0)
				(effects
					(font
						(size 1.27 1.27)
						(thickness 0.15)
					)
					(justify left bottom)
				)
			)
			(property "Manufacturer" "Analog Devices"
				(at 35.56 -15.24 0)
				(effects
					(font
						(size 1.27 1.27)
						(thickness 0.15)
					)
					(justify left bottom)
					(hide yes)
				)
			)
			(property "Author" "Antmicro"
				(at 35.56 -17.78 0)
				(effects
					(font
						(size 1.27 1.27)
						(thickness 0.15)
					)
					(justify left bottom)
					(hide yes)
				)
			)
			(property "License" "Apache-2.0"
				(at 35.56 -20.32 0)
				(effects
					(font
						(size 1.27 1.27)
						(thickness 0.15)
					)
					(justify left bottom)
					(hide yes)
				)
			)
			(property "ki_keywords" "SMT, PMIC, IC, CONTROLLER, ESD"
				(at 0 0 0)
				(effects
					(font
						(size 1.27 1.27)
					)
					(hide yes)
				)
			)
			(symbol "LTC2950CTS8-1_1_1"
				(rectangle
					(start 2.54 2.54)
					(end 17.78 -15.24)
					(stroke
						(width 0.254)
						(type default)
					)
					(fill
						(type background)
					)
				)
				(polyline
					(pts
						(xy 7.62 -7.62) (xy 8.382 -7.62)
					)
					(stroke
						(width 0.254)
						(type default)
					)
					(fill
						(type background)
					)
				)
				(polyline
					(pts
						(xy 8.382 -6.731) (xy 11.938 -6.731)
					)
					(stroke
						(width 0.254)
						(type default)
					)
					(fill
						(type background)
					)
				)
				(circle
					(center 8.636 -7.62)
					(radius 0.254)
					(stroke
						(width 0.254)
						(type default)
					)
					(fill
						(type background)
					)
				)
				(polyline
					(pts
						(xy 9.144 -5.207) (xy 11.176 -5.207)
					)
					(stroke
						(width 0.254)
						(type default)
					)
					(fill
						(type background)
					)
				)
				(polyline
					(pts
						(xy 10.16 -6.731) (xy 10.16 -5.207)
					)
					(stroke
						(width 0.254)
						(type default)
					)
					(fill
						(type background)
					)
				)
				(circle
					(center 11.684 -7.62)
					(radius 0.254)
					(stroke
						(width 0.254)
						(type default)
					)
					(fill
						(type background)
					)
				)
				(polyline
					(pts
						(xy 12.7 -7.62) (xy 11.938 -7.62)
					)
					(stroke
						(width 0.254)
						(type default)
					)
					(fill
						(type background)
					)
				)
				(text "CTRL"
					(at 10.16 -4.445 0)
					(effects
						(font
							(size 0.635 0.635)
							(thickness 0.15)
						)
					)
				)
				(pin power_in line
					(at 0 0 0)
					(length 2.54)
					(name "V_{IN}"
						(effects
							(font
								(size 1.27 1.27)
							)
						)
					)
					(number "1"
						(effects
							(font
								(size 1.27 1.27)
							)
						)
					)
				)
				(pin input line
					(at 0 -7.62 0)
					(length 2.54)
					(name "~{KILL}"
						(effects
							(font
								(size 1.27 1.27)
							)
						)
					)
					(number "8"
						(effects
							(font
								(size 1.27 1.27)
							)
						)
					)
				)
				(pin input line
					(at 0 -10.16 0)
					(length 2.54)
					(name "~{PB}"
						(effects
							(font
								(size 1.27 1.27)
							)
						)
					)
					(number "2"
						(effects
							(font
								(size 1.27 1.27)
							)
						)
					)
				)
				(pin output line
					(at 20.32 0 180)
					(length 2.54)
					(name "EN"
						(effects
							(font
								(size 1.27 1.27)
							)
						)
					)
					(number "6"
						(effects
							(font
								(size 1.27 1.27)
							)
						)
					)
				)
				(pin output line
					(at 20.32 -2.54 180)
					(length 2.54)
					(name "~{INT}"
						(effects
							(font
								(size 1.27 1.27)
							)
						)
					)
					(number "5"
						(effects
							(font
								(size 1.27 1.27)
							)
						)
					)
				)
				(pin passive line
					(at 20.32 -5.08 180)
					(length 2.54)
					(name "ONT"
						(effects
							(font
								(size 1.27 1.27)
							)
						)
					)
					(number "3"
						(effects
							(font
								(size 1.27 1.27)
							)
						)
					)
				)
				(pin passive line
					(at 20.32 -7.62 180)
					(length 2.54)
					(name "OFFT"
						(effects
							(font
								(size 1.27 1.27)
							)
						)
					)
					(number "7"
						(effects
							(font
								(size 1.27 1.27)
							)
						)
					)
				)
				(pin power_in line
					(at 20.32 -12.7 180)
					(length 2.54)
					(name "GND"
						(effects
							(font
								(size 1.27 1.27)
							)
						)
					)
					(number "4"
						(effects
							(font
								(size 1.27 1.27)
							)
						)
					)
				)
			)
		)
	(symbol "antmicroPMICPowerSequencers:TPS3840PL30DBVR"
			(exclude_from_sim no)
			(in_bom yes)
			(on_board yes)
			(property "Reference" "U"
				(at 38.1 -1.27 0)
				(effects
					(font
						(size 1.27 1.27)
						(thickness 0.15)
					)
					(justify left bottom)
				)
			)
			(property "Value" "TPS3840PL30DBVR"
				(at 38.1 -13.97 0)
				(effects
					(font
						(size 1.27 1.27)
						(thickness 0.15)
					)
					(justify left bottom)
					(hide yes)
				)
			)
			(property "Footprint" "antmicro-footprints:SOT-23-5"
				(at 38.1 -6.35 0)
				(effects
					(font
						(size 1.27 1.27)
						(thickness 0.15)
					)
					(justify left bottom)
					(hide yes)
				)
			)
			(property "Datasheet" "https://www.ti.com/lit/ds/symlink/tps3840.pdf?HQS=dis-mous-null-mousermode-dsf-pf-null-wwe&DCM=yes&ref_url=https%3A%2F%2Fwww.mouser.com%2F&distId=26"
				(at 38.1 -8.89 0)
				(effects
					(font
						(size 1.27 1.27)
						(thickness 0.15)
					)
					(justify left bottom)
					(hide yes)
				)
			)
			(property "Description" "Voltage supervisor"
				(at 0 0 0)
				(effects
					(font
						(size 1.27 1.27)
					)
					(hide yes)
				)
			)
			(property "Manufacturer" "Texas Instruments"
				(at 38.1 -11.43 0)
				(effects
					(font
						(size 1.27 1.27)
						(thickness 0.15)
					)
					(justify left bottom)
					(hide yes)
				)
			)
			(property "MPN" "TPS3840PL30DBVR"
				(at 38.1 -3.81 0)
				(effects
					(font
						(size 1.27 1.27)
						(thickness 0.15)
					)
					(justify left bottom)
				)
			)
			(property "Author" "Antmicro"
				(at 38.1 -16.51 0)
				(effects
					(font
						(size 1.27 1.27)
						(thickness 0.15)
					)
					(justify left bottom)
					(hide yes)
				)
			)
			(property "License" "Apache-2.0"
				(at 38.1 -19.05 0)
				(effects
					(font
						(size 1.27 1.27)
						(thickness 0.15)
					)
					(justify left bottom)
					(hide yes)
				)
			)
			(property "ki_keywords" "SMT, PMIC, IC, CONTROLLER"
				(at 0 0 0)
				(effects
					(font
						(size 1.27 1.27)
					)
					(hide yes)
				)
			)
			(property "ki_fp_filters" "DBV0005A_N DBV0005A_M DBV0005A_L"
				(at 0 0 0)
				(effects
					(font
						(size 1.27 1.27)
					)
					(hide yes)
				)
			)
			(symbol "TPS3840PL30DBVR_1_1"
				(rectangle
					(start 2.54 2.54)
					(end 15.24 -7.62)
					(stroke
						(width 0.254)
						(type default)
					)
					(fill
						(type background)
					)
				)
				(pin power_in line
					(at 0 0 0)
					(length 2.54)
					(name "VDD"
						(effects
							(font
								(size 1.27 1.27)
							)
						)
					)
					(number "2"
						(effects
							(font
								(size 1.27 1.27)
							)
						)
					)
				)
				(pin input line
					(at 0 -2.54 0)
					(length 2.54)
					(name "~{MR}"
						(effects
							(font
								(size 1.27 1.27)
							)
						)
					)
					(number "4"
						(effects
							(font
								(size 1.27 1.27)
							)
						)
					)
				)
				(pin passive line
					(at 0 -5.08 0)
					(length 2.54)
					(name "CT"
						(effects
							(font
								(size 1.27 1.27)
							)
						)
					)
					(number "5"
						(effects
							(font
								(size 1.27 1.27)
							)
						)
					)
				)
				(pin output line
					(at 17.78 0 180)
					(length 2.54)
					(name "~{RESET}"
						(effects
							(font
								(size 1.27 1.27)
							)
						)
					)
					(number "1"
						(effects
							(font
								(size 1.27 1.27)
							)
						)
					)
				)
				(pin power_in line
					(at 17.78 -5.08 180)
					(length 2.54)
					(name "GND"
						(effects
							(font
								(size 1.27 1.27)
							)
						)
					)
					(number "3"
						(effects
							(font
								(size 1.27 1.27)
							)
						)
					)
				)
			)
		)
	(symbol "antmicroPMICVoltageRegulatorsLinear:TLV73333PDBVT"
			(exclude_from_sim no)
			(in_bom yes)
			(on_board yes)
			(property "Reference" "U"
				(at 33.02 -2.54 0)
				(effects
					(font
						(size 1.27 1.27)
						(thickness 0.15)
					)
					(justify left bottom)
				)
			)
			(property "Value" "TLV73333PDBVT"
				(at 33.02 -15.24 0)
				(effects
					(font
						(size 1.27 1.27)
						(thickness 0.15)
					)
					(justify left bottom)
					(hide yes)
				)
			)
			(property "Footprint" "antmicro-footprints:SOT-23-5"
				(at 33.02 -17.78 0)
				(effects
					(font
						(size 1.27 1.27)
						(thickness 0.15)
					)
					(justify left bottom)
					(hide yes)
				)
			)
			(property "Datasheet" "https://www.ti.com/lit/ds/symlink/tlv733p.pdf?ts=1702303961350&ref_url=https%253A%252F%252Fwww.ti.com%252Fproduct%252FTLV733P%252Fpart-details%252FTLV73330PDBVR"
				(at 33.02 -20.32 0)
				(effects
					(font
						(size 1.27 1.27)
						(thickness 0.15)
					)
					(justify left bottom)
					(hide yes)
				)
			)
			(property "Description" "Fixed LDO Voltage Regulator, 1.4V to 5.5V, 125mV Dropout, 3V3out, 300mAout, SOT-23-5"
				(at 0 0 0)
				(effects
					(font
						(size 1.27 1.27)
					)
					(hide yes)
				)
			)
			(property "Manufacturer" "Texas Instruments"
				(at 33.02 -5.08 0)
				(effects
					(font
						(size 1.27 1.27)
						(thickness 0.15)
					)
					(justify left bottom)
					(hide yes)
				)
			)
			(property "MPN" "TLV73333PDBVT"
				(at 33.02 -7.62 0)
				(effects
					(font
						(size 1.27 1.27)
						(thickness 0.15)
					)
					(justify left bottom)
				)
			)
			(property "Author" "Antmicro"
				(at 33.02 -10.16 0)
				(effects
					(font
						(size 1.27 1.27)
						(thickness 0.15)
					)
					(justify left bottom)
					(hide yes)
				)
			)
			(property "License" "Apache-2.0"
				(at 33.02 -12.7 0)
				(effects
					(font
						(size 1.27 1.27)
						(thickness 0.15)
					)
					(justify left bottom)
					(hide yes)
				)
			)
			(property "ki_keywords" "SMT, PMIC, IC, LDO, LINEAR, VOLTAGE, REGULATOR"
				(at 0 0 0)
				(effects
					(font
						(size 1.27 1.27)
					)
					(hide yes)
				)
			)
			(symbol "TLV73333PDBVT_1_1"
				(rectangle
					(start 2.54 2.54)
					(end 17.78 -5.08)
					(stroke
						(width 0.254)
						(type default)
					)
					(fill
						(type background)
					)
				)
				(pin power_in line
					(at 0 0 0)
					(length 2.54)
					(name "VIN"
						(effects
							(font
								(size 1.27 1.27)
							)
						)
					)
					(number "1"
						(effects
							(font
								(size 1.27 1.27)
							)
						)
					)
				)
				(pin input line
					(at 0 -2.54 0)
					(length 2.54)
					(name "EN"
						(effects
							(font
								(size 1.27 1.27)
							)
						)
					)
					(number "3"
						(effects
							(font
								(size 1.27 1.27)
							)
						)
					)
				)
				(pin no_connect line
					(at 17.78 -3.81 180)
					(length 2.54)
					(hide yes)
					(name "NC"
						(effects
							(font
								(size 1.27 1.27)
							)
						)
					)
					(number "4"
						(effects
							(font
								(size 1.27 1.27)
							)
						)
					)
				)
				(pin power_out line
					(at 20.32 0 180)
					(length 2.54)
					(name "VOUT"
						(effects
							(font
								(size 1.27 1.27)
							)
						)
					)
					(number "5"
						(effects
							(font
								(size 1.27 1.27)
							)
						)
					)
				)
				(pin power_in line
					(at 20.32 -2.54 180)
					(length 2.54)
					(name "GND"
						(effects
							(font
								(size 1.27 1.27)
							)
						)
					)
					(number "2"
						(effects
							(font
								(size 1.27 1.27)
							)
						)
					)
				)
			)
		)
	(symbol "antmicroPciConnectors:Bus_M.2_1-2199230-6"
			(exclude_from_sim no)
			(in_bom yes)
			(on_board yes)
			(property "Reference" "J"
				(at 45.72 -2.54 0)
				(effects
					(font
						(size 1.27 1.27)
						(thickness 0.15)
					)
					(justify left bottom)
				)
			)
			(property "Value" "Bus_M.2_1-2199230-6"
				(at 45.72 -7.62 0)
				(effects
					(font
						(size 1.27 1.27)
						(thickness 0.15)
					)
					(justify left bottom)
					(hide yes)
				)
			)
			(property "Footprint" "antmicro-footprints:Bus_M.2_Socket_Key_M_TE_1-2199230-6"
				(at 45.72 -10.16 0)
				(effects
					(font
						(size 1.27 1.27)
						(thickness 0.15)
					)
					(justify left bottom)
					(hide yes)
				)
			)
			(property "Datasheet" "https://www.te.com/commerce/DocumentDelivery/DDEController?Action=srchrtrv&DocNm=2199230&DocType=Customer+Drawing&DocLang=English"
				(at 45.72 -12.7 0)
				(effects
					(font
						(size 1.27 1.27)
						(thickness 0.15)
					)
					(justify left bottom)
					(hide yes)
				)
			)
			(property "Description" "Key M Card Edge Connector, 0, Dual Side, 67 Contacts, Surface Mount, Right Angle, Solder"
				(at 0 0 0)
				(effects
					(font
						(size 1.27 1.27)
					)
					(hide yes)
				)
			)
			(property "Manufacturer" "TE Connectivity"
				(at 45.72 -15.24 0)
				(effects
					(font
						(size 1.27 1.27)
						(thickness 0.15)
					)
					(justify left bottom)
					(hide yes)
				)
			)
			(property "MPN" "1-2199230-6"
				(at 45.72 -5.08 0)
				(effects
					(font
						(size 1.27 1.27)
						(thickness 0.15)
					)
					(justify left bottom)
				)
			)
			(property "Author" "Antmicro"
				(at 45.72 -17.78 0)
				(effects
					(font
						(size 1.27 1.27)
						(thickness 0.15)
					)
					(justify left bottom)
					(hide yes)
				)
			)
			(property "License" "Apache-2.0"
				(at 45.72 -20.32 0)
				(effects
					(font
						(size 1.27 1.27)
						(thickness 0.15)
					)
					(justify left bottom)
					(hide yes)
				)
			)
			(property "ki_keywords" "HORIZONTAL, SMT, PCIE, CONNECTOR"
				(at 0 0 0)
				(effects
					(font
						(size 1.27 1.27)
					)
					(hide yes)
				)
			)
			(symbol "Bus_M.2_1-2199230-6_0_0"
				(text "KEY M"
					(at 15.24 0 0)
					(effects
						(font
							(size 1.27 1.27)
							(bold yes)
						)
					)
				)
			)
			(symbol "Bus_M.2_1-2199230-6_1_1"
				(rectangle
					(start 3.81 2.54)
					(end 26.67 -80.01)
					(stroke
						(width 0.254)
						(type default)
					)
					(fill
						(type background)
					)
				)
				(pin input line
					(at 0 0 0)
					(length 3.81)
					(name "~{PERST}"
						(effects
							(font
								(size 1.27 1.27)
							)
						)
					)
					(number "50"
						(effects
							(font
								(size 1.27 1.27)
							)
						)
					)
				)
				(pin output line
					(at 0 -2.54 0)
					(length 3.81)
					(name "~{CLKREQ}"
						(effects
							(font
								(size 1.27 1.27)
							)
						)
					)
					(number "52"
						(effects
							(font
								(size 1.27 1.27)
							)
						)
					)
				)
				(pin input line
					(at 0 -5.08 0)
					(length 3.81)
					(name "~{PEWAKE}"
						(effects
							(font
								(size 1.27 1.27)
							)
						)
					)
					(number "54"
						(effects
							(font
								(size 1.27 1.27)
							)
						)
					)
				)
				(pin input line
					(at 0 -12.7 0)
					(length 3.81)
					(name "REFCLK_P"
						(effects
							(font
								(size 1.27 1.27)
							)
						)
					)
					(number "55"
						(effects
							(font
								(size 1.27 1.27)
							)
						)
					)
				)
				(pin input line
					(at 0 -15.24 0)
					(length 3.81)
					(name "REFCLK_N"
						(effects
							(font
								(size 1.27 1.27)
							)
						)
					)
					(number "53"
						(effects
							(font
								(size 1.27 1.27)
							)
						)
					)
				)
				(pin input line
					(at 0 -21.59 0)
					(length 3.81)
					(name "PET0_P"
						(effects
							(font
								(size 1.27 1.27)
							)
						)
					)
					(number "49"
						(effects
							(font
								(size 1.27 1.27)
							)
						)
					)
				)
				(pin input line
					(at 0 -24.13 0)
					(length 3.81)
					(name "PET0_N"
						(effects
							(font
								(size 1.27 1.27)
							)
						)
					)
					(number "47"
						(effects
							(font
								(size 1.27 1.27)
							)
						)
					)
				)
				(pin output line
					(at 0 -29.21 0)
					(length 3.81)
					(name "PER0_P"
						(effects
							(font
								(size 1.27 1.27)
							)
						)
					)
					(number "43"
						(effects
							(font
								(size 1.27 1.27)
							)
						)
					)
				)
				(pin output line
					(at 0 -31.75 0)
					(length 3.81)
					(name "PER0_N"
						(effects
							(font
								(size 1.27 1.27)
							)
						)
					)
					(number "41"
						(effects
							(font
								(size 1.27 1.27)
							)
						)
					)
				)
				(pin input line
					(at 0 -36.83 0)
					(length 3.81)
					(name "PET1_P"
						(effects
							(font
								(size 1.27 1.27)
							)
						)
					)
					(number "37"
						(effects
							(font
								(size 1.27 1.27)
							)
						)
					)
				)
				(pin input line
					(at 0 -39.37 0)
					(length 3.81)
					(name "PET1_N"
						(effects
							(font
								(size 1.27 1.27)
							)
						)
					)
					(number "35"
						(effects
							(font
								(size 1.27 1.27)
							)
						)
					)
				)
				(pin output line
					(at 0 -44.45 0)
					(length 3.81)
					(name "PER1_P"
						(effects
							(font
								(size 1.27 1.27)
							)
						)
					)
					(number "31"
						(effects
							(font
								(size 1.27 1.27)
							)
						)
					)
				)
				(pin output line
					(at 0 -46.99 0)
					(length 3.81)
					(name "PER1_N"
						(effects
							(font
								(size 1.27 1.27)
							)
						)
					)
					(number "29"
						(effects
							(font
								(size 1.27 1.27)
							)
						)
					)
				)
				(pin input line
					(at 0 -52.07 0)
					(length 3.81)
					(name "PET2_P"
						(effects
							(font
								(size 1.27 1.27)
							)
						)
					)
					(number "25"
						(effects
							(font
								(size 1.27 1.27)
							)
						)
					)
				)
				(pin input line
					(at 0 -54.61 0)
					(length 3.81)
					(name "PET2_N"
						(effects
							(font
								(size 1.27 1.27)
							)
						)
					)
					(number "23"
						(effects
							(font
								(size 1.27 1.27)
							)
						)
					)
				)
				(pin output line
					(at 0 -59.69 0)
					(length 3.81)
					(name "PER2_P"
						(effects
							(font
								(size 1.27 1.27)
							)
						)
					)
					(number "19"
						(effects
							(font
								(size 1.27 1.27)
							)
						)
					)
				)
				(pin output line
					(at 0 -62.23 0)
					(length 3.81)
					(name "PER2_N"
						(effects
							(font
								(size 1.27 1.27)
							)
						)
					)
					(number "17"
						(effects
							(font
								(size 1.27 1.27)
							)
						)
					)
				)
				(pin input line
					(at 0 -67.31 0)
					(length 3.81)
					(name "PET3_P"
						(effects
							(font
								(size 1.27 1.27)
							)
						)
					)
					(number "13"
						(effects
							(font
								(size 1.27 1.27)
							)
						)
					)
				)
				(pin input line
					(at 0 -69.85 0)
					(length 3.81)
					(name "PET3_N"
						(effects
							(font
								(size 1.27 1.27)
							)
						)
					)
					(number "11"
						(effects
							(font
								(size 1.27 1.27)
							)
						)
					)
				)
				(pin output line
					(at 0 -74.93 0)
					(length 3.81)
					(name "PER3_P"
						(effects
							(font
								(size 1.27 1.27)
							)
						)
					)
					(number "7"
						(effects
							(font
								(size 1.27 1.27)
							)
						)
					)
				)
				(pin output line
					(at 0 -77.47 0)
					(length 3.81)
					(name "PER3_N"
						(effects
							(font
								(size 1.27 1.27)
							)
						)
					)
					(number "5"
						(effects
							(font
								(size 1.27 1.27)
							)
						)
					)
				)
				(pin no_connect line
					(at 26.67 -38.1 180)
					(length 3.81)
					(hide yes)
					(name "NC"
						(effects
							(font
								(size 1.27 1.27)
							)
						)
					)
					(number "69"
						(effects
							(font
								(size 1.27 1.27)
							)
						)
					)
				)
				(pin no_connect line
					(at 26.67 -39.37 180)
					(length 3.81)
					(hide yes)
					(name "NC"
						(effects
							(font
								(size 1.27 1.27)
							)
						)
					)
					(number "6"
						(effects
							(font
								(size 1.27 1.27)
							)
						)
					)
				)
				(pin no_connect line
					(at 26.67 -40.64 180)
					(length 3.81)
					(hide yes)
					(name "NC"
						(effects
							(font
								(size 1.27 1.27)
							)
						)
					)
					(number "67"
						(effects
							(font
								(size 1.27 1.27)
							)
						)
					)
				)
				(pin no_connect line
					(at 26.67 -41.91 180)
					(length 3.81)
					(hide yes)
					(name "NC"
						(effects
							(font
								(size 1.27 1.27)
							)
						)
					)
					(number "48"
						(effects
							(font
								(size 1.27 1.27)
							)
						)
					)
				)
				(pin no_connect line
					(at 26.67 -43.18 180)
					(length 3.81)
					(hide yes)
					(name "NC"
						(effects
							(font
								(size 1.27 1.27)
							)
						)
					)
					(number "56"
						(effects
							(font
								(size 1.27 1.27)
							)
						)
					)
				)
				(pin no_connect line
					(at 26.67 -44.45 180)
					(length 3.81)
					(hide yes)
					(name "NC"
						(effects
							(font
								(size 1.27 1.27)
							)
						)
					)
					(number "20"
						(effects
							(font
								(size 1.27 1.27)
							)
						)
					)
				)
				(pin no_connect line
					(at 26.67 -45.72 180)
					(length 3.81)
					(hide yes)
					(name "NC"
						(effects
							(font
								(size 1.27 1.27)
							)
						)
					)
					(number "22"
						(effects
							(font
								(size 1.27 1.27)
							)
						)
					)
				)
				(pin no_connect line
					(at 26.67 -46.99 180)
					(length 3.81)
					(hide yes)
					(name "NC"
						(effects
							(font
								(size 1.27 1.27)
							)
						)
					)
					(number "24"
						(effects
							(font
								(size 1.27 1.27)
							)
						)
					)
				)
				(pin no_connect line
					(at 26.67 -59.69 180)
					(length 3.81)
					(hide yes)
					(name "NC"
						(effects
							(font
								(size 1.27 1.27)
							)
						)
					)
					(number "26"
						(effects
							(font
								(size 1.27 1.27)
							)
						)
					)
				)
				(pin no_connect line
					(at 26.67 -60.96 180)
					(length 3.81)
					(hide yes)
					(name "NC"
						(effects
							(font
								(size 1.27 1.27)
							)
						)
					)
					(number "28"
						(effects
							(font
								(size 1.27 1.27)
							)
						)
					)
				)
				(pin no_connect line
					(at 26.67 -62.23 180)
					(length 3.81)
					(hide yes)
					(name "NC"
						(effects
							(font
								(size 1.27 1.27)
							)
						)
					)
					(number "30"
						(effects
							(font
								(size 1.27 1.27)
							)
						)
					)
				)
				(pin no_connect line
					(at 26.67 -63.5 180)
					(length 3.81)
					(hide yes)
					(name "NC"
						(effects
							(font
								(size 1.27 1.27)
							)
						)
					)
					(number "32"
						(effects
							(font
								(size 1.27 1.27)
							)
						)
					)
				)
				(pin no_connect line
					(at 26.67 -64.77 180)
					(length 3.81)
					(hide yes)
					(name "NC"
						(effects
							(font
								(size 1.27 1.27)
							)
						)
					)
					(number "8"
						(effects
							(font
								(size 1.27 1.27)
							)
						)
					)
				)
				(pin no_connect line
					(at 26.67 -66.04 180)
					(length 3.81)
					(hide yes)
					(name "NC"
						(effects
							(font
								(size 1.27 1.27)
							)
						)
					)
					(number "34"
						(effects
							(font
								(size 1.27 1.27)
							)
						)
					)
				)
				(pin no_connect line
					(at 26.67 -67.31 180)
					(length 3.81)
					(hide yes)
					(name "NC"
						(effects
							(font
								(size 1.27 1.27)
							)
						)
					)
					(number "36"
						(effects
							(font
								(size 1.27 1.27)
							)
						)
					)
				)
				(pin no_connect line
					(at 26.67 -68.58 180)
					(length 3.81)
					(hide yes)
					(name "NC"
						(effects
							(font
								(size 1.27 1.27)
							)
						)
					)
					(number "46"
						(effects
							(font
								(size 1.27 1.27)
							)
						)
					)
				)
				(pin no_connect line
					(at 26.67 -69.85 180)
					(length 3.81)
					(hide yes)
					(name "NC"
						(effects
							(font
								(size 1.27 1.27)
							)
						)
					)
					(number "38"
						(effects
							(font
								(size 1.27 1.27)
							)
						)
					)
				)
				(pin no_connect line
					(at 26.67 -71.12 180)
					(length 3.81)
					(hide yes)
					(name "NC"
						(effects
							(font
								(size 1.27 1.27)
							)
						)
					)
					(number "58"
						(effects
							(font
								(size 1.27 1.27)
							)
						)
					)
				)
				(pin passive line
					(at 30.48 0 180)
					(length 3.81)
					(name "3V3"
						(effects
							(font
								(size 1.27 1.27)
							)
						)
					)
					(number "12"
						(effects
							(font
								(size 1.27 1.27)
							)
						)
					)
				)
				(pin passive line
					(at 30.48 0 180)
					(length 3.81)
					(hide yes)
					(name "3V3"
						(effects
							(font
								(size 1.27 1.27)
							)
						)
					)
					(number "14"
						(effects
							(font
								(size 1.27 1.27)
							)
						)
					)
				)
				(pin passive line
					(at 30.48 0 180)
					(length 3.81)
					(hide yes)
					(name "3V3"
						(effects
							(font
								(size 1.27 1.27)
							)
						)
					)
					(number "16"
						(effects
							(font
								(size 1.27 1.27)
							)
						)
					)
				)
				(pin passive line
					(at 30.48 0 180)
					(length 3.81)
					(hide yes)
					(name "3V3"
						(effects
							(font
								(size 1.27 1.27)
							)
						)
					)
					(number "18"
						(effects
							(font
								(size 1.27 1.27)
							)
						)
					)
				)
				(pin passive line
					(at 30.48 0 180)
					(length 3.81)
					(hide yes)
					(name "3V3"
						(effects
							(font
								(size 1.27 1.27)
							)
						)
					)
					(number "2"
						(effects
							(font
								(size 1.27 1.27)
							)
						)
					)
				)
				(pin passive line
					(at 30.48 0 180)
					(length 3.81)
					(hide yes)
					(name "3V3"
						(effects
							(font
								(size 1.27 1.27)
							)
						)
					)
					(number "4"
						(effects
							(font
								(size 1.27 1.27)
							)
						)
					)
				)
				(pin passive line
					(at 30.48 0 180)
					(length 3.81)
					(hide yes)
					(name "3V3"
						(effects
							(font
								(size 1.27 1.27)
							)
						)
					)
					(number "70"
						(effects
							(font
								(size 1.27 1.27)
							)
						)
					)
				)
				(pin passive line
					(at 30.48 0 180)
					(length 3.81)
					(hide yes)
					(name "3V3"
						(effects
							(font
								(size 1.27 1.27)
							)
						)
					)
					(number "72"
						(effects
							(font
								(size 1.27 1.27)
							)
						)
					)
				)
				(pin passive line
					(at 30.48 0 180)
					(length 3.81)
					(hide yes)
					(name "3V3"
						(effects
							(font
								(size 1.27 1.27)
							)
						)
					)
					(number "74"
						(effects
							(font
								(size 1.27 1.27)
							)
						)
					)
				)
				(pin input line
					(at 30.48 -12.7 180)
					(length 3.81)
					(name "SUSCLK"
						(effects
							(font
								(size 1.27 1.27)
							)
						)
					)
					(number "68"
						(effects
							(font
								(size 1.27 1.27)
							)
						)
					)
				)
				(pin output line
					(at 30.48 -26.67 180)
					(length 3.81)
					(name "ALERT"
						(effects
							(font
								(size 1.27 1.27)
							)
						)
					)
					(number "44"
						(effects
							(font
								(size 1.27 1.27)
							)
						)
					)
				)
				(pin bidirectional line
					(at 30.48 -29.21 180)
					(length 3.81)
					(name "SMB_DATA"
						(effects
							(font
								(size 1.27 1.27)
							)
						)
					)
					(number "42"
						(effects
							(font
								(size 1.27 1.27)
							)
						)
					)
				)
				(pin input line
					(at 30.48 -31.75 180)
					(length 3.81)
					(name "SMB_CLK"
						(effects
							(font
								(size 1.27 1.27)
							)
						)
					)
					(number "40"
						(effects
							(font
								(size 1.27 1.27)
							)
						)
					)
				)
				(pin passive line
					(at 30.48 -54.61 180)
					(length 3.81)
					(name "LED"
						(effects
							(font
								(size 1.27 1.27)
							)
						)
					)
					(number "10"
						(effects
							(font
								(size 1.27 1.27)
							)
						)
					)
				)
				(pin passive line
					(at 30.48 -74.93 180)
					(length 3.81)
					(name "MP"
						(effects
							(font
								(size 1.27 1.27)
							)
						)
					)
					(number "MP1"
						(effects
							(font
								(size 1.27 1.27)
							)
						)
					)
				)
				(pin passive line
					(at 30.48 -74.93 180)
					(length 3.81)
					(hide yes)
					(name "MP"
						(effects
							(font
								(size 1.27 1.27)
							)
						)
					)
					(number "MP2"
						(effects
							(font
								(size 1.27 1.27)
							)
						)
					)
				)
				(pin power_in line
					(at 30.48 -77.47 180)
					(length 3.81)
					(name "GND"
						(effects
							(font
								(size 1.27 1.27)
							)
						)
					)
					(number "1"
						(effects
							(font
								(size 1.27 1.27)
							)
						)
					)
				)
				(pin passive line
					(at 30.48 -77.47 180)
					(length 3.81)
					(hide yes)
					(name "GND"
						(effects
							(font
								(size 1.27 1.27)
							)
						)
					)
					(number "15"
						(effects
							(font
								(size 1.27 1.27)
							)
						)
					)
				)
				(pin passive line
					(at 30.48 -77.47 180)
					(length 3.81)
					(hide yes)
					(name "GND"
						(effects
							(font
								(size 1.27 1.27)
							)
						)
					)
					(number "21"
						(effects
							(font
								(size 1.27 1.27)
							)
						)
					)
				)
				(pin passive line
					(at 30.48 -77.47 180)
					(length 3.81)
					(hide yes)
					(name "GND"
						(effects
							(font
								(size 1.27 1.27)
							)
						)
					)
					(number "27"
						(effects
							(font
								(size 1.27 1.27)
							)
						)
					)
				)
				(pin passive line
					(at 30.48 -77.47 180)
					(length 3.81)
					(hide yes)
					(name "GND"
						(effects
							(font
								(size 1.27 1.27)
							)
						)
					)
					(number "3"
						(effects
							(font
								(size 1.27 1.27)
							)
						)
					)
				)
				(pin passive line
					(at 30.48 -77.47 180)
					(length 3.81)
					(hide yes)
					(name "GND"
						(effects
							(font
								(size 1.27 1.27)
							)
						)
					)
					(number "33"
						(effects
							(font
								(size 1.27 1.27)
							)
						)
					)
				)
				(pin passive line
					(at 30.48 -77.47 180)
					(length 3.81)
					(hide yes)
					(name "GND"
						(effects
							(font
								(size 1.27 1.27)
							)
						)
					)
					(number "39"
						(effects
							(font
								(size 1.27 1.27)
							)
						)
					)
				)
				(pin passive line
					(at 30.48 -77.47 180)
					(length 3.81)
					(hide yes)
					(name "GND"
						(effects
							(font
								(size 1.27 1.27)
							)
						)
					)
					(number "45"
						(effects
							(font
								(size 1.27 1.27)
							)
						)
					)
				)
				(pin passive line
					(at 30.48 -77.47 180)
					(length 3.81)
					(hide yes)
					(name "GND"
						(effects
							(font
								(size 1.27 1.27)
							)
						)
					)
					(number "51"
						(effects
							(font
								(size 1.27 1.27)
							)
						)
					)
				)
				(pin passive line
					(at 30.48 -77.47 180)
					(length 3.81)
					(hide yes)
					(name "GND"
						(effects
							(font
								(size 1.27 1.27)
							)
						)
					)
					(number "57"
						(effects
							(font
								(size 1.27 1.27)
							)
						)
					)
				)
				(pin passive line
					(at 30.48 -77.47 180)
					(length 3.81)
					(hide yes)
					(name "GND"
						(effects
							(font
								(size 1.27 1.27)
							)
						)
					)
					(number "71"
						(effects
							(font
								(size 1.27 1.27)
							)
						)
					)
				)
				(pin passive line
					(at 30.48 -77.47 180)
					(length 3.81)
					(hide yes)
					(name "GND"
						(effects
							(font
								(size 1.27 1.27)
							)
						)
					)
					(number "73"
						(effects
							(font
								(size 1.27 1.27)
							)
						)
					)
				)
				(pin passive line
					(at 30.48 -77.47 180)
					(length 3.81)
					(hide yes)
					(name "GND"
						(effects
							(font
								(size 1.27 1.27)
							)
						)
					)
					(number "75"
						(effects
							(font
								(size 1.27 1.27)
							)
						)
					)
				)
				(pin passive line
					(at 30.48 -77.47 180)
					(length 3.81)
					(hide yes)
					(name "GND"
						(effects
							(font
								(size 1.27 1.27)
							)
						)
					)
					(number "9"
						(effects
							(font
								(size 1.27 1.27)
							)
						)
					)
				)
			)
		)
	(symbol "antmicroPciConnectors:Bus_M.2_2199230-2"
			(exclude_from_sim no)
			(in_bom yes)
			(on_board yes)
			(property "Reference" "J"
				(at 45.72 -1.27 0)
				(effects
					(font
						(size 1.27 1.27)
						(thickness 0.15)
					)
					(justify left bottom)
				)
			)
			(property "Value" "Bus_M.2_2199230-2"
				(at 45.72 -6.35 0)
				(effects
					(font
						(size 1.27 1.27)
						(thickness 0.15)
					)
					(justify left bottom)
					(hide yes)
				)
			)
			(property "Footprint" "antmicro-footprints:Bus_M.2_Socket_Key_E_TE_2199230-6"
				(at 45.72 -8.89 0)
				(effects
					(font
						(size 1.27 1.27)
						(thickness 0.15)
					)
					(justify left bottom)
					(hide yes)
				)
			)
			(property "Datasheet" "https://eu.mouser.com/datasheet/2/418/9/ENG_DS_1_1773702_1NGFFQRG_EN_0214_1_1773702_1NGFF_-3328593.pdf"
				(at 45.72 -11.43 0)
				(effects
					(font
						(size 1.27 1.27)
						(thickness 0.15)
					)
					(justify left bottom)
					(hide yes)
				)
			)
			(property "Description" "Key E, PCI connector"
				(at 0 0 0)
				(effects
					(font
						(size 1.27 1.27)
					)
					(hide yes)
				)
			)
			(property "MPN" "2199230-2"
				(at 45.72 -3.81 0)
				(effects
					(font
						(size 1.27 1.27)
						(thickness 0.15)
					)
					(justify left bottom)
				)
			)
			(property "Manufacturer" "TE Connectivity"
				(at 45.72 -13.97 0)
				(effects
					(font
						(size 1.27 1.27)
						(thickness 0.15)
					)
					(justify left bottom)
					(hide yes)
				)
			)
			(property "Author" "Antmicro"
				(at 45.72 -16.51 0)
				(effects
					(font
						(size 1.27 1.27)
						(thickness 0.15)
					)
					(justify left bottom)
					(hide yes)
				)
			)
			(property "License" "Apache-2.0"
				(at 45.72 -19.05 0)
				(effects
					(font
						(size 1.27 1.27)
						(thickness 0.15)
					)
					(justify left bottom)
					(hide yes)
				)
			)
			(property "ki_keywords" "HORIZONTAL, SMT, PCIE, CONNECTOR"
				(at 0 0 0)
				(effects
					(font
						(size 1.27 1.27)
					)
					(hide yes)
				)
			)
			(symbol "Bus_M.2_2199230-2_0_0"
				(text "KEY E"
					(at 15.24 0 0)
					(effects
						(font
							(size 1.27 1.27)
							(bold yes)
						)
					)
				)
			)
			(symbol "Bus_M.2_2199230-2_1_1"
				(rectangle
					(start 2.54 2.54)
					(end 27.94 -106.68)
					(stroke
						(width 0.254)
						(type default)
					)
					(fill
						(type background)
					)
				)
				(pin input line
					(at 0 0 0)
					(length 2.54)
					(name "~{PERST0}"
						(effects
							(font
								(size 1.27 1.27)
							)
						)
					)
					(number "52"
						(effects
							(font
								(size 1.27 1.27)
							)
						)
					)
				)
				(pin output line
					(at 0 -2.54 0)
					(length 2.54)
					(name "~{CLKREQ0}"
						(effects
							(font
								(size 1.27 1.27)
							)
						)
					)
					(number "53"
						(effects
							(font
								(size 1.27 1.27)
							)
						)
					)
				)
				(pin output line
					(at 0 -5.08 0)
					(length 2.54)
					(name "~{PEWAKE0}"
						(effects
							(font
								(size 1.27 1.27)
							)
						)
					)
					(number "55"
						(effects
							(font
								(size 1.27 1.27)
							)
						)
					)
				)
				(pin input line
					(at 0 -10.16 0)
					(length 2.54)
					(name "REFCLK0_P"
						(effects
							(font
								(size 1.27 1.27)
							)
						)
					)
					(number "47"
						(effects
							(font
								(size 1.27 1.27)
							)
						)
					)
				)
				(pin input line
					(at 0 -12.7 0)
					(length 2.54)
					(name "REFCLK0_N"
						(effects
							(font
								(size 1.27 1.27)
							)
						)
					)
					(number "49"
						(effects
							(font
								(size 1.27 1.27)
							)
						)
					)
				)
				(pin input line
					(at 0 -17.78 0)
					(length 2.54)
					(name "PET0_P"
						(effects
							(font
								(size 1.27 1.27)
							)
						)
					)
					(number "35"
						(effects
							(font
								(size 1.27 1.27)
							)
						)
					)
				)
				(pin input line
					(at 0 -20.32 0)
					(length 2.54)
					(name "PET0_N"
						(effects
							(font
								(size 1.27 1.27)
							)
						)
					)
					(number "37"
						(effects
							(font
								(size 1.27 1.27)
							)
						)
					)
				)
				(pin output line
					(at 0 -25.4 0)
					(length 2.54)
					(name "PER0_P"
						(effects
							(font
								(size 1.27 1.27)
							)
						)
					)
					(number "41"
						(effects
							(font
								(size 1.27 1.27)
							)
						)
					)
				)
				(pin output line
					(at 0 -27.94 0)
					(length 2.54)
					(name "PER0_N"
						(effects
							(font
								(size 1.27 1.27)
							)
						)
					)
					(number "43"
						(effects
							(font
								(size 1.27 1.27)
							)
						)
					)
				)
				(pin input line
					(at 0 -33.02 0)
					(length 2.54)
					(name "REFCLK1_P"
						(effects
							(font
								(size 1.27 1.27)
							)
						)
					)
					(number "71"
						(effects
							(font
								(size 1.27 1.27)
							)
						)
					)
				)
				(pin input line
					(at 0 -35.56 0)
					(length 2.54)
					(name "REFCLK1_N"
						(effects
							(font
								(size 1.27 1.27)
							)
						)
					)
					(number "73"
						(effects
							(font
								(size 1.27 1.27)
							)
						)
					)
				)
				(pin input line
					(at 0 -40.64 0)
					(length 2.54)
					(name "PET1_P"
						(effects
							(font
								(size 1.27 1.27)
							)
						)
					)
					(number "59"
						(effects
							(font
								(size 1.27 1.27)
							)
						)
					)
				)
				(pin input line
					(at 0 -43.18 0)
					(length 2.54)
					(name "PET1_N"
						(effects
							(font
								(size 1.27 1.27)
							)
						)
					)
					(number "61"
						(effects
							(font
								(size 1.27 1.27)
							)
						)
					)
				)
				(pin output line
					(at 0 -48.26 0)
					(length 2.54)
					(name "PER1_P"
						(effects
							(font
								(size 1.27 1.27)
							)
						)
					)
					(number "65"
						(effects
							(font
								(size 1.27 1.27)
							)
						)
					)
				)
				(pin output line
					(at 0 -50.8 0)
					(length 2.54)
					(name "PER1_N"
						(effects
							(font
								(size 1.27 1.27)
							)
						)
					)
					(number "67"
						(effects
							(font
								(size 1.27 1.27)
							)
						)
					)
				)
				(pin bidirectional line
					(at 0 -55.88 0)
					(length 2.54)
					(name "UIM_SWP"
						(effects
							(font
								(size 1.27 1.27)
							)
						)
					)
					(number "66"
						(effects
							(font
								(size 1.27 1.27)
							)
						)
					)
				)
				(pin bidirectional line
					(at 0 -58.42 0)
					(length 2.54)
					(name "UIM_POWER_SNK"
						(effects
							(font
								(size 1.27 1.27)
							)
						)
					)
					(number "68"
						(effects
							(font
								(size 1.27 1.27)
							)
						)
					)
				)
				(pin bidirectional line
					(at 0 -60.96 0)
					(length 2.54)
					(name "UIM_POWER_SRC"
						(effects
							(font
								(size 1.27 1.27)
							)
						)
					)
					(number "70"
						(effects
							(font
								(size 1.27 1.27)
							)
						)
					)
				)
				(pin bidirectional line
					(at 0 -66.04 0)
					(length 2.54)
					(name "PCM_CLK"
						(effects
							(font
								(size 1.27 1.27)
							)
						)
					)
					(number "8"
						(effects
							(font
								(size 1.27 1.27)
							)
						)
					)
				)
				(pin bidirectional line
					(at 0 -68.58 0)
					(length 2.54)
					(name "PCM_SYNC"
						(effects
							(font
								(size 1.27 1.27)
							)
						)
					)
					(number "10"
						(effects
							(font
								(size 1.27 1.27)
							)
						)
					)
				)
				(pin bidirectional line
					(at 0 -71.12 0)
					(length 2.54)
					(name "PCM_OUT"
						(effects
							(font
								(size 1.27 1.27)
							)
						)
					)
					(number "14"
						(effects
							(font
								(size 1.27 1.27)
							)
						)
					)
				)
				(pin bidirectional line
					(at 0 -73.66 0)
					(length 2.54)
					(name "PCM_IN"
						(effects
							(font
								(size 1.27 1.27)
							)
						)
					)
					(number "12"
						(effects
							(font
								(size 1.27 1.27)
							)
						)
					)
				)
				(pin bidirectional line
					(at 0 -78.74 0)
					(length 2.54)
					(name "USB_D_P"
						(effects
							(font
								(size 1.27 1.27)
							)
						)
					)
					(number "3"
						(effects
							(font
								(size 1.27 1.27)
							)
						)
					)
				)
				(pin bidirectional line
					(at 0 -81.28 0)
					(length 2.54)
					(name "USB_D_N"
						(effects
							(font
								(size 1.27 1.27)
							)
						)
					)
					(number "5"
						(effects
							(font
								(size 1.27 1.27)
							)
						)
					)
				)
				(pin input line
					(at 0 -86.36 0)
					(length 2.54)
					(name "SDIO_CLK"
						(effects
							(font
								(size 1.27 1.27)
							)
						)
					)
					(number "9"
						(effects
							(font
								(size 1.27 1.27)
							)
						)
					)
				)
				(pin bidirectional line
					(at 0 -88.9 0)
					(length 2.54)
					(name "SDIO_CMD"
						(effects
							(font
								(size 1.27 1.27)
							)
						)
					)
					(number "11"
						(effects
							(font
								(size 1.27 1.27)
							)
						)
					)
				)
				(pin bidirectional line
					(at 0 -91.44 0)
					(length 2.54)
					(name "SDIO_D0"
						(effects
							(font
								(size 1.27 1.27)
							)
						)
					)
					(number "13"
						(effects
							(font
								(size 1.27 1.27)
							)
						)
					)
				)
				(pin bidirectional line
					(at 0 -93.98 0)
					(length 2.54)
					(name "SDIO_D1"
						(effects
							(font
								(size 1.27 1.27)
							)
						)
					)
					(number "15"
						(effects
							(font
								(size 1.27 1.27)
							)
						)
					)
				)
				(pin bidirectional line
					(at 0 -96.52 0)
					(length 2.54)
					(name "SDIO_D2"
						(effects
							(font
								(size 1.27 1.27)
							)
						)
					)
					(number "17"
						(effects
							(font
								(size 1.27 1.27)
							)
						)
					)
				)
				(pin bidirectional line
					(at 0 -99.06 0)
					(length 2.54)
					(name "SDIO_D3"
						(effects
							(font
								(size 1.27 1.27)
							)
						)
					)
					(number "19"
						(effects
							(font
								(size 1.27 1.27)
							)
						)
					)
				)
				(pin bidirectional line
					(at 0 -101.6 0)
					(length 2.54)
					(name "SDIO_~{WAKE}"
						(effects
							(font
								(size 1.27 1.27)
							)
						)
					)
					(number "21"
						(effects
							(font
								(size 1.27 1.27)
							)
						)
					)
				)
				(pin input line
					(at 0 -104.14 0)
					(length 2.54)
					(name "SDIO_~{RESET}"
						(effects
							(font
								(size 1.27 1.27)
							)
						)
					)
					(number "23"
						(effects
							(font
								(size 1.27 1.27)
							)
						)
					)
				)
				(pin no_connect line
					(at 27.94 -93.98 180)
					(length 2.54)
					(hide yes)
					(name "RFU"
						(effects
							(font
								(size 1.27 1.27)
							)
						)
					)
					(number "64"
						(effects
							(font
								(size 1.27 1.27)
							)
						)
					)
				)
				(pin power_in line
					(at 30.48 0 180)
					(length 2.54)
					(name "3.3V"
						(effects
							(font
								(size 1.27 1.27)
							)
						)
					)
					(number "2"
						(effects
							(font
								(size 1.27 1.27)
							)
						)
					)
				)
				(pin passive line
					(at 30.48 0 180)
					(length 2.54)
					(hide yes)
					(name "3.3V"
						(effects
							(font
								(size 1.27 1.27)
							)
						)
					)
					(number "4"
						(effects
							(font
								(size 1.27 1.27)
							)
						)
					)
				)
				(pin passive line
					(at 30.48 0 180)
					(length 2.54)
					(hide yes)
					(name "3.3V"
						(effects
							(font
								(size 1.27 1.27)
							)
						)
					)
					(number "72"
						(effects
							(font
								(size 1.27 1.27)
							)
						)
					)
				)
				(pin passive line
					(at 30.48 0 180)
					(length 2.54)
					(hide yes)
					(name "3.3V"
						(effects
							(font
								(size 1.27 1.27)
							)
						)
					)
					(number "74"
						(effects
							(font
								(size 1.27 1.27)
							)
						)
					)
				)
				(pin input line
					(at 30.48 -12.7 180)
					(length 2.54)
					(name "SUSCLK"
						(effects
							(font
								(size 1.27 1.27)
							)
						)
					)
					(number "50"
						(effects
							(font
								(size 1.27 1.27)
							)
						)
					)
				)
				(pin output line
					(at 30.48 -25.4 180)
					(length 2.54)
					(name "~{ALERT}"
						(effects
							(font
								(size 1.27 1.27)
							)
						)
					)
					(number "62"
						(effects
							(font
								(size 1.27 1.27)
							)
						)
					)
				)
				(pin bidirectional line
					(at 30.48 -27.94 180)
					(length 2.54)
					(name "I2C_DATA"
						(effects
							(font
								(size 1.27 1.27)
							)
						)
					)
					(number "58"
						(effects
							(font
								(size 1.27 1.27)
							)
						)
					)
				)
				(pin bidirectional line
					(at 30.48 -30.48 180)
					(length 2.54)
					(name "I2C_CLK"
						(effects
							(font
								(size 1.27 1.27)
							)
						)
					)
					(number "60"
						(effects
							(font
								(size 1.27 1.27)
							)
						)
					)
				)
				(pin input line
					(at 30.48 -35.56 180)
					(length 2.54)
					(name "W_DISABLE1"
						(effects
							(font
								(size 1.27 1.27)
							)
						)
					)
					(number "56"
						(effects
							(font
								(size 1.27 1.27)
							)
						)
					)
				)
				(pin input line
					(at 30.48 -38.1 180)
					(length 2.54)
					(name "W_DISABLE2"
						(effects
							(font
								(size 1.27 1.27)
							)
						)
					)
					(number "54"
						(effects
							(font
								(size 1.27 1.27)
							)
						)
					)
				)
				(pin output line
					(at 30.48 -43.18 180)
					(length 2.54)
					(name "~{UART_WAKE}"
						(effects
							(font
								(size 1.27 1.27)
							)
						)
					)
					(number "20"
						(effects
							(font
								(size 1.27 1.27)
							)
						)
					)
				)
				(pin bidirectional line
					(at 30.48 -45.72 180)
					(length 2.54)
					(name "UART_TXD"
						(effects
							(font
								(size 1.27 1.27)
							)
						)
					)
					(number "32"
						(effects
							(font
								(size 1.27 1.27)
							)
						)
					)
				)
				(pin bidirectional line
					(at 30.48 -48.26 180)
					(length 2.54)
					(name "UART_RXD"
						(effects
							(font
								(size 1.27 1.27)
							)
						)
					)
					(number "22"
						(effects
							(font
								(size 1.27 1.27)
							)
						)
					)
				)
				(pin bidirectional line
					(at 30.48 -50.8 180)
					(length 2.54)
					(name "UART_RTS"
						(effects
							(font
								(size 1.27 1.27)
							)
						)
					)
					(number "36"
						(effects
							(font
								(size 1.27 1.27)
							)
						)
					)
				)
				(pin bidirectional line
					(at 30.48 -53.34 180)
					(length 2.54)
					(name "UART_CTS"
						(effects
							(font
								(size 1.27 1.27)
							)
						)
					)
					(number "34"
						(effects
							(font
								(size 1.27 1.27)
							)
						)
					)
				)
				(pin bidirectional line
					(at 30.48 -63.5 180)
					(length 2.54)
					(name "COEX_RXD"
						(effects
							(font
								(size 1.27 1.27)
							)
						)
					)
					(number "48"
						(effects
							(font
								(size 1.27 1.27)
							)
						)
					)
				)
				(pin bidirectional line
					(at 30.48 -66.04 180)
					(length 2.54)
					(name "COEX_TXD"
						(effects
							(font
								(size 1.27 1.27)
							)
						)
					)
					(number "46"
						(effects
							(font
								(size 1.27 1.27)
							)
						)
					)
				)
				(pin bidirectional line
					(at 30.48 -68.58 180)
					(length 2.54)
					(name "COEX3"
						(effects
							(font
								(size 1.27 1.27)
							)
						)
					)
					(number "44"
						(effects
							(font
								(size 1.27 1.27)
							)
						)
					)
				)
				(pin bidirectional line
					(at 30.48 -74.93 180)
					(length 2.54)
					(name "VENDOR_1"
						(effects
							(font
								(size 1.27 1.27)
							)
						)
					)
					(number "38"
						(effects
							(font
								(size 1.27 1.27)
							)
						)
					)
				)
				(pin bidirectional line
					(at 30.48 -77.47 180)
					(length 2.54)
					(name "VENDOR_2"
						(effects
							(font
								(size 1.27 1.27)
							)
						)
					)
					(number "40"
						(effects
							(font
								(size 1.27 1.27)
							)
						)
					)
				)
				(pin bidirectional line
					(at 30.48 -80.01 180)
					(length 2.54)
					(name "VENDOR_3"
						(effects
							(font
								(size 1.27 1.27)
							)
						)
					)
					(number "42"
						(effects
							(font
								(size 1.27 1.27)
							)
						)
					)
				)
				(pin output line
					(at 30.48 -85.09 180)
					(length 2.54)
					(name "~{LED_1}"
						(effects
							(font
								(size 1.27 1.27)
							)
						)
					)
					(number "6"
						(effects
							(font
								(size 1.27 1.27)
							)
						)
					)
				)
				(pin output line
					(at 30.48 -90.17 180)
					(length 2.54)
					(name "~{LED_2}"
						(effects
							(font
								(size 1.27 1.27)
							)
						)
					)
					(number "16"
						(effects
							(font
								(size 1.27 1.27)
							)
						)
					)
				)
				(pin passive line
					(at 30.48 -101.6 180)
					(length 2.54)
					(name "MP"
						(effects
							(font
								(size 1.27 1.27)
							)
						)
					)
					(number "MP"
						(effects
							(font
								(size 1.27 1.27)
							)
						)
					)
				)
				(pin power_in line
					(at 30.48 -104.14 180)
					(length 2.54)
					(name "GND"
						(effects
							(font
								(size 1.27 1.27)
							)
						)
					)
					(number "1"
						(effects
							(font
								(size 1.27 1.27)
							)
						)
					)
				)
				(pin passive line
					(at 30.48 -104.14 180)
					(length 2.54)
					(hide yes)
					(name "GND"
						(effects
							(font
								(size 1.27 1.27)
							)
						)
					)
					(number "18"
						(effects
							(font
								(size 1.27 1.27)
							)
						)
					)
				)
				(pin passive line
					(at 30.48 -104.14 180)
					(length 2.54)
					(hide yes)
					(name "GND"
						(effects
							(font
								(size 1.27 1.27)
							)
						)
					)
					(number "33"
						(effects
							(font
								(size 1.27 1.27)
							)
						)
					)
				)
				(pin passive line
					(at 30.48 -104.14 180)
					(length 2.54)
					(hide yes)
					(name "GND"
						(effects
							(font
								(size 1.27 1.27)
							)
						)
					)
					(number "39"
						(effects
							(font
								(size 1.27 1.27)
							)
						)
					)
				)
				(pin passive line
					(at 30.48 -104.14 180)
					(length 2.54)
					(hide yes)
					(name "GND"
						(effects
							(font
								(size 1.27 1.27)
							)
						)
					)
					(number "45"
						(effects
							(font
								(size 1.27 1.27)
							)
						)
					)
				)
				(pin passive line
					(at 30.48 -104.14 180)
					(length 2.54)
					(hide yes)
					(name "GND"
						(effects
							(font
								(size 1.27 1.27)
							)
						)
					)
					(number "51"
						(effects
							(font
								(size 1.27 1.27)
							)
						)
					)
				)
				(pin passive line
					(at 30.48 -104.14 180)
					(length 2.54)
					(hide yes)
					(name "GND"
						(effects
							(font
								(size 1.27 1.27)
							)
						)
					)
					(number "57"
						(effects
							(font
								(size 1.27 1.27)
							)
						)
					)
				)
				(pin passive line
					(at 30.48 -104.14 180)
					(length 2.54)
					(hide yes)
					(name "GND"
						(effects
							(font
								(size 1.27 1.27)
							)
						)
					)
					(number "63"
						(effects
							(font
								(size 1.27 1.27)
							)
						)
					)
				)
				(pin passive line
					(at 30.48 -104.14 180)
					(length 2.54)
					(hide yes)
					(name "GND"
						(effects
							(font
								(size 1.27 1.27)
							)
						)
					)
					(number "69"
						(effects
							(font
								(size 1.27 1.27)
							)
						)
					)
				)
				(pin passive line
					(at 30.48 -104.14 180)
					(length 2.54)
					(hide yes)
					(name "GND"
						(effects
							(font
								(size 1.27 1.27)
							)
						)
					)
					(number "7"
						(effects
							(font
								(size 1.27 1.27)
							)
						)
					)
				)
				(pin passive line
					(at 30.48 -104.14 180)
					(length 2.54)
					(hide yes)
					(name "GND"
						(effects
							(font
								(size 1.27 1.27)
							)
						)
					)
					(number "75"
						(effects
							(font
								(size 1.27 1.27)
							)
						)
					)
				)
			)
		)
	(symbol "antmicroPciConnectors:Bus_M.2_MDT180M03001"
			(exclude_from_sim no)
			(in_bom yes)
			(on_board yes)
			(property "Reference" "J"
				(at 45.72 -2.54 0)
				(effects
					(font
						(size 1.27 1.27)
						(thickness 0.15)
					)
					(justify left bottom)
				)
			)
			(property "Value" "Bus_M.2_MDT180M03001"
				(at 45.72 -7.62 0)
				(effects
					(font
						(size 1.27 1.27)
						(thickness 0.15)
					)
					(justify left bottom)
					(hide yes)
				)
			)
			(property "Footprint" "antmicro-footprints:Bus_M.2_Socket_Key_M_Amphenol_MDT180M03001"
				(at 45.72 -10.16 0)
				(effects
					(font
						(size 1.27 1.27)
						(thickness 0.15)
					)
					(justify left bottom)
					(hide yes)
				)
			)
			(property "Datasheet" "https://cdn.amphenol-cs.com/media/wysiwyg/files/drawing/mdt180xxx001.pdf"
				(at 45.72 -12.7 0)
				(effects
					(font
						(size 1.27 1.27)
						(thickness 0.15)
					)
					(justify left bottom)
					(hide yes)
				)
			)
			(property "Description" "Key M Card Edge Connector, 0, Dual Side, 67 Contacts, Surface Mount, Right Angle, Solder"
				(at 0 0 0)
				(effects
					(font
						(size 1.27 1.27)
					)
					(hide yes)
				)
			)
			(property "Manufacturer" "Amphenol"
				(at 45.72 -15.24 0)
				(effects
					(font
						(size 1.27 1.27)
						(thickness 0.15)
					)
					(justify left bottom)
					(hide yes)
				)
			)
			(property "MPN" "MDT180M03001"
				(at 45.72 -5.08 0)
				(effects
					(font
						(size 1.27 1.27)
						(thickness 0.15)
					)
					(justify left bottom)
				)
			)
			(property "Author" "Antmicro"
				(at 45.72 -17.78 0)
				(effects
					(font
						(size 1.27 1.27)
						(thickness 0.15)
					)
					(justify left bottom)
					(hide yes)
				)
			)
			(property "License" "Apache-2.0"
				(at 45.72 -20.32 0)
				(effects
					(font
						(size 1.27 1.27)
						(thickness 0.15)
					)
					(justify left bottom)
					(hide yes)
				)
			)
			(property "ki_keywords" "HORIZONTAL, SMT, PCIE, CONNECTOR"
				(at 0 0 0)
				(effects
					(font
						(size 1.27 1.27)
					)
					(hide yes)
				)
			)
			(symbol "Bus_M.2_MDT180M03001_0_0"
				(text "KEY M"
					(at 15.24 0 0)
					(effects
						(font
							(size 1.27 1.27)
							(bold yes)
						)
					)
				)
			)
			(symbol "Bus_M.2_MDT180M03001_1_1"
				(rectangle
					(start 3.81 2.54)
					(end 26.67 -80.01)
					(stroke
						(width 0.254)
						(type default)
					)
					(fill
						(type background)
					)
				)
				(pin input line
					(at 0 0 0)
					(length 3.81)
					(name "~{PERST}"
						(effects
							(font
								(size 1.27 1.27)
							)
						)
					)
					(number "50"
						(effects
							(font
								(size 1.27 1.27)
							)
						)
					)
				)
				(pin output line
					(at 0 -2.54 0)
					(length 3.81)
					(name "~{CLKREQ}"
						(effects
							(font
								(size 1.27 1.27)
							)
						)
					)
					(number "52"
						(effects
							(font
								(size 1.27 1.27)
							)
						)
					)
				)
				(pin input line
					(at 0 -5.08 0)
					(length 3.81)
					(name "~{PEWAKE}"
						(effects
							(font
								(size 1.27 1.27)
							)
						)
					)
					(number "54"
						(effects
							(font
								(size 1.27 1.27)
							)
						)
					)
				)
				(pin input line
					(at 0 -12.7 0)
					(length 3.81)
					(name "REFCLK_P"
						(effects
							(font
								(size 1.27 1.27)
							)
						)
					)
					(number "55"
						(effects
							(font
								(size 1.27 1.27)
							)
						)
					)
				)
				(pin input line
					(at 0 -15.24 0)
					(length 3.81)
					(name "REFCLK_N"
						(effects
							(font
								(size 1.27 1.27)
							)
						)
					)
					(number "53"
						(effects
							(font
								(size 1.27 1.27)
							)
						)
					)
				)
				(pin input line
					(at 0 -21.59 0)
					(length 3.81)
					(name "PET0_P"
						(effects
							(font
								(size 1.27 1.27)
							)
						)
					)
					(number "49"
						(effects
							(font
								(size 1.27 1.27)
							)
						)
					)
				)
				(pin input line
					(at 0 -24.13 0)
					(length 3.81)
					(name "PET0_N"
						(effects
							(font
								(size 1.27 1.27)
							)
						)
					)
					(number "47"
						(effects
							(font
								(size 1.27 1.27)
							)
						)
					)
				)
				(pin output line
					(at 0 -29.21 0)
					(length 3.81)
					(name "PER0_P"
						(effects
							(font
								(size 1.27 1.27)
							)
						)
					)
					(number "43"
						(effects
							(font
								(size 1.27 1.27)
							)
						)
					)
				)
				(pin output line
					(at 0 -31.75 0)
					(length 3.81)
					(name "PER0_N"
						(effects
							(font
								(size 1.27 1.27)
							)
						)
					)
					(number "41"
						(effects
							(font
								(size 1.27 1.27)
							)
						)
					)
				)
				(pin input line
					(at 0 -36.83 0)
					(length 3.81)
					(name "PET1_P"
						(effects
							(font
								(size 1.27 1.27)
							)
						)
					)
					(number "37"
						(effects
							(font
								(size 1.27 1.27)
							)
						)
					)
				)
				(pin input line
					(at 0 -39.37 0)
					(length 3.81)
					(name "PET1_N"
						(effects
							(font
								(size 1.27 1.27)
							)
						)
					)
					(number "35"
						(effects
							(font
								(size 1.27 1.27)
							)
						)
					)
				)
				(pin output line
					(at 0 -44.45 0)
					(length 3.81)
					(name "PER1_P"
						(effects
							(font
								(size 1.27 1.27)
							)
						)
					)
					(number "31"
						(effects
							(font
								(size 1.27 1.27)
							)
						)
					)
				)
				(pin output line
					(at 0 -46.99 0)
					(length 3.81)
					(name "PER1_N"
						(effects
							(font
								(size 1.27 1.27)
							)
						)
					)
					(number "29"
						(effects
							(font
								(size 1.27 1.27)
							)
						)
					)
				)
				(pin input line
					(at 0 -52.07 0)
					(length 3.81)
					(name "PET2_P"
						(effects
							(font
								(size 1.27 1.27)
							)
						)
					)
					(number "25"
						(effects
							(font
								(size 1.27 1.27)
							)
						)
					)
				)
				(pin input line
					(at 0 -54.61 0)
					(length 3.81)
					(name "PET2_N"
						(effects
							(font
								(size 1.27 1.27)
							)
						)
					)
					(number "23"
						(effects
							(font
								(size 1.27 1.27)
							)
						)
					)
				)
				(pin output line
					(at 0 -59.69 0)
					(length 3.81)
					(name "PER2_P"
						(effects
							(font
								(size 1.27 1.27)
							)
						)
					)
					(number "19"
						(effects
							(font
								(size 1.27 1.27)
							)
						)
					)
				)
				(pin output line
					(at 0 -62.23 0)
					(length 3.81)
					(name "PER2_N"
						(effects
							(font
								(size 1.27 1.27)
							)
						)
					)
					(number "17"
						(effects
							(font
								(size 1.27 1.27)
							)
						)
					)
				)
				(pin input line
					(at 0 -67.31 0)
					(length 3.81)
					(name "PET3_P"
						(effects
							(font
								(size 1.27 1.27)
							)
						)
					)
					(number "13"
						(effects
							(font
								(size 1.27 1.27)
							)
						)
					)
				)
				(pin input line
					(at 0 -69.85 0)
					(length 3.81)
					(name "PET3_N"
						(effects
							(font
								(size 1.27 1.27)
							)
						)
					)
					(number "11"
						(effects
							(font
								(size 1.27 1.27)
							)
						)
					)
				)
				(pin output line
					(at 0 -74.93 0)
					(length 3.81)
					(name "PER3_P"
						(effects
							(font
								(size 1.27 1.27)
							)
						)
					)
					(number "7"
						(effects
							(font
								(size 1.27 1.27)
							)
						)
					)
				)
				(pin output line
					(at 0 -77.47 0)
					(length 3.81)
					(name "PER3_N"
						(effects
							(font
								(size 1.27 1.27)
							)
						)
					)
					(number "5"
						(effects
							(font
								(size 1.27 1.27)
							)
						)
					)
				)
				(pin no_connect line
					(at 26.67 -38.1 180)
					(length 3.81)
					(hide yes)
					(name "NC"
						(effects
							(font
								(size 1.27 1.27)
							)
						)
					)
					(number "69"
						(effects
							(font
								(size 1.27 1.27)
							)
						)
					)
				)
				(pin no_connect line
					(at 26.67 -39.37 180)
					(length 3.81)
					(hide yes)
					(name "NC"
						(effects
							(font
								(size 1.27 1.27)
							)
						)
					)
					(number "6"
						(effects
							(font
								(size 1.27 1.27)
							)
						)
					)
				)
				(pin no_connect line
					(at 26.67 -40.64 180)
					(length 3.81)
					(hide yes)
					(name "NC"
						(effects
							(font
								(size 1.27 1.27)
							)
						)
					)
					(number "67"
						(effects
							(font
								(size 1.27 1.27)
							)
						)
					)
				)
				(pin no_connect line
					(at 26.67 -41.91 180)
					(length 3.81)
					(hide yes)
					(name "NC"
						(effects
							(font
								(size 1.27 1.27)
							)
						)
					)
					(number "48"
						(effects
							(font
								(size 1.27 1.27)
							)
						)
					)
				)
				(pin no_connect line
					(at 26.67 -43.18 180)
					(length 3.81)
					(hide yes)
					(name "NC"
						(effects
							(font
								(size 1.27 1.27)
							)
						)
					)
					(number "56"
						(effects
							(font
								(size 1.27 1.27)
							)
						)
					)
				)
				(pin no_connect line
					(at 26.67 -44.45 180)
					(length 3.81)
					(hide yes)
					(name "NC"
						(effects
							(font
								(size 1.27 1.27)
							)
						)
					)
					(number "20"
						(effects
							(font
								(size 1.27 1.27)
							)
						)
					)
				)
				(pin no_connect line
					(at 26.67 -45.72 180)
					(length 3.81)
					(hide yes)
					(name "NC"
						(effects
							(font
								(size 1.27 1.27)
							)
						)
					)
					(number "22"
						(effects
							(font
								(size 1.27 1.27)
							)
						)
					)
				)
				(pin no_connect line
					(at 26.67 -46.99 180)
					(length 3.81)
					(hide yes)
					(name "NC"
						(effects
							(font
								(size 1.27 1.27)
							)
						)
					)
					(number "24"
						(effects
							(font
								(size 1.27 1.27)
							)
						)
					)
				)
				(pin no_connect line
					(at 26.67 -59.69 180)
					(length 3.81)
					(hide yes)
					(name "NC"
						(effects
							(font
								(size 1.27 1.27)
							)
						)
					)
					(number "26"
						(effects
							(font
								(size 1.27 1.27)
							)
						)
					)
				)
				(pin no_connect line
					(at 26.67 -60.96 180)
					(length 3.81)
					(hide yes)
					(name "NC"
						(effects
							(font
								(size 1.27 1.27)
							)
						)
					)
					(number "28"
						(effects
							(font
								(size 1.27 1.27)
							)
						)
					)
				)
				(pin no_connect line
					(at 26.67 -62.23 180)
					(length 3.81)
					(hide yes)
					(name "NC"
						(effects
							(font
								(size 1.27 1.27)
							)
						)
					)
					(number "30"
						(effects
							(font
								(size 1.27 1.27)
							)
						)
					)
				)
				(pin no_connect line
					(at 26.67 -63.5 180)
					(length 3.81)
					(hide yes)
					(name "NC"
						(effects
							(font
								(size 1.27 1.27)
							)
						)
					)
					(number "32"
						(effects
							(font
								(size 1.27 1.27)
							)
						)
					)
				)
				(pin no_connect line
					(at 26.67 -64.77 180)
					(length 3.81)
					(hide yes)
					(name "NC"
						(effects
							(font
								(size 1.27 1.27)
							)
						)
					)
					(number "8"
						(effects
							(font
								(size 1.27 1.27)
							)
						)
					)
				)
				(pin no_connect line
					(at 26.67 -66.04 180)
					(length 3.81)
					(hide yes)
					(name "NC"
						(effects
							(font
								(size 1.27 1.27)
							)
						)
					)
					(number "34"
						(effects
							(font
								(size 1.27 1.27)
							)
						)
					)
				)
				(pin no_connect line
					(at 26.67 -67.31 180)
					(length 3.81)
					(hide yes)
					(name "NC"
						(effects
							(font
								(size 1.27 1.27)
							)
						)
					)
					(number "36"
						(effects
							(font
								(size 1.27 1.27)
							)
						)
					)
				)
				(pin no_connect line
					(at 26.67 -68.58 180)
					(length 3.81)
					(hide yes)
					(name "NC"
						(effects
							(font
								(size 1.27 1.27)
							)
						)
					)
					(number "46"
						(effects
							(font
								(size 1.27 1.27)
							)
						)
					)
				)
				(pin no_connect line
					(at 26.67 -69.85 180)
					(length 3.81)
					(hide yes)
					(name "NC"
						(effects
							(font
								(size 1.27 1.27)
							)
						)
					)
					(number "38"
						(effects
							(font
								(size 1.27 1.27)
							)
						)
					)
				)
				(pin no_connect line
					(at 26.67 -71.12 180)
					(length 3.81)
					(hide yes)
					(name "NC"
						(effects
							(font
								(size 1.27 1.27)
							)
						)
					)
					(number "58"
						(effects
							(font
								(size 1.27 1.27)
							)
						)
					)
				)
				(pin passive line
					(at 30.48 0 180)
					(length 3.81)
					(name "3V3"
						(effects
							(font
								(size 1.27 1.27)
							)
						)
					)
					(number "12"
						(effects
							(font
								(size 1.27 1.27)
							)
						)
					)
				)
				(pin passive line
					(at 30.48 0 180)
					(length 3.81)
					(hide yes)
					(name "3V3"
						(effects
							(font
								(size 1.27 1.27)
							)
						)
					)
					(number "14"
						(effects
							(font
								(size 1.27 1.27)
							)
						)
					)
				)
				(pin passive line
					(at 30.48 0 180)
					(length 3.81)
					(hide yes)
					(name "3V3"
						(effects
							(font
								(size 1.27 1.27)
							)
						)
					)
					(number "16"
						(effects
							(font
								(size 1.27 1.27)
							)
						)
					)
				)
				(pin passive line
					(at 30.48 0 180)
					(length 3.81)
					(hide yes)
					(name "3V3"
						(effects
							(font
								(size 1.27 1.27)
							)
						)
					)
					(number "18"
						(effects
							(font
								(size 1.27 1.27)
							)
						)
					)
				)
				(pin passive line
					(at 30.48 0 180)
					(length 3.81)
					(hide yes)
					(name "3V3"
						(effects
							(font
								(size 1.27 1.27)
							)
						)
					)
					(number "2"
						(effects
							(font
								(size 1.27 1.27)
							)
						)
					)
				)
				(pin passive line
					(at 30.48 0 180)
					(length 3.81)
					(hide yes)
					(name "3V3"
						(effects
							(font
								(size 1.27 1.27)
							)
						)
					)
					(number "4"
						(effects
							(font
								(size 1.27 1.27)
							)
						)
					)
				)
				(pin passive line
					(at 30.48 0 180)
					(length 3.81)
					(hide yes)
					(name "3V3"
						(effects
							(font
								(size 1.27 1.27)
							)
						)
					)
					(number "70"
						(effects
							(font
								(size 1.27 1.27)
							)
						)
					)
				)
				(pin passive line
					(at 30.48 0 180)
					(length 3.81)
					(hide yes)
					(name "3V3"
						(effects
							(font
								(size 1.27 1.27)
							)
						)
					)
					(number "72"
						(effects
							(font
								(size 1.27 1.27)
							)
						)
					)
				)
				(pin passive line
					(at 30.48 0 180)
					(length 3.81)
					(hide yes)
					(name "3V3"
						(effects
							(font
								(size 1.27 1.27)
							)
						)
					)
					(number "74"
						(effects
							(font
								(size 1.27 1.27)
							)
						)
					)
				)
				(pin input line
					(at 30.48 -12.7 180)
					(length 3.81)
					(name "SUSCLK"
						(effects
							(font
								(size 1.27 1.27)
							)
						)
					)
					(number "68"
						(effects
							(font
								(size 1.27 1.27)
							)
						)
					)
				)
				(pin output line
					(at 30.48 -26.67 180)
					(length 3.81)
					(name "ALERT"
						(effects
							(font
								(size 1.27 1.27)
							)
						)
					)
					(number "44"
						(effects
							(font
								(size 1.27 1.27)
							)
						)
					)
				)
				(pin bidirectional line
					(at 30.48 -29.21 180)
					(length 3.81)
					(name "SMB_DATA"
						(effects
							(font
								(size 1.27 1.27)
							)
						)
					)
					(number "42"
						(effects
							(font
								(size 1.27 1.27)
							)
						)
					)
				)
				(pin input line
					(at 30.48 -31.75 180)
					(length 3.81)
					(name "SMB_CLK"
						(effects
							(font
								(size 1.27 1.27)
							)
						)
					)
					(number "40"
						(effects
							(font
								(size 1.27 1.27)
							)
						)
					)
				)
				(pin passive line
					(at 30.48 -54.61 180)
					(length 3.81)
					(name "LED"
						(effects
							(font
								(size 1.27 1.27)
							)
						)
					)
					(number "10"
						(effects
							(font
								(size 1.27 1.27)
							)
						)
					)
				)
				(pin passive line
					(at 30.48 -74.93 180)
					(length 3.81)
					(name "SH"
						(effects
							(font
								(size 1.27 1.27)
							)
						)
					)
					(number "SH"
						(effects
							(font
								(size 1.27 1.27)
							)
						)
					)
				)
				(pin power_in line
					(at 30.48 -77.47 180)
					(length 3.81)
					(name "GND"
						(effects
							(font
								(size 1.27 1.27)
							)
						)
					)
					(number "1"
						(effects
							(font
								(size 1.27 1.27)
							)
						)
					)
				)
				(pin passive line
					(at 30.48 -77.47 180)
					(length 3.81)
					(hide yes)
					(name "GND"
						(effects
							(font
								(size 1.27 1.27)
							)
						)
					)
					(number "15"
						(effects
							(font
								(size 1.27 1.27)
							)
						)
					)
				)
				(pin passive line
					(at 30.48 -77.47 180)
					(length 3.81)
					(hide yes)
					(name "GND"
						(effects
							(font
								(size 1.27 1.27)
							)
						)
					)
					(number "21"
						(effects
							(font
								(size 1.27 1.27)
							)
						)
					)
				)
				(pin passive line
					(at 30.48 -77.47 180)
					(length 3.81)
					(hide yes)
					(name "GND"
						(effects
							(font
								(size 1.27 1.27)
							)
						)
					)
					(number "27"
						(effects
							(font
								(size 1.27 1.27)
							)
						)
					)
				)
				(pin passive line
					(at 30.48 -77.47 180)
					(length 3.81)
					(hide yes)
					(name "GND"
						(effects
							(font
								(size 1.27 1.27)
							)
						)
					)
					(number "3"
						(effects
							(font
								(size 1.27 1.27)
							)
						)
					)
				)
				(pin passive line
					(at 30.48 -77.47 180)
					(length 3.81)
					(hide yes)
					(name "GND"
						(effects
							(font
								(size 1.27 1.27)
							)
						)
					)
					(number "33"
						(effects
							(font
								(size 1.27 1.27)
							)
						)
					)
				)
				(pin passive line
					(at 30.48 -77.47 180)
					(length 3.81)
					(hide yes)
					(name "GND"
						(effects
							(font
								(size 1.27 1.27)
							)
						)
					)
					(number "39"
						(effects
							(font
								(size 1.27 1.27)
							)
						)
					)
				)
				(pin passive line
					(at 30.48 -77.47 180)
					(length 3.81)
					(hide yes)
					(name "GND"
						(effects
							(font
								(size 1.27 1.27)
							)
						)
					)
					(number "45"
						(effects
							(font
								(size 1.27 1.27)
							)
						)
					)
				)
				(pin passive line
					(at 30.48 -77.47 180)
					(length 3.81)
					(hide yes)
					(name "GND"
						(effects
							(font
								(size 1.27 1.27)
							)
						)
					)
					(number "51"
						(effects
							(font
								(size 1.27 1.27)
							)
						)
					)
				)
				(pin passive line
					(at 30.48 -77.47 180)
					(length 3.81)
					(hide yes)
					(name "GND"
						(effects
							(font
								(size 1.27 1.27)
							)
						)
					)
					(number "57"
						(effects
							(font
								(size 1.27 1.27)
							)
						)
					)
				)
				(pin passive line
					(at 30.48 -77.47 180)
					(length 3.81)
					(hide yes)
					(name "GND"
						(effects
							(font
								(size 1.27 1.27)
							)
						)
					)
					(number "71"
						(effects
							(font
								(size 1.27 1.27)
							)
						)
					)
				)
				(pin passive line
					(at 30.48 -77.47 180)
					(length 3.81)
					(hide yes)
					(name "GND"
						(effects
							(font
								(size 1.27 1.27)
							)
						)
					)
					(number "73"
						(effects
							(font
								(size 1.27 1.27)
							)
						)
					)
				)
				(pin passive line
					(at 30.48 -77.47 180)
					(length 3.81)
					(hide yes)
					(name "GND"
						(effects
							(font
								(size 1.27 1.27)
							)
						)
					)
					(number "75"
						(effects
							(font
								(size 1.27 1.27)
							)
						)
					)
				)
				(pin passive line
					(at 30.48 -77.47 180)
					(length 3.81)
					(hide yes)
					(name "GND"
						(effects
							(font
								(size 1.27 1.27)
							)
						)
					)
					(number "9"
						(effects
							(font
								(size 1.27 1.27)
							)
						)
					)
				)
			)
		)
	(symbol "antmicroPciConnectors:OCuLink_x4_Amphenol_G14A421211112HR"
			(exclude_from_sim no)
			(in_bom yes)
			(on_board yes)
			(property "Reference" "J"
				(at 39.37 -5.08 0)
				(effects
					(font
						(size 1.27 1.27)
						(thickness 0.15)
					)
					(justify left bottom)
				)
			)
			(property "Value" "OCuLink_x4_Amphenol_G14A421211112HR"
				(at 39.37 -12.7 0)
				(effects
					(font
						(size 1.27 1.27)
						(thickness 0.15)
					)
					(justify left bottom)
					(hide yes)
				)
			)
			(property "Footprint" "antmicro-footprints:Amphenol_G14A421211112HR"
				(at 39.37 -15.24 0)
				(effects
					(font
						(size 1.27 1.27)
						(thickness 0.15)
					)
					(justify left bottom)
					(hide yes)
				)
			)
			(property "Datasheet" "https://cdn.amphenol-cs.com/media/wysiwyg/files/drawing/g14a421x1bxxxhr.pdf"
				(at 39.37 -17.78 0)
				(effects
					(font
						(size 1.27 1.27)
						(thickness 0.15)
					)
					(justify left bottom)
					(hide yes)
				)
			)
			(property "Description" "I/O Connectors OCulink, Receptacle, 0.5mm pitch, 4X, R/A SMT with shell leg SMT type, 30U\" gold plating, LCP, black, T&R packing"
				(at 0 0 0)
				(effects
					(font
						(size 1.27 1.27)
					)
					(hide yes)
				)
			)
			(property "Manufacturer" "Amphenol"
				(at 39.37 -10.16 0)
				(effects
					(font
						(size 1.27 1.27)
						(thickness 0.15)
					)
					(justify left bottom)
					(hide yes)
				)
			)
			(property "MPN" "G14A421211112HR"
				(at 39.37 -7.62 0)
				(effects
					(font
						(size 1.27 1.27)
						(thickness 0.15)
					)
					(justify left bottom)
				)
			)
			(property "Author" "Antmicro"
				(at 39.37 -20.32 0)
				(effects
					(font
						(size 1.27 1.27)
						(thickness 0.15)
					)
					(justify left bottom)
					(hide yes)
				)
			)
			(property "License" "Apache-2.0"
				(at 39.37 -22.86 0)
				(effects
					(font
						(size 1.27 1.27)
						(thickness 0.15)
					)
					(justify left bottom)
					(hide yes)
				)
			)
			(property "ki_keywords" "SMT, CONNECTOR, PCIE"
				(at 0 0 0)
				(effects
					(font
						(size 1.27 1.27)
					)
					(hide yes)
				)
			)
			(symbol "OCuLink_x4_Amphenol_G14A421211112HR_1_1"
				(rectangle
					(start 3.81 2.54)
					(end 21.59 -93.98)
					(stroke
						(width 0.254)
						(type default)
					)
					(fill
						(type background)
					)
				)
				(pin passive line
					(at 0 0 0)
					(length 3.81)
					(name "5V"
						(effects
							(font
								(size 1.27 1.27)
							)
						)
					)
					(number "A21"
						(effects
							(font
								(size 1.27 1.27)
							)
						)
					)
				)
				(pin passive line
					(at 0 0 0)
					(length 3.81)
					(hide yes)
					(name "5V"
						(effects
							(font
								(size 1.27 1.27)
							)
						)
					)
					(number "B1"
						(effects
							(font
								(size 1.27 1.27)
							)
						)
					)
				)
				(pin power_in line
					(at 0 -2.54 0)
					(length 3.81)
					(name "V_{ACT}_RX_3V3"
						(effects
							(font
								(size 1.27 1.27)
							)
						)
					)
					(number "A1"
						(effects
							(font
								(size 1.27 1.27)
							)
						)
					)
				)
				(pin power_in line
					(at 0 -5.08 0)
					(length 3.81)
					(name "V_{ACT}_TX_3V3"
						(effects
							(font
								(size 1.27 1.27)
							)
						)
					)
					(number "B21"
						(effects
							(font
								(size 1.27 1.27)
							)
						)
					)
				)
				(pin bidirectional line
					(at 0 -10.16 0)
					(length 3.81)
					(name "SCL"
						(effects
							(font
								(size 1.27 1.27)
							)
						)
					)
					(number "B9"
						(effects
							(font
								(size 1.27 1.27)
							)
						)
					)
				)
				(pin bidirectional line
					(at 0 -12.7 0)
					(length 3.81)
					(name "SDA"
						(effects
							(font
								(size 1.27 1.27)
							)
						)
					)
					(number "B10"
						(effects
							(font
								(size 1.27 1.27)
							)
						)
					)
				)
				(pin bidirectional line
					(at 0 -17.78 0)
					(length 3.81)
					(name "VSP1"
						(effects
							(font
								(size 1.27 1.27)
							)
						)
					)
					(number "A12"
						(effects
							(font
								(size 1.27 1.27)
							)
						)
					)
				)
				(pin bidirectional line
					(at 0 -20.32 0)
					(length 3.81)
					(name "VSP2"
						(effects
							(font
								(size 1.27 1.27)
							)
						)
					)
					(number "A13"
						(effects
							(font
								(size 1.27 1.27)
							)
						)
					)
				)
				(pin bidirectional line
					(at 0 -25.4 0)
					(length 3.81)
					(name "~{PERST}"
						(effects
							(font
								(size 1.27 1.27)
							)
						)
					)
					(number "B12"
						(effects
							(font
								(size 1.27 1.27)
							)
						)
					)
				)
				(pin bidirectional line
					(at 0 -27.94 0)
					(length 3.81)
					(name "~{CPRSNT}"
						(effects
							(font
								(size 1.27 1.27)
							)
						)
					)
					(number "B13"
						(effects
							(font
								(size 1.27 1.27)
							)
						)
					)
				)
				(pin bidirectional line
					(at 0 -30.48 0)
					(length 3.81)
					(name "~{CWAKE}"
						(effects
							(font
								(size 1.27 1.27)
							)
						)
					)
					(number "A10"
						(effects
							(font
								(size 1.27 1.27)
							)
						)
					)
				)
				(pin output line
					(at 0 -35.56 0)
					(length 3.81)
					(name "PER0+"
						(effects
							(font
								(size 1.27 1.27)
							)
						)
					)
					(number "A3"
						(effects
							(font
								(size 1.27 1.27)
							)
						)
					)
				)
				(pin output line
					(at 0 -38.1 0)
					(length 3.81)
					(name "PER0-"
						(effects
							(font
								(size 1.27 1.27)
							)
						)
					)
					(number "A4"
						(effects
							(font
								(size 1.27 1.27)
							)
						)
					)
				)
				(pin output line
					(at 0 -43.18 0)
					(length 3.81)
					(name "PER1+"
						(effects
							(font
								(size 1.27 1.27)
							)
						)
					)
					(number "A6"
						(effects
							(font
								(size 1.27 1.27)
							)
						)
					)
				)
				(pin output line
					(at 0 -45.72 0)
					(length 3.81)
					(name "PER1-"
						(effects
							(font
								(size 1.27 1.27)
							)
						)
					)
					(number "A7"
						(effects
							(font
								(size 1.27 1.27)
							)
						)
					)
				)
				(pin output line
					(at 0 -50.8 0)
					(length 3.81)
					(name "PER2+"
						(effects
							(font
								(size 1.27 1.27)
							)
						)
					)
					(number "A15"
						(effects
							(font
								(size 1.27 1.27)
							)
						)
					)
				)
				(pin output line
					(at 0 -53.34 0)
					(length 3.81)
					(name "PER2-"
						(effects
							(font
								(size 1.27 1.27)
							)
						)
					)
					(number "A16"
						(effects
							(font
								(size 1.27 1.27)
							)
						)
					)
				)
				(pin output line
					(at 0 -58.42 0)
					(length 3.81)
					(name "PER3+"
						(effects
							(font
								(size 1.27 1.27)
							)
						)
					)
					(number "A18"
						(effects
							(font
								(size 1.27 1.27)
							)
						)
					)
				)
				(pin output line
					(at 0 -60.96 0)
					(length 3.81)
					(name "PER3-"
						(effects
							(font
								(size 1.27 1.27)
							)
						)
					)
					(number "A19"
						(effects
							(font
								(size 1.27 1.27)
							)
						)
					)
				)
				(pin input line
					(at 0 -66.04 0)
					(length 3.81)
					(name "PET0+"
						(effects
							(font
								(size 1.27 1.27)
							)
						)
					)
					(number "B3"
						(effects
							(font
								(size 1.27 1.27)
							)
						)
					)
				)
				(pin input line
					(at 0 -68.58 0)
					(length 3.81)
					(name "PET0-"
						(effects
							(font
								(size 1.27 1.27)
							)
						)
					)
					(number "B4"
						(effects
							(font
								(size 1.27 1.27)
							)
						)
					)
				)
				(pin input line
					(at 0 -73.66 0)
					(length 3.81)
					(name "PET1+"
						(effects
							(font
								(size 1.27 1.27)
							)
						)
					)
					(number "B6"
						(effects
							(font
								(size 1.27 1.27)
							)
						)
					)
				)
				(pin input line
					(at 0 -76.2 0)
					(length 3.81)
					(name "PET1-"
						(effects
							(font
								(size 1.27 1.27)
							)
						)
					)
					(number "B7"
						(effects
							(font
								(size 1.27 1.27)
							)
						)
					)
				)
				(pin input line
					(at 0 -81.28 0)
					(length 3.81)
					(name "PET2+"
						(effects
							(font
								(size 1.27 1.27)
							)
						)
					)
					(number "B15"
						(effects
							(font
								(size 1.27 1.27)
							)
						)
					)
				)
				(pin input line
					(at 0 -83.82 0)
					(length 3.81)
					(name "PET2-"
						(effects
							(font
								(size 1.27 1.27)
							)
						)
					)
					(number "B16"
						(effects
							(font
								(size 1.27 1.27)
							)
						)
					)
				)
				(pin input line
					(at 0 -88.9 0)
					(length 3.81)
					(name "PET3+"
						(effects
							(font
								(size 1.27 1.27)
							)
						)
					)
					(number "B18"
						(effects
							(font
								(size 1.27 1.27)
							)
						)
					)
				)
				(pin input line
					(at 0 -91.44 0)
					(length 3.81)
					(name "PET3-"
						(effects
							(font
								(size 1.27 1.27)
							)
						)
					)
					(number "B19"
						(effects
							(font
								(size 1.27 1.27)
							)
						)
					)
				)
				(pin no_connect line
					(at 21.59 -76.2 180)
					(length 3.81)
					(hide yes)
					(name "NC"
						(effects
							(font
								(size 1.27 1.27)
							)
						)
					)
					(number "A9"
						(effects
							(font
								(size 1.27 1.27)
							)
						)
					)
				)
				(pin passive line
					(at 25.4 -88.9 180)
					(length 3.81)
					(name "SH"
						(effects
							(font
								(size 1.27 1.27)
							)
						)
					)
					(number "SH"
						(effects
							(font
								(size 1.27 1.27)
							)
						)
					)
				)
				(pin passive line
					(at 25.4 -91.44 180)
					(length 3.81)
					(name "GND"
						(effects
							(font
								(size 1.27 1.27)
							)
						)
					)
					(number "A11"
						(effects
							(font
								(size 1.27 1.27)
							)
						)
					)
				)
				(pin passive line
					(at 25.4 -91.44 180)
					(length 3.81)
					(hide yes)
					(name "GND"
						(effects
							(font
								(size 1.27 1.27)
							)
						)
					)
					(number "A14"
						(effects
							(font
								(size 1.27 1.27)
							)
						)
					)
				)
				(pin passive line
					(at 25.4 -91.44 180)
					(length 3.81)
					(hide yes)
					(name "GND"
						(effects
							(font
								(size 1.27 1.27)
							)
						)
					)
					(number "A17"
						(effects
							(font
								(size 1.27 1.27)
							)
						)
					)
				)
				(pin passive line
					(at 25.4 -91.44 180)
					(length 3.81)
					(hide yes)
					(name "GND"
						(effects
							(font
								(size 1.27 1.27)
							)
						)
					)
					(number "A2"
						(effects
							(font
								(size 1.27 1.27)
							)
						)
					)
				)
				(pin passive line
					(at 25.4 -91.44 180)
					(length 3.81)
					(hide yes)
					(name "GND"
						(effects
							(font
								(size 1.27 1.27)
							)
						)
					)
					(number "A20"
						(effects
							(font
								(size 1.27 1.27)
							)
						)
					)
				)
				(pin passive line
					(at 25.4 -91.44 180)
					(length 3.81)
					(hide yes)
					(name "GND"
						(effects
							(font
								(size 1.27 1.27)
							)
						)
					)
					(number "A5"
						(effects
							(font
								(size 1.27 1.27)
							)
						)
					)
				)
				(pin passive line
					(at 25.4 -91.44 180)
					(length 3.81)
					(hide yes)
					(name "GND"
						(effects
							(font
								(size 1.27 1.27)
							)
						)
					)
					(number "A8"
						(effects
							(font
								(size 1.27 1.27)
							)
						)
					)
				)
				(pin passive line
					(at 25.4 -91.44 180)
					(length 3.81)
					(hide yes)
					(name "GND"
						(effects
							(font
								(size 1.27 1.27)
							)
						)
					)
					(number "B11"
						(effects
							(font
								(size 1.27 1.27)
							)
						)
					)
				)
				(pin passive line
					(at 25.4 -91.44 180)
					(length 3.81)
					(hide yes)
					(name "GND"
						(effects
							(font
								(size 1.27 1.27)
							)
						)
					)
					(number "B14"
						(effects
							(font
								(size 1.27 1.27)
							)
						)
					)
				)
				(pin passive line
					(at 25.4 -91.44 180)
					(length 3.81)
					(hide yes)
					(name "GND"
						(effects
							(font
								(size 1.27 1.27)
							)
						)
					)
					(number "B17"
						(effects
							(font
								(size 1.27 1.27)
							)
						)
					)
				)
				(pin passive line
					(at 25.4 -91.44 180)
					(length 3.81)
					(hide yes)
					(name "GND"
						(effects
							(font
								(size 1.27 1.27)
							)
						)
					)
					(number "B2"
						(effects
							(font
								(size 1.27 1.27)
							)
						)
					)
				)
				(pin passive line
					(at 25.4 -91.44 180)
					(length 3.81)
					(hide yes)
					(name "GND"
						(effects
							(font
								(size 1.27 1.27)
							)
						)
					)
					(number "B20"
						(effects
							(font
								(size 1.27 1.27)
							)
						)
					)
				)
				(pin passive line
					(at 25.4 -91.44 180)
					(length 3.81)
					(hide yes)
					(name "GND"
						(effects
							(font
								(size 1.27 1.27)
							)
						)
					)
					(number "B5"
						(effects
							(font
								(size 1.27 1.27)
							)
						)
					)
				)
				(pin passive line
					(at 25.4 -91.44 180)
					(length 3.81)
					(hide yes)
					(name "GND"
						(effects
							(font
								(size 1.27 1.27)
							)
						)
					)
					(number "B8"
						(effects
							(font
								(size 1.27 1.27)
							)
						)
					)
				)
			)
		)
	(symbol "antmicroPowerMeasurement:INA219AIDCNR"
			(exclude_from_sim no)
			(in_bom yes)
			(on_board yes)
			(property "Reference" "U"
				(at 25.4 -5.08 0)
				(effects
					(font
						(size 1.27 1.27)
						(thickness 0.15)
					)
					(justify left bottom)
				)
			)
			(property "Value" "INA219AIDCNR"
				(at 25.4 -10.16 0)
				(effects
					(font
						(size 1.27 1.27)
						(thickness 0.15)
					)
					(justify left bottom)
					(hide yes)
				)
			)
			(property "Footprint" "antmicro-footprints:SOT-23-8"
				(at 25.4 -12.7 0)
				(effects
					(font
						(size 1.27 1.27)
						(thickness 0.15)
					)
					(justify left bottom)
					(hide yes)
				)
			)
			(property "Datasheet" "https://www.ti.com/lit/ds/symlink/ina219.pdf?ts=1713856455637&ref_url=https%253A%252F%252Fwww.mouser.es%252F"
				(at 25.4 -15.24 0)
				(effects
					(font
						(size 1.27 1.27)
						(thickness 0.15)
					)
					(justify left bottom)
					(hide yes)
				)
			)
			(property "Description" "Zerø-Drift, Bidirectional Current/Power Monitor With I2C Interface"
				(at 0 0 0)
				(effects
					(font
						(size 1.27 1.27)
					)
					(hide yes)
				)
			)
			(property "Manufacturer" "Texas Instruments"
				(at 25.4 -17.78 0)
				(effects
					(font
						(size 1.27 1.27)
						(thickness 0.15)
					)
					(justify left bottom)
					(hide yes)
				)
			)
			(property "MPN" "INA219AIDCNR"
				(at 25.4 -7.62 0)
				(effects
					(font
						(size 1.27 1.27)
						(thickness 0.15)
					)
					(justify left bottom)
				)
			)
			(property "Author" "Antmicro"
				(at 25.4 -20.32 0)
				(effects
					(font
						(size 1.27 1.27)
						(thickness 0.15)
					)
					(justify left bottom)
					(hide yes)
				)
			)
			(property "License" "Apache-2.0"
				(at 25.4 -22.86 0)
				(effects
					(font
						(size 1.27 1.27)
						(thickness 0.15)
					)
					(justify left bottom)
					(hide yes)
				)
			)
			(property "ki_keywords" "IC, PMIC, SMT, MONITOR"
				(at 0 0 0)
				(effects
					(font
						(size 1.27 1.27)
					)
					(hide yes)
				)
			)
			(symbol "INA219AIDCNR_1_1"
				(rectangle
					(start 2.54 1.27)
					(end 12.7 -13.97)
					(stroke
						(width 0.254)
						(type default)
					)
					(fill
						(type background)
					)
				)
				(pin passive line
					(at 0 0 0)
					(length 2.54)
					(name "IN+"
						(effects
							(font
								(size 1.27 1.27)
							)
						)
					)
					(number "1"
						(effects
							(font
								(size 1.27 1.27)
							)
						)
					)
				)
				(pin open_collector line
					(at 0 -5.08 0)
					(length 2.54)
					(name "SDA"
						(effects
							(font
								(size 1.27 1.27)
							)
						)
					)
					(number "6"
						(effects
							(font
								(size 1.27 1.27)
							)
						)
					)
				)
				(pin open_collector line
					(at 0 -7.62 0)
					(length 2.54)
					(name "SCL"
						(effects
							(font
								(size 1.27 1.27)
							)
						)
					)
					(number "5"
						(effects
							(font
								(size 1.27 1.27)
							)
						)
					)
				)
				(pin passive line
					(at 0 -10.16 0)
					(length 2.54)
					(name "A1"
						(effects
							(font
								(size 1.27 1.27)
							)
						)
					)
					(number "8"
						(effects
							(font
								(size 1.27 1.27)
							)
						)
					)
				)
				(pin passive line
					(at 0 -12.7 0)
					(length 2.54)
					(name "A0"
						(effects
							(font
								(size 1.27 1.27)
							)
						)
					)
					(number "7"
						(effects
							(font
								(size 1.27 1.27)
							)
						)
					)
				)
				(pin passive line
					(at 15.24 0 180)
					(length 2.54)
					(name "IN-"
						(effects
							(font
								(size 1.27 1.27)
							)
						)
					)
					(number "2"
						(effects
							(font
								(size 1.27 1.27)
							)
						)
					)
				)
				(pin power_in line
					(at 15.24 -5.08 180)
					(length 2.54)
					(name "V_{S}"
						(effects
							(font
								(size 1.27 1.27)
							)
						)
					)
					(number "4"
						(effects
							(font
								(size 1.27 1.27)
							)
						)
					)
				)
				(pin power_in line
					(at 15.24 -12.7 180)
					(length 2.54)
					(name "GND"
						(effects
							(font
								(size 1.27 1.27)
							)
						)
					)
					(number "3"
						(effects
							(font
								(size 1.27 1.27)
							)
						)
					)
				)
			)
		)
	(symbol "antmicroPushbuttonSwitches:SW_1-1825027-1_THT"
			(pin_names
				(hide yes)
			)
			(exclude_from_sim no)
			(in_bom yes)
			(on_board yes)
			(property "Reference" "SW"
				(at 25.4 -5.08 0)
				(effects
					(font
						(size 1.27 1.27)
						(thickness 0.15)
					)
					(justify left bottom)
				)
			)
			(property "Value" "SW_1-1825027-1_THT"
				(at 25.4 -7.62 0)
				(effects
					(font
						(size 1.27 1.27)
						(thickness 0.15)
					)
					(justify left bottom)
					(hide yes)
				)
			)
			(property "Footprint" "antmicro-footprints:SW_1-1825027-1_THT"
				(at 25.4 -10.16 0)
				(effects
					(font
						(size 1.27 1.27)
						(thickness 0.15)
					)
					(justify left bottom)
					(hide yes)
				)
			)
			(property "Datasheet" "https://www.te.com/commerce/DocumentDelivery/DDEController?Action=showdoc&DocId=Customer+Drawing%7F1825027%7FH1%7Fpdf%7FEnglish%7FENG_CD_1825027_H1.pdf%7F1-1825027-1"
				(at 25.4 -12.7 0)
				(effects
					(font
						(size 1.27 1.27)
						(thickness 0.15)
					)
					(justify left bottom)
					(hide yes)
				)
			)
			(property "Description" "Tactile Switch, Side Actuated, Through Hole, Round Button, 160 gf, 50mA at 24VDC"
				(at 0 0 0)
				(effects
					(font
						(size 1.27 1.27)
					)
					(hide yes)
				)
			)
			(property "MPN" "1-1825027-1"
				(at 25.4 -15.24 0)
				(effects
					(font
						(size 1.27 1.27)
						(thickness 0.15)
					)
					(justify left bottom)
				)
			)
			(property "Manufacturer" "TE Connectivity"
				(at 25.4 -17.78 0)
				(effects
					(font
						(size 1.27 1.27)
						(thickness 0.15)
					)
					(justify left bottom)
					(hide yes)
				)
			)
			(property "Author" "Antmicro"
				(at 25.4 -20.32 0)
				(effects
					(font
						(size 1.27 1.27)
						(thickness 0.15)
					)
					(justify left bottom)
					(hide yes)
				)
			)
			(property "License" "Apache-2.0"
				(at 25.4 -22.86 0)
				(effects
					(font
						(size 1.27 1.27)
						(thickness 0.15)
					)
					(justify left bottom)
					(hide yes)
				)
			)
			(property "ki_keywords" "HORIZONTAL, SWITCH, THT, MECHANICAL, TACTILE"
				(at 0 0 0)
				(effects
					(font
						(size 1.27 1.27)
					)
					(hide yes)
				)
			)
			(symbol "SW_1-1825027-1_THT_1_1"
				(polyline
					(pts
						(xy 2.54 0) (xy 3.302 0)
					)
					(stroke
						(width 0.254)
						(type default)
					)
					(fill
						(type none)
					)
				)
				(polyline
					(pts
						(xy 3.302 1.27) (xy 6.858 1.27)
					)
					(stroke
						(width 0.254)
						(type default)
					)
					(fill
						(type none)
					)
				)
				(polyline
					(pts
						(xy 3.302 -1.016) (xy 6.858 -1.016)
					)
					(stroke
						(width 0.254)
						(type default)
					)
					(fill
						(type none)
					)
				)
				(circle
					(center 3.556 0)
					(radius 0.254)
					(stroke
						(width 0.254)
						(type default)
					)
					(fill
						(type none)
					)
				)
				(polyline
					(pts
						(xy 4.064 2.794) (xy 6.096 2.794)
					)
					(stroke
						(width 0.254)
						(type default)
					)
					(fill
						(type none)
					)
				)
				(polyline
					(pts
						(xy 5.08 1.27) (xy 5.08 2.794)
					)
					(stroke
						(width 0.254)
						(type default)
					)
					(fill
						(type none)
					)
				)
				(circle
					(center 6.604 0)
					(radius 0.254)
					(stroke
						(width 0.254)
						(type default)
					)
					(fill
						(type none)
					)
				)
				(polyline
					(pts
						(xy 7.62 0) (xy 6.858 0)
					)
					(stroke
						(width 0.254)
						(type default)
					)
					(fill
						(type none)
					)
				)
				(polyline
					(pts
						(xy 7.62 -2.54) (xy 5.08 -2.54) (xy 5.08 -1.016)
					)
					(stroke
						(width 0.254)
						(type default)
					)
					(fill
						(type none)
					)
				)
				(pin passive line
					(at 0 0 0)
					(length 2.54)
					(name "1"
						(effects
							(font
								(size 1.27 1.27)
							)
						)
					)
					(number "1"
						(effects
							(font
								(size 1.27 1.27)
							)
						)
					)
				)
				(pin passive line
					(at 10.16 0 180)
					(length 2.54)
					(name "2"
						(effects
							(font
								(size 1.27 1.27)
							)
						)
					)
					(number "2"
						(effects
							(font
								(size 1.27 1.27)
							)
						)
					)
				)
				(pin passive line
					(at 10.16 -2.54 180)
					(length 2.54)
					(name "SH"
						(effects
							(font
								(size 1.27 1.27)
							)
						)
					)
					(number "SH"
						(effects
							(font
								(size 1.27 1.27)
							)
						)
					)
				)
			)
		)
	(symbol "antmicroResistors0402:R_0R_0402"
			(pin_numbers
				(hide yes)
			)
			(pin_names
				(hide yes)
			)
			(exclude_from_sim no)
			(in_bom yes)
			(on_board yes)
			(property "Reference" "R"
				(at 20.32 -5.08 0)
				(effects
					(font
						(size 1.27 1.27)
						(thickness 0.15)
					)
					(justify left bottom)
				)
			)
			(property "Value" "R_0R_0402"
				(at 20.32 -12.7 0)
				(effects
					(font
						(size 1.27 1.27)
						(thickness 0.15)
					)
					(justify left bottom)
					(hide yes)
				)
			)
			(property "Footprint" "antmicro-footprints:R_0402_1005Metric"
				(at 20.32 -15.24 0)
				(effects
					(font
						(size 1.27 1.27)
						(thickness 0.15)
					)
					(justify left bottom)
					(hide yes)
				)
			)
			(property "Datasheet" "https://industrial.panasonic.com/cdbs/www-data/pdf/RDA0000/AOA0000C301.pdf"
				(at 20.32 -17.78 0)
				(effects
					(font
						(size 1.27 1.27)
						(thickness 0.15)
					)
					(justify left bottom)
					(hide yes)
				)
			)
			(property "Description" "SMD Chip Resistor, Jumper, 0 ohm, 100 mW, 0402 [1005 Metric], Thick Film, General Purpose"
				(at 0 0 0)
				(effects
					(font
						(size 1.27 1.27)
					)
					(hide yes)
				)
			)
			(property "MPN" "ERJ2GE0R00X"
				(at 20.32 -20.32 0)
				(effects
					(font
						(size 1.27 1.27)
						(thickness 0.15)
					)
					(justify left bottom)
					(hide yes)
				)
			)
			(property "Manufacturer" "Panasonic"
				(at 20.32 -22.86 0)
				(effects
					(font
						(size 1.27 1.27)
						(thickness 0.15)
					)
					(justify left bottom)
					(hide yes)
				)
			)
			(property "License" "Apache-2.0"
				(at 20.32 -25.4 0)
				(effects
					(font
						(size 1.27 1.27)
						(thickness 0.15)
					)
					(justify left bottom)
					(hide yes)
				)
			)
			(property "Author" "Antmicro"
				(at 20.32 -27.94 0)
				(effects
					(font
						(size 1.27 1.27)
						(thickness 0.15)
					)
					(justify left bottom)
					(hide yes)
				)
			)
			(property "Val" "0R"
				(at 20.32 -7.62 0)
				(effects
					(font
						(size 1.27 1.27)
						(thickness 0.15)
					)
					(justify left bottom)
				)
			)
			(property "Tolerance" "~"
				(at 20.32 -10.16 0)
				(effects
					(font
						(size 1.27 1.27)
					)
					(justify left bottom)
					(hide yes)
				)
			)
			(property "Current" "1A"
				(at 20.32 -30.48 0)
				(effects
					(font
						(size 1.27 1.27)
						(thickness 0.15)
					)
					(justify left bottom)
					(hide yes)
				)
			)
			(property "Public" "False"
				(at 20.32 -30.48 0)
				(effects
					(font
						(size 1.27 1.27)
					)
					(justify left bottom)
					(hide yes)
				)
			)
			(property "ki_keywords" "0402, SMT, RESISTOR, PASSIVE"
				(at 0 0 0)
				(effects
					(font
						(size 1.27 1.27)
					)
					(hide yes)
				)
			)
			(symbol "R_0R_0402_0_1"
				(rectangle
					(start 0.635 0.889)
					(end 4.445 -0.889)
					(stroke
						(width 0.254)
						(type default)
					)
					(fill
						(type none)
					)
				)
			)
			(symbol "R_0R_0402_1_1"
				(pin passive line
					(at 0 0 0)
					(length 0.635)
					(name "~"
						(effects
							(font
								(size 1.27 1.27)
							)
						)
					)
					(number "1"
						(effects
							(font
								(size 1.27 1.27)
							)
						)
					)
				)
				(pin passive line
					(at 5.08 0 180)
					(length 0.635)
					(name "~"
						(effects
							(font
								(size 1.27 1.27)
							)
						)
					)
					(number "2"
						(effects
							(font
								(size 1.27 1.27)
							)
						)
					)
				)
			)
		)
	(symbol "antmicroResistors0402:R_100k_0402"
			(pin_numbers
				(hide yes)
			)
			(pin_names
				(hide yes)
			)
			(exclude_from_sim no)
			(in_bom yes)
			(on_board yes)
			(property "Reference" "R"
				(at 20.32 -5.08 0)
				(effects
					(font
						(size 1.27 1.27)
						(thickness 0.15)
					)
					(justify left bottom)
				)
			)
			(property "Value" "R_100k_0402"
				(at 20.32 -12.7 0)
				(effects
					(font
						(size 1.27 1.27)
						(thickness 0.15)
					)
					(justify left bottom)
					(hide yes)
				)
			)
			(property "Footprint" "antmicro-footprints:R_0402_1005Metric"
				(at 20.32 -15.24 0)
				(effects
					(font
						(size 1.27 1.27)
						(thickness 0.15)
					)
					(justify left bottom)
					(hide yes)
				)
			)
			(property "Datasheet" "https://www.bourns.com/docs/product-datasheets/cr.pdf"
				(at 20.32 -17.78 0)
				(effects
					(font
						(size 1.27 1.27)
						(thickness 0.15)
					)
					(justify left bottom)
					(hide yes)
				)
			)
			(property "Description" "SMD Chip Resistor, 100 kohm, ± 1%, 62.5 mW, 0402 [1005 Metric], Thick Film, General Purpose"
				(at 0 0 0)
				(effects
					(font
						(size 1.27 1.27)
					)
					(hide yes)
				)
			)
			(property "MPN" "CR0402-FX-1003GLF"
				(at 20.32 -20.32 0)
				(effects
					(font
						(size 1.27 1.27)
						(thickness 0.15)
					)
					(justify left bottom)
					(hide yes)
				)
			)
			(property "Manufacturer" "Bourns"
				(at 20.32 -22.86 0)
				(effects
					(font
						(size 1.27 1.27)
						(thickness 0.15)
					)
					(justify left bottom)
					(hide yes)
				)
			)
			(property "License" "Apache-2.0"
				(at 20.32 -25.4 0)
				(effects
					(font
						(size 1.27 1.27)
						(thickness 0.15)
					)
					(justify left bottom)
					(hide yes)
				)
			)
			(property "Author" "Antmicro"
				(at 20.32 -27.94 0)
				(effects
					(font
						(size 1.27 1.27)
						(thickness 0.15)
					)
					(justify left bottom)
					(hide yes)
				)
			)
			(property "Val" "100k"
				(at 20.32 -7.62 0)
				(effects
					(font
						(size 1.27 1.27)
						(thickness 0.15)
					)
					(justify left bottom)
				)
			)
			(property "Tolerance" "1%"
				(at 20.32 -10.16 0)
				(effects
					(font
						(size 1.27 1.27)
					)
					(justify left bottom)
					(hide yes)
				)
			)
			(property "Public" "False"
				(at 20.32 -30.48 0)
				(effects
					(font
						(size 1.27 1.27)
					)
					(justify left bottom)
					(hide yes)
				)
			)
			(property "ki_keywords" "0402, SMT, RESISTOR, PASSIVE"
				(at 0 0 0)
				(effects
					(font
						(size 1.27 1.27)
					)
					(hide yes)
				)
			)
			(symbol "R_100k_0402_0_1"
				(rectangle
					(start 0.635 0.889)
					(end 4.445 -0.889)
					(stroke
						(width 0.254)
						(type default)
					)
					(fill
						(type none)
					)
				)
			)
			(symbol "R_100k_0402_1_1"
				(pin passive line
					(at 0 0 0)
					(length 0.635)
					(name "~"
						(effects
							(font
								(size 1.27 1.27)
							)
						)
					)
					(number "1"
						(effects
							(font
								(size 1.27 1.27)
							)
						)
					)
				)
				(pin passive line
					(at 5.08 0 180)
					(length 0.635)
					(name "~"
						(effects
							(font
								(size 1.27 1.27)
							)
						)
					)
					(number "2"
						(effects
							(font
								(size 1.27 1.27)
							)
						)
					)
				)
			)
		)
	(symbol "antmicroResistors0402:R_10k_0402"
			(pin_numbers
				(hide yes)
			)
			(pin_names
				(hide yes)
			)
			(exclude_from_sim no)
			(in_bom yes)
			(on_board yes)
			(property "Reference" "R"
				(at 20.32 -5.08 0)
				(effects
					(font
						(size 1.27 1.27)
						(thickness 0.15)
					)
					(justify left bottom)
				)
			)
			(property "Value" "R_10k_0402"
				(at 20.32 -12.7 0)
				(effects
					(font
						(size 1.27 1.27)
						(thickness 0.15)
					)
					(justify left bottom)
					(hide yes)
				)
			)
			(property "Footprint" "antmicro-footprints:R_0402_1005Metric"
				(at 20.32 -15.24 0)
				(effects
					(font
						(size 1.27 1.27)
						(thickness 0.15)
					)
					(justify left bottom)
					(hide yes)
				)
			)
			(property "Datasheet" "https://www.bourns.com/docs/product-datasheets/cr.pdf"
				(at 20.32 -17.78 0)
				(effects
					(font
						(size 1.27 1.27)
						(thickness 0.15)
					)
					(justify left bottom)
					(hide yes)
				)
			)
			(property "Description" "SMD Chip Resistor, 10 kohm, ± 1%, 62.5 mW, 0402 [1005 Metric], Thick Film, General Purpose"
				(at 0 0 0)
				(effects
					(font
						(size 1.27 1.27)
					)
					(hide yes)
				)
			)
			(property "MPN" "CR0402-FX-1002GLF"
				(at 20.32 -20.32 0)
				(effects
					(font
						(size 1.27 1.27)
						(thickness 0.15)
					)
					(justify left bottom)
					(hide yes)
				)
			)
			(property "Manufacturer" "Bourns"
				(at 20.32 -22.86 0)
				(effects
					(font
						(size 1.27 1.27)
						(thickness 0.15)
					)
					(justify left bottom)
					(hide yes)
				)
			)
			(property "License" "Apache-2.0"
				(at 20.32 -25.4 0)
				(effects
					(font
						(size 1.27 1.27)
						(thickness 0.15)
					)
					(justify left bottom)
					(hide yes)
				)
			)
			(property "Author" "Antmicro"
				(at 20.32 -27.94 0)
				(effects
					(font
						(size 1.27 1.27)
						(thickness 0.15)
					)
					(justify left bottom)
					(hide yes)
				)
			)
			(property "Val" "10k"
				(at 20.32 -7.62 0)
				(effects
					(font
						(size 1.27 1.27)
						(thickness 0.15)
					)
					(justify left bottom)
				)
			)
			(property "Tolerance" "1%"
				(at 20.32 -10.16 0)
				(effects
					(font
						(size 1.27 1.27)
					)
					(justify left bottom)
					(hide yes)
				)
			)
			(property "Public" "False"
				(at 20.32 -30.48 0)
				(effects
					(font
						(size 1.27 1.27)
					)
					(justify left bottom)
					(hide yes)
				)
			)
			(property "ki_keywords" "0402, SMT, RESISTOR, PASSIVE"
				(at 0 0 0)
				(effects
					(font
						(size 1.27 1.27)
					)
					(hide yes)
				)
			)
			(symbol "R_10k_0402_0_1"
				(rectangle
					(start 0.635 0.889)
					(end 4.445 -0.889)
					(stroke
						(width 0.254)
						(type default)
					)
					(fill
						(type none)
					)
				)
			)
			(symbol "R_10k_0402_1_1"
				(pin passive line
					(at 0 0 0)
					(length 0.635)
					(name "~"
						(effects
							(font
								(size 1.27 1.27)
							)
						)
					)
					(number "1"
						(effects
							(font
								(size 1.27 1.27)
							)
						)
					)
				)
				(pin passive line
					(at 5.08 0 180)
					(length 0.635)
					(name "~"
						(effects
							(font
								(size 1.27 1.27)
							)
						)
					)
					(number "2"
						(effects
							(font
								(size 1.27 1.27)
							)
						)
					)
				)
			)
		)
	(symbol "antmicroResistors0402:R_110k_0402"
			(pin_numbers
				(hide yes)
			)
			(pin_names
				(hide yes)
			)
			(exclude_from_sim no)
			(in_bom yes)
			(on_board yes)
			(property "Reference" "R"
				(at 20.32 -5.08 0)
				(effects
					(font
						(size 1.27 1.27)
						(thickness 0.15)
					)
					(justify left bottom)
				)
			)
			(property "Value" "R_110k_0402"
				(at 20.32 -12.7 0)
				(effects
					(font
						(size 1.27 1.27)
						(thickness 0.15)
					)
					(justify left bottom)
					(hide yes)
				)
			)
			(property "Footprint" "antmicro-footprints:R_0402_1005Metric"
				(at 20.32 -15.24 0)
				(effects
					(font
						(size 1.27 1.27)
						(thickness 0.15)
					)
					(justify left bottom)
					(hide yes)
				)
			)
			(property "Datasheet" "https://www.bourns.com/docs/product-datasheets/cr.pdf"
				(at 20.32 -17.78 0)
				(effects
					(font
						(size 1.27 1.27)
						(thickness 0.15)
					)
					(justify left bottom)
					(hide yes)
				)
			)
			(property "Description" "SMD Chip Resistor, 110 kohm, ± 1%, 63 mW, 0402 [1005 Metric], Thick Film, General Purpose"
				(at 0 0 0)
				(effects
					(font
						(size 1.27 1.27)
					)
					(hide yes)
				)
			)
			(property "MPN" "CR0402-FX-1103GLF"
				(at 20.32 -20.32 0)
				(effects
					(font
						(size 1.27 1.27)
						(thickness 0.15)
					)
					(justify left bottom)
					(hide yes)
				)
			)
			(property "Manufacturer" "Bourns"
				(at 20.32 -22.86 0)
				(effects
					(font
						(size 1.27 1.27)
						(thickness 0.15)
					)
					(justify left bottom)
					(hide yes)
				)
			)
			(property "License" "Apache-2.0"
				(at 20.32 -25.4 0)
				(effects
					(font
						(size 1.27 1.27)
						(thickness 0.15)
					)
					(justify left bottom)
					(hide yes)
				)
			)
			(property "Author" "Antmicro"
				(at 20.32 -27.94 0)
				(effects
					(font
						(size 1.27 1.27)
						(thickness 0.15)
					)
					(justify left bottom)
					(hide yes)
				)
			)
			(property "Val" "110k"
				(at 20.32 -7.62 0)
				(effects
					(font
						(size 1.27 1.27)
						(thickness 0.15)
					)
					(justify left bottom)
				)
			)
			(property "Tolerance" "1%"
				(at 20.32 -10.16 0)
				(effects
					(font
						(size 1.27 1.27)
					)
					(justify left bottom)
					(hide yes)
				)
			)
			(property "Public" "False"
				(at 20.32 -30.48 0)
				(effects
					(font
						(size 1.27 1.27)
					)
					(justify left bottom)
					(hide yes)
				)
			)
			(property "ki_keywords" "0402, SMT, RESISTOR, PASSIVE"
				(at 0 0 0)
				(effects
					(font
						(size 1.27 1.27)
					)
					(hide yes)
				)
			)
			(symbol "R_110k_0402_0_1"
				(rectangle
					(start 0.635 0.889)
					(end 4.445 -0.889)
					(stroke
						(width 0.254)
						(type default)
					)
					(fill
						(type none)
					)
				)
			)
			(symbol "R_110k_0402_1_1"
				(pin passive line
					(at 0 0 0)
					(length 0.635)
					(name "~"
						(effects
							(font
								(size 1.27 1.27)
							)
						)
					)
					(number "1"
						(effects
							(font
								(size 1.27 1.27)
							)
						)
					)
				)
				(pin passive line
					(at 5.08 0 180)
					(length 0.635)
					(name "~"
						(effects
							(font
								(size 1.27 1.27)
							)
						)
					)
					(number "2"
						(effects
							(font
								(size 1.27 1.27)
							)
						)
					)
				)
			)
		)
	(symbol "antmicroResistors0402:R_15k_0402"
			(pin_numbers
				(hide yes)
			)
			(pin_names
				(hide yes)
			)
			(exclude_from_sim no)
			(in_bom yes)
			(on_board yes)
			(property "Reference" "R"
				(at 20.32 -5.08 0)
				(effects
					(font
						(size 1.27 1.27)
						(thickness 0.15)
					)
					(justify left bottom)
				)
			)
			(property "Value" "R_15k_0402"
				(at 20.32 -12.7 0)
				(effects
					(font
						(size 1.27 1.27)
						(thickness 0.15)
					)
					(justify left bottom)
					(hide yes)
				)
			)
			(property "Footprint" "antmicro-footprints:R_0402_1005Metric"
				(at 20.32 -15.24 0)
				(effects
					(font
						(size 1.27 1.27)
						(thickness 0.15)
					)
					(justify left bottom)
					(hide yes)
				)
			)
			(property "Datasheet" "https://www.bourns.com/docs/product-datasheets/cr.pdf"
				(at 20.32 -17.78 0)
				(effects
					(font
						(size 1.27 1.27)
						(thickness 0.15)
					)
					(justify left bottom)
					(hide yes)
				)
			)
			(property "Description" "SMD Chip Resistor, 15 kohm, ± 1%, 62.5 mW, 0402 [1005 Metric], Thick Film, General Purpose"
				(at 0 0 0)
				(effects
					(font
						(size 1.27 1.27)
					)
					(hide yes)
				)
			)
			(property "MPN" "CR0402-FX-1502GLF"
				(at 20.32 -20.32 0)
				(effects
					(font
						(size 1.27 1.27)
						(thickness 0.15)
					)
					(justify left bottom)
					(hide yes)
				)
			)
			(property "Manufacturer" "Bourns"
				(at 20.32 -22.86 0)
				(effects
					(font
						(size 1.27 1.27)
						(thickness 0.15)
					)
					(justify left bottom)
					(hide yes)
				)
			)
			(property "License" "Apache-2.0"
				(at 20.32 -25.4 0)
				(effects
					(font
						(size 1.27 1.27)
						(thickness 0.15)
					)
					(justify left bottom)
					(hide yes)
				)
			)
			(property "Author" "Antmicro"
				(at 20.32 -27.94 0)
				(effects
					(font
						(size 1.27 1.27)
						(thickness 0.15)
					)
					(justify left bottom)
					(hide yes)
				)
			)
			(property "Val" "15k"
				(at 20.32 -7.62 0)
				(effects
					(font
						(size 1.27 1.27)
						(thickness 0.15)
					)
					(justify left bottom)
				)
			)
			(property "Tolerance" "1%"
				(at 20.32 -10.16 0)
				(effects
					(font
						(size 1.27 1.27)
					)
					(justify left bottom)
					(hide yes)
				)
			)
			(property "Public" "False"
				(at 20.32 -30.48 0)
				(effects
					(font
						(size 1.27 1.27)
					)
					(justify left bottom)
					(hide yes)
				)
			)
			(property "ki_keywords" "0402, SMT, RESISTOR, PASSIVE"
				(at 0 0 0)
				(effects
					(font
						(size 1.27 1.27)
					)
					(hide yes)
				)
			)
			(symbol "R_15k_0402_0_1"
				(rectangle
					(start 0.635 0.889)
					(end 4.445 -0.889)
					(stroke
						(width 0.254)
						(type default)
					)
					(fill
						(type none)
					)
				)
			)
			(symbol "R_15k_0402_1_1"
				(pin passive line
					(at 0 0 0)
					(length 0.635)
					(name "~"
						(effects
							(font
								(size 1.27 1.27)
							)
						)
					)
					(number "1"
						(effects
							(font
								(size 1.27 1.27)
							)
						)
					)
				)
				(pin passive line
					(at 5.08 0 180)
					(length 0.635)
					(name "~"
						(effects
							(font
								(size 1.27 1.27)
							)
						)
					)
					(number "2"
						(effects
							(font
								(size 1.27 1.27)
							)
						)
					)
				)
			)
		)
	(symbol "antmicroResistors0402:R_1k_0402"
			(pin_numbers
				(hide yes)
			)
			(pin_names
				(hide yes)
			)
			(exclude_from_sim no)
			(in_bom yes)
			(on_board yes)
			(property "Reference" "R"
				(at 20.32 -5.08 0)
				(effects
					(font
						(size 1.27 1.27)
						(thickness 0.15)
					)
					(justify left bottom)
				)
			)
			(property "Value" "R_1k_0402"
				(at 20.32 -12.7 0)
				(effects
					(font
						(size 1.27 1.27)
						(thickness 0.15)
					)
					(justify left bottom)
					(hide yes)
				)
			)
			(property "Footprint" "antmicro-footprints:R_0402_1005Metric"
				(at 20.32 -15.24 0)
				(effects
					(font
						(size 1.27 1.27)
						(thickness 0.15)
					)
					(justify left bottom)
					(hide yes)
				)
			)
			(property "Datasheet" "https://www.bourns.com/docs/product-datasheets/cr.pdf"
				(at 20.32 -17.78 0)
				(effects
					(font
						(size 1.27 1.27)
						(thickness 0.15)
					)
					(justify left bottom)
					(hide yes)
				)
			)
			(property "Description" "SMD Chip Resistor, 1 kohm, ± 1%, 63 mW, 0402 [1005 Metric], Thick Film, General Purpose"
				(at 0 0 0)
				(effects
					(font
						(size 1.27 1.27)
					)
					(hide yes)
				)
			)
			(property "MPN" "CR0402-FX-1001GLF"
				(at 20.32 -20.32 0)
				(effects
					(font
						(size 1.27 1.27)
						(thickness 0.15)
					)
					(justify left bottom)
					(hide yes)
				)
			)
			(property "Manufacturer" "Bourns"
				(at 20.32 -22.86 0)
				(effects
					(font
						(size 1.27 1.27)
						(thickness 0.15)
					)
					(justify left bottom)
					(hide yes)
				)
			)
			(property "License" "Apache-2.0"
				(at 20.32 -25.4 0)
				(effects
					(font
						(size 1.27 1.27)
						(thickness 0.15)
					)
					(justify left bottom)
					(hide yes)
				)
			)
			(property "Author" "Antmicro"
				(at 20.32 -27.94 0)
				(effects
					(font
						(size 1.27 1.27)
						(thickness 0.15)
					)
					(justify left bottom)
					(hide yes)
				)
			)
			(property "Val" "1k"
				(at 20.32 -7.62 0)
				(effects
					(font
						(size 1.27 1.27)
						(thickness 0.15)
					)
					(justify left bottom)
				)
			)
			(property "Tolerance" "1%"
				(at 20.32 -10.16 0)
				(effects
					(font
						(size 1.27 1.27)
					)
					(justify left bottom)
					(hide yes)
				)
			)
			(property "Public" "False"
				(at 20.32 -30.48 0)
				(effects
					(font
						(size 1.27 1.27)
					)
					(justify left bottom)
					(hide yes)
				)
			)
			(property "ki_keywords" "0402, SMT, RESISTOR, PASSIVE"
				(at 0 0 0)
				(effects
					(font
						(size 1.27 1.27)
					)
					(hide yes)
				)
			)
			(symbol "R_1k_0402_0_1"
				(rectangle
					(start 0.635 0.889)
					(end 4.445 -0.889)
					(stroke
						(width 0.254)
						(type default)
					)
					(fill
						(type none)
					)
				)
			)
			(symbol "R_1k_0402_1_1"
				(pin passive line
					(at 0 0 0)
					(length 0.635)
					(name "~"
						(effects
							(font
								(size 1.27 1.27)
							)
						)
					)
					(number "1"
						(effects
							(font
								(size 1.27 1.27)
							)
						)
					)
				)
				(pin passive line
					(at 5.08 0 180)
					(length 0.635)
					(name "~"
						(effects
							(font
								(size 1.27 1.27)
							)
						)
					)
					(number "2"
						(effects
							(font
								(size 1.27 1.27)
							)
						)
					)
				)
			)
		)
	(symbol "antmicroResistors0402:R_220R_0402"
			(pin_numbers
				(hide yes)
			)
			(pin_names
				(hide yes)
			)
			(exclude_from_sim no)
			(in_bom yes)
			(on_board yes)
			(property "Reference" "R"
				(at 20.32 -5.08 0)
				(effects
					(font
						(size 1.27 1.27)
						(thickness 0.15)
					)
					(justify left bottom)
				)
			)
			(property "Value" "R_220R_0402"
				(at 20.32 -12.7 0)
				(effects
					(font
						(size 1.27 1.27)
						(thickness 0.15)
					)
					(justify left bottom)
					(hide yes)
				)
			)
			(property "Footprint" "antmicro-footprints:R_0402_1005Metric"
				(at 20.32 -15.24 0)
				(effects
					(font
						(size 1.27 1.27)
						(thickness 0.15)
					)
					(justify left bottom)
					(hide yes)
				)
			)
			(property "Datasheet" "https://www.bourns.com/docs/product-datasheets/cr.pdf"
				(at 20.32 -17.78 0)
				(effects
					(font
						(size 1.27 1.27)
						(thickness 0.15)
					)
					(justify left bottom)
					(hide yes)
				)
			)
			(property "Description" "SMD Chip Resistor, 220 ohm, ± 1%, 62.5 mW, 0402 [1005 Metric], Thick Film, General Purpose"
				(at 0 0 0)
				(effects
					(font
						(size 1.27 1.27)
					)
					(hide yes)
				)
			)
			(property "MPN" "CR0402-FX-2200GLF"
				(at 20.32 -20.32 0)
				(effects
					(font
						(size 1.27 1.27)
						(thickness 0.15)
					)
					(justify left bottom)
					(hide yes)
				)
			)
			(property "Manufacturer" "Bourns"
				(at 20.32 -22.86 0)
				(effects
					(font
						(size 1.27 1.27)
						(thickness 0.15)
					)
					(justify left bottom)
					(hide yes)
				)
			)
			(property "License" "Apache-2.0"
				(at 20.32 -25.4 0)
				(effects
					(font
						(size 1.27 1.27)
						(thickness 0.15)
					)
					(justify left bottom)
					(hide yes)
				)
			)
			(property "Author" "Antmicro"
				(at 20.32 -27.94 0)
				(effects
					(font
						(size 1.27 1.27)
						(thickness 0.15)
					)
					(justify left bottom)
					(hide yes)
				)
			)
			(property "Val" "220R"
				(at 20.32 -7.62 0)
				(effects
					(font
						(size 1.27 1.27)
						(thickness 0.15)
					)
					(justify left bottom)
				)
			)
			(property "Tolerance" "1%"
				(at 20.32 -10.16 0)
				(effects
					(font
						(size 1.27 1.27)
					)
					(justify left bottom)
					(hide yes)
				)
			)
			(property "Public" "False"
				(at 20.32 -30.48 0)
				(effects
					(font
						(size 1.27 1.27)
					)
					(justify left bottom)
					(hide yes)
				)
			)
			(property "ki_keywords" "0402, SMT, RESISTOR, PASSIVE"
				(at 0 0 0)
				(effects
					(font
						(size 1.27 1.27)
					)
					(hide yes)
				)
			)
			(symbol "R_220R_0402_0_1"
				(rectangle
					(start 0.635 0.889)
					(end 4.445 -0.889)
					(stroke
						(width 0.254)
						(type default)
					)
					(fill
						(type none)
					)
				)
			)
			(symbol "R_220R_0402_1_1"
				(pin passive line
					(at 0 0 0)
					(length 0.635)
					(name "~"
						(effects
							(font
								(size 1.27 1.27)
							)
						)
					)
					(number "1"
						(effects
							(font
								(size 1.27 1.27)
							)
						)
					)
				)
				(pin passive line
					(at 5.08 0 180)
					(length 0.635)
					(name "~"
						(effects
							(font
								(size 1.27 1.27)
							)
						)
					)
					(number "2"
						(effects
							(font
								(size 1.27 1.27)
							)
						)
					)
				)
			)
		)
	(symbol "antmicroResistors0402:R_27R_0402"
			(pin_numbers
				(hide yes)
			)
			(pin_names
				(hide yes)
			)
			(exclude_from_sim no)
			(in_bom yes)
			(on_board yes)
			(property "Reference" "R"
				(at 20.32 -5.08 0)
				(effects
					(font
						(size 1.27 1.27)
						(thickness 0.15)
					)
					(justify left bottom)
				)
			)
			(property "Value" "R_27R_0402"
				(at 20.32 -12.7 0)
				(effects
					(font
						(size 1.27 1.27)
						(thickness 0.15)
					)
					(justify left bottom)
					(hide yes)
				)
			)
			(property "Footprint" "antmicro-footprints:R_0402_1005Metric"
				(at 20.32 -15.24 0)
				(effects
					(font
						(size 1.27 1.27)
						(thickness 0.15)
					)
					(justify left bottom)
					(hide yes)
				)
			)
			(property "Datasheet" "https://www.bourns.com/docs/product-datasheets/cr.pdf"
				(at 20.32 -17.78 0)
				(effects
					(font
						(size 1.27 1.27)
						(thickness 0.15)
					)
					(justify left bottom)
					(hide yes)
				)
			)
			(property "Description" "SMD Chip Resistor, 27 ohm, ± 1%, 63 mW, 0402 [1005 Metric], Thick Film, General Purpose"
				(at 0 0 0)
				(effects
					(font
						(size 1.27 1.27)
					)
					(hide yes)
				)
			)
			(property "MPN" "CR0402-FX-27R0GLF"
				(at 20.32 -20.32 0)
				(effects
					(font
						(size 1.27 1.27)
						(thickness 0.15)
					)
					(justify left bottom)
					(hide yes)
				)
			)
			(property "Manufacturer" "Bourns"
				(at 20.32 -22.86 0)
				(effects
					(font
						(size 1.27 1.27)
						(thickness 0.15)
					)
					(justify left bottom)
					(hide yes)
				)
			)
			(property "License" "Apache-2.0"
				(at 20.32 -25.4 0)
				(effects
					(font
						(size 1.27 1.27)
						(thickness 0.15)
					)
					(justify left bottom)
					(hide yes)
				)
			)
			(property "Author" "Antmicro"
				(at 20.32 -27.94 0)
				(effects
					(font
						(size 1.27 1.27)
						(thickness 0.15)
					)
					(justify left bottom)
					(hide yes)
				)
			)
			(property "Val" "27R"
				(at 20.32 -7.62 0)
				(effects
					(font
						(size 1.27 1.27)
						(thickness 0.15)
					)
					(justify left bottom)
				)
			)
			(property "Tolerance" "1%"
				(at 20.32 -10.16 0)
				(effects
					(font
						(size 1.27 1.27)
					)
					(justify left bottom)
					(hide yes)
				)
			)
			(property "Public" "False"
				(at 20.32 -30.48 0)
				(effects
					(font
						(size 1.27 1.27)
					)
					(justify left bottom)
					(hide yes)
				)
			)
			(property "ki_keywords" "0402, SMT, RESISTOR, PASSIVE"
				(at 0 0 0)
				(effects
					(font
						(size 1.27 1.27)
					)
					(hide yes)
				)
			)
			(symbol "R_27R_0402_0_1"
				(rectangle
					(start 0.635 0.889)
					(end 4.445 -0.889)
					(stroke
						(width 0.254)
						(type default)
					)
					(fill
						(type none)
					)
				)
			)
			(symbol "R_27R_0402_1_1"
				(pin passive line
					(at 0 0 0)
					(length 0.635)
					(name "~"
						(effects
							(font
								(size 1.27 1.27)
							)
						)
					)
					(number "1"
						(effects
							(font
								(size 1.27 1.27)
							)
						)
					)
				)
				(pin passive line
					(at 5.08 0 180)
					(length 0.635)
					(name "~"
						(effects
							(font
								(size 1.27 1.27)
							)
						)
					)
					(number "2"
						(effects
							(font
								(size 1.27 1.27)
							)
						)
					)
				)
			)
		)
	(symbol "antmicroResistors0402:R_2k2_0402"
			(pin_numbers
				(hide yes)
			)
			(pin_names
				(hide yes)
			)
			(exclude_from_sim no)
			(in_bom yes)
			(on_board yes)
			(property "Reference" "R"
				(at 20.32 -5.08 0)
				(effects
					(font
						(size 1.27 1.27)
						(thickness 0.15)
					)
					(justify left bottom)
				)
			)
			(property "Value" "R_2k2_0402"
				(at 20.32 -12.7 0)
				(effects
					(font
						(size 1.27 1.27)
						(thickness 0.15)
					)
					(justify left bottom)
					(hide yes)
				)
			)
			(property "Footprint" "antmicro-footprints:R_0402_1005Metric"
				(at 20.32 -15.24 0)
				(effects
					(font
						(size 1.27 1.27)
						(thickness 0.15)
					)
					(justify left bottom)
					(hide yes)
				)
			)
			(property "Datasheet" "https://www.bourns.com/docs/product-datasheets/cr.pdf"
				(at 20.32 -17.78 0)
				(effects
					(font
						(size 1.27 1.27)
						(thickness 0.15)
					)
					(justify left bottom)
					(hide yes)
				)
			)
			(property "Description" "SMD Chip Resistor, 2.2 kohm, ± 1%, 62.5 mW, 0402 [1005 Metric], Thick Film, General Purpose"
				(at 0 0 0)
				(effects
					(font
						(size 1.27 1.27)
					)
					(hide yes)
				)
			)
			(property "MPN" "CR0402-FX-2201GLF"
				(at 20.32 -20.32 0)
				(effects
					(font
						(size 1.27 1.27)
						(thickness 0.15)
					)
					(justify left bottom)
					(hide yes)
				)
			)
			(property "Manufacturer" "Bourns"
				(at 20.32 -22.86 0)
				(effects
					(font
						(size 1.27 1.27)
						(thickness 0.15)
					)
					(justify left bottom)
					(hide yes)
				)
			)
			(property "License" "Apache-2.0"
				(at 20.32 -25.4 0)
				(effects
					(font
						(size 1.27 1.27)
						(thickness 0.15)
					)
					(justify left bottom)
					(hide yes)
				)
			)
			(property "Author" "Antmicro"
				(at 20.32 -27.94 0)
				(effects
					(font
						(size 1.27 1.27)
						(thickness 0.15)
					)
					(justify left bottom)
					(hide yes)
				)
			)
			(property "Val" "2k2"
				(at 20.32 -7.62 0)
				(effects
					(font
						(size 1.27 1.27)
						(thickness 0.15)
					)
					(justify left bottom)
				)
			)
			(property "Tolerance" "1%"
				(at 20.32 -10.16 0)
				(effects
					(font
						(size 1.27 1.27)
					)
					(justify left bottom)
					(hide yes)
				)
			)
			(property "Public" "False"
				(at 20.32 -30.48 0)
				(effects
					(font
						(size 1.27 1.27)
					)
					(justify left bottom)
					(hide yes)
				)
			)
			(property "ki_keywords" "0402, SMT, RESISTOR, PASSIVE"
				(at 0 0 0)
				(effects
					(font
						(size 1.27 1.27)
					)
					(hide yes)
				)
			)
			(symbol "R_2k2_0402_0_1"
				(rectangle
					(start 0.635 0.889)
					(end 4.445 -0.889)
					(stroke
						(width 0.254)
						(type default)
					)
					(fill
						(type none)
					)
				)
			)
			(symbol "R_2k2_0402_1_1"
				(pin passive line
					(at 0 0 0)
					(length 0.635)
					(name "~"
						(effects
							(font
								(size 1.27 1.27)
							)
						)
					)
					(number "1"
						(effects
							(font
								(size 1.27 1.27)
							)
						)
					)
				)
				(pin passive line
					(at 5.08 0 180)
					(length 0.635)
					(name "~"
						(effects
							(font
								(size 1.27 1.27)
							)
						)
					)
					(number "2"
						(effects
							(font
								(size 1.27 1.27)
							)
						)
					)
				)
			)
		)
	(symbol "antmicroResistors0402:R_30k_0402"
			(pin_numbers
				(hide yes)
			)
			(pin_names
				(hide yes)
			)
			(exclude_from_sim no)
			(in_bom yes)
			(on_board yes)
			(property "Reference" "R"
				(at 20.32 -5.08 0)
				(effects
					(font
						(size 1.27 1.27)
						(thickness 0.15)
					)
					(justify left bottom)
				)
			)
			(property "Value" "R_30k_0402"
				(at 20.32 -12.7 0)
				(effects
					(font
						(size 1.27 1.27)
						(thickness 0.15)
					)
					(justify left bottom)
					(hide yes)
				)
			)
			(property "Footprint" "antmicro-footprints:R_0402_1005Metric"
				(at 20.32 -15.24 0)
				(effects
					(font
						(size 1.27 1.27)
						(thickness 0.15)
					)
					(justify left bottom)
					(hide yes)
				)
			)
			(property "Datasheet" "https://www.bourns.com/docs/product-datasheets/cr.pdf"
				(at 20.32 -17.78 0)
				(effects
					(font
						(size 1.27 1.27)
						(thickness 0.15)
					)
					(justify left bottom)
					(hide yes)
				)
			)
			(property "Description" "SMD Chip Resistor, 30 kohm, ± 1%, 63 mW, 0402 [1005 Metric], Thick Film, General Purpose"
				(at 0 0 0)
				(effects
					(font
						(size 1.27 1.27)
					)
					(hide yes)
				)
			)
			(property "MPN" "CR0402-FX-3002GLF"
				(at 20.32 -20.32 0)
				(effects
					(font
						(size 1.27 1.27)
						(thickness 0.15)
					)
					(justify left bottom)
					(hide yes)
				)
			)
			(property "Manufacturer" "Bourns"
				(at 20.32 -22.86 0)
				(effects
					(font
						(size 1.27 1.27)
						(thickness 0.15)
					)
					(justify left bottom)
					(hide yes)
				)
			)
			(property "License" "Apache-2.0"
				(at 20.32 -25.4 0)
				(effects
					(font
						(size 1.27 1.27)
						(thickness 0.15)
					)
					(justify left bottom)
					(hide yes)
				)
			)
			(property "Author" "Antmicro"
				(at 20.32 -27.94 0)
				(effects
					(font
						(size 1.27 1.27)
						(thickness 0.15)
					)
					(justify left bottom)
					(hide yes)
				)
			)
			(property "Val" "30k"
				(at 20.32 -7.62 0)
				(effects
					(font
						(size 1.27 1.27)
						(thickness 0.15)
					)
					(justify left bottom)
				)
			)
			(property "Tolerance" "1%"
				(at 20.32 -10.16 0)
				(effects
					(font
						(size 1.27 1.27)
					)
					(justify left bottom)
					(hide yes)
				)
			)
			(property "Public" "False"
				(at 20.32 -30.48 0)
				(effects
					(font
						(size 1.27 1.27)
					)
					(justify left bottom)
					(hide yes)
				)
			)
			(property "ki_keywords" "0402, SMT, RESISTOR, PASSIVE"
				(at 0 0 0)
				(effects
					(font
						(size 1.27 1.27)
					)
					(hide yes)
				)
			)
			(symbol "R_30k_0402_0_1"
				(rectangle
					(start 0.635 0.889)
					(end 4.445 -0.889)
					(stroke
						(width 0.254)
						(type default)
					)
					(fill
						(type none)
					)
				)
			)
			(symbol "R_30k_0402_1_1"
				(pin passive line
					(at 0 0 0)
					(length 0.635)
					(name "~"
						(effects
							(font
								(size 1.27 1.27)
							)
						)
					)
					(number "1"
						(effects
							(font
								(size 1.27 1.27)
							)
						)
					)
				)
				(pin passive line
					(at 5.08 0 180)
					(length 0.635)
					(name "~"
						(effects
							(font
								(size 1.27 1.27)
							)
						)
					)
					(number "2"
						(effects
							(font
								(size 1.27 1.27)
							)
						)
					)
				)
			)
		)
	(symbol "antmicroResistors0402:R_330R_0402"
			(pin_numbers
				(hide yes)
			)
			(pin_names
				(hide yes)
			)
			(exclude_from_sim no)
			(in_bom yes)
			(on_board yes)
			(property "Reference" "R"
				(at 20.32 -5.08 0)
				(effects
					(font
						(size 1.27 1.27)
						(thickness 0.15)
					)
					(justify left bottom)
				)
			)
			(property "Value" "R_330R_0402"
				(at 20.32 -12.7 0)
				(effects
					(font
						(size 1.27 1.27)
						(thickness 0.15)
					)
					(justify left bottom)
					(hide yes)
				)
			)
			(property "Footprint" "antmicro-footprints:R_0402_1005Metric"
				(at 20.32 -15.24 0)
				(effects
					(font
						(size 1.27 1.27)
						(thickness 0.15)
					)
					(justify left bottom)
					(hide yes)
				)
			)
			(property "Datasheet" "https://www.bourns.com/docs/product-datasheets/cr.pdf"
				(at 20.32 -17.78 0)
				(effects
					(font
						(size 1.27 1.27)
						(thickness 0.15)
					)
					(justify left bottom)
					(hide yes)
				)
			)
			(property "Description" "SMD Chip Resistor, 330 ohm, ± 1%, 62.5 mW, 0402 [1005 Metric], Thick Film, General Purpose"
				(at 0 0 0)
				(effects
					(font
						(size 1.27 1.27)
					)
					(hide yes)
				)
			)
			(property "MPN" "CR0402-FX-3300GLF"
				(at 20.32 -20.32 0)
				(effects
					(font
						(size 1.27 1.27)
						(thickness 0.15)
					)
					(justify left bottom)
					(hide yes)
				)
			)
			(property "Manufacturer" "Bourns"
				(at 20.32 -22.86 0)
				(effects
					(font
						(size 1.27 1.27)
						(thickness 0.15)
					)
					(justify left bottom)
					(hide yes)
				)
			)
			(property "License" "Apache-2.0"
				(at 20.32 -25.4 0)
				(effects
					(font
						(size 1.27 1.27)
						(thickness 0.15)
					)
					(justify left bottom)
					(hide yes)
				)
			)
			(property "Author" "Antmicro"
				(at 20.32 -27.94 0)
				(effects
					(font
						(size 1.27 1.27)
						(thickness 0.15)
					)
					(justify left bottom)
					(hide yes)
				)
			)
			(property "Val" "330R"
				(at 20.32 -7.62 0)
				(effects
					(font
						(size 1.27 1.27)
						(thickness 0.15)
					)
					(justify left bottom)
				)
			)
			(property "Tolerance" "1%"
				(at 20.32 -10.16 0)
				(effects
					(font
						(size 1.27 1.27)
					)
					(justify left bottom)
					(hide yes)
				)
			)
			(property "Public" "False"
				(at 20.32 -30.48 0)
				(effects
					(font
						(size 1.27 1.27)
					)
					(justify left bottom)
					(hide yes)
				)
			)
			(property "ki_keywords" "0402, SMT, RESISTOR, PASSIVE"
				(at 0 0 0)
				(effects
					(font
						(size 1.27 1.27)
					)
					(hide yes)
				)
			)
			(symbol "R_330R_0402_0_1"
				(rectangle
					(start 0.635 0.889)
					(end 4.445 -0.889)
					(stroke
						(width 0.254)
						(type default)
					)
					(fill
						(type none)
					)
				)
			)
			(symbol "R_330R_0402_1_1"
				(pin passive line
					(at 0 0 0)
					(length 0.635)
					(name "~"
						(effects
							(font
								(size 1.27 1.27)
							)
						)
					)
					(number "1"
						(effects
							(font
								(size 1.27 1.27)
							)
						)
					)
				)
				(pin passive line
					(at 5.08 0 180)
					(length 0.635)
					(name "~"
						(effects
							(font
								(size 1.27 1.27)
							)
						)
					)
					(number "2"
						(effects
							(font
								(size 1.27 1.27)
							)
						)
					)
				)
			)
		)
	(symbol "antmicroResistors0402:R_470R_0402"
			(pin_numbers
				(hide yes)
			)
			(pin_names
				(hide yes)
			)
			(exclude_from_sim no)
			(in_bom yes)
			(on_board yes)
			(property "Reference" "R"
				(at 20.32 -5.08 0)
				(effects
					(font
						(size 1.27 1.27)
						(thickness 0.15)
					)
					(justify left bottom)
				)
			)
			(property "Value" "R_470R_0402"
				(at 20.32 -12.7 0)
				(effects
					(font
						(size 1.27 1.27)
						(thickness 0.15)
					)
					(justify left bottom)
					(hide yes)
				)
			)
			(property "Footprint" "antmicro-footprints:R_0402_1005Metric"
				(at 20.32 -15.24 0)
				(effects
					(font
						(size 1.27 1.27)
						(thickness 0.15)
					)
					(justify left bottom)
					(hide yes)
				)
			)
			(property "Datasheet" "https://www.bourns.com/docs/product-datasheets/cr.pdf"
				(at 20.32 -17.78 0)
				(effects
					(font
						(size 1.27 1.27)
						(thickness 0.15)
					)
					(justify left bottom)
					(hide yes)
				)
			)
			(property "Description" "SMD Chip Resistor, 470 ohm, ± 1%, 62.5 mW, 0402 [1005 Metric], Thick Film, General Purpose"
				(at 0 0 0)
				(effects
					(font
						(size 1.27 1.27)
					)
					(hide yes)
				)
			)
			(property "MPN" "CR0402-FX-4700GLF"
				(at 20.32 -20.32 0)
				(effects
					(font
						(size 1.27 1.27)
						(thickness 0.15)
					)
					(justify left bottom)
					(hide yes)
				)
			)
			(property "Manufacturer" "Bourns"
				(at 20.32 -22.86 0)
				(effects
					(font
						(size 1.27 1.27)
						(thickness 0.15)
					)
					(justify left bottom)
					(hide yes)
				)
			)
			(property "License" "Apache-2.0"
				(at 20.32 -25.4 0)
				(effects
					(font
						(size 1.27 1.27)
						(thickness 0.15)
					)
					(justify left bottom)
					(hide yes)
				)
			)
			(property "Author" "Antmicro"
				(at 20.32 -27.94 0)
				(effects
					(font
						(size 1.27 1.27)
						(thickness 0.15)
					)
					(justify left bottom)
					(hide yes)
				)
			)
			(property "Val" "470R"
				(at 20.32 -7.62 0)
				(effects
					(font
						(size 1.27 1.27)
						(thickness 0.15)
					)
					(justify left bottom)
				)
			)
			(property "Tolerance" "1%"
				(at 20.32 -10.16 0)
				(effects
					(font
						(size 1.27 1.27)
					)
					(justify left bottom)
					(hide yes)
				)
			)
			(property "ki_keywords" "0402, SMT, RESISTOR, PASSIVE"
				(at 0 0 0)
				(effects
					(font
						(size 1.27 1.27)
					)
					(hide yes)
				)
			)
			(symbol "R_470R_0402_0_1"
				(rectangle
					(start 0.635 0.889)
					(end 4.445 -0.889)
					(stroke
						(width 0.254)
						(type default)
					)
					(fill
						(type none)
					)
				)
			)
			(symbol "R_470R_0402_1_1"
				(pin passive line
					(at 0 0 0)
					(length 0.635)
					(name "~"
						(effects
							(font
								(size 1.27 1.27)
							)
						)
					)
					(number "1"
						(effects
							(font
								(size 1.27 1.27)
							)
						)
					)
				)
				(pin passive line
					(at 5.08 0 180)
					(length 0.635)
					(name "~"
						(effects
							(font
								(size 1.27 1.27)
							)
						)
					)
					(number "2"
						(effects
							(font
								(size 1.27 1.27)
							)
						)
					)
				)
			)
		)
	(symbol "antmicroResistors0402:R_5k1_0402"
			(pin_numbers
				(hide yes)
			)
			(pin_names
				(hide yes)
			)
			(exclude_from_sim no)
			(in_bom yes)
			(on_board yes)
			(property "Reference" "R"
				(at 20.32 -5.08 0)
				(effects
					(font
						(size 1.27 1.27)
						(thickness 0.15)
					)
					(justify left bottom)
				)
			)
			(property "Value" "R_5k1_0402"
				(at 20.32 -12.7 0)
				(effects
					(font
						(size 1.27 1.27)
						(thickness 0.15)
					)
					(justify left bottom)
					(hide yes)
				)
			)
			(property "Footprint" "antmicro-footprints:R_0402_1005Metric"
				(at 20.32 -15.24 0)
				(effects
					(font
						(size 1.27 1.27)
						(thickness 0.15)
					)
					(justify left bottom)
					(hide yes)
				)
			)
			(property "Datasheet" "https://www.bourns.com/docs/product-datasheets/cr.pdf"
				(at 20.32 -17.78 0)
				(effects
					(font
						(size 1.27 1.27)
						(thickness 0.15)
					)
					(justify left bottom)
					(hide yes)
				)
			)
			(property "Description" "SMD Chip Resistor, 5.1 kohm, ± 1%, 63 mW, 0402 [1005 Metric], Thick Film, General Purpose"
				(at 0 0 0)
				(effects
					(font
						(size 1.27 1.27)
					)
					(hide yes)
				)
			)
			(property "MPN" "CR0402-FX-5101GLF"
				(at 20.32 -20.32 0)
				(effects
					(font
						(size 1.27 1.27)
						(thickness 0.15)
					)
					(justify left bottom)
					(hide yes)
				)
			)
			(property "Manufacturer" "Bourns"
				(at 20.32 -22.86 0)
				(effects
					(font
						(size 1.27 1.27)
						(thickness 0.15)
					)
					(justify left bottom)
					(hide yes)
				)
			)
			(property "License" "Apache-2.0"
				(at 20.32 -25.4 0)
				(effects
					(font
						(size 1.27 1.27)
						(thickness 0.15)
					)
					(justify left bottom)
					(hide yes)
				)
			)
			(property "Author" "Antmicro"
				(at 20.32 -27.94 0)
				(effects
					(font
						(size 1.27 1.27)
						(thickness 0.15)
					)
					(justify left bottom)
					(hide yes)
				)
			)
			(property "Val" "5k1"
				(at 20.32 -7.62 0)
				(effects
					(font
						(size 1.27 1.27)
						(thickness 0.15)
					)
					(justify left bottom)
				)
			)
			(property "Tolerance" "1%"
				(at 20.32 -10.16 0)
				(effects
					(font
						(size 1.27 1.27)
					)
					(justify left bottom)
					(hide yes)
				)
			)
			(property "Public" "False"
				(at 20.32 -30.48 0)
				(effects
					(font
						(size 1.27 1.27)
					)
					(justify left bottom)
					(hide yes)
				)
			)
			(property "ki_keywords" "0402, SMT, RESISTOR, PASSIVE"
				(at 0 0 0)
				(effects
					(font
						(size 1.27 1.27)
					)
					(hide yes)
				)
			)
			(symbol "R_5k1_0402_0_1"
				(rectangle
					(start 0.635 0.889)
					(end 4.445 -0.889)
					(stroke
						(width 0.254)
						(type default)
					)
					(fill
						(type none)
					)
				)
			)
			(symbol "R_5k1_0402_1_1"
				(pin passive line
					(at 0 0 0)
					(length 0.635)
					(name "~"
						(effects
							(font
								(size 1.27 1.27)
							)
						)
					)
					(number "1"
						(effects
							(font
								(size 1.27 1.27)
							)
						)
					)
				)
				(pin passive line
					(at 5.08 0 180)
					(length 0.635)
					(name "~"
						(effects
							(font
								(size 1.27 1.27)
							)
						)
					)
					(number "2"
						(effects
							(font
								(size 1.27 1.27)
							)
						)
					)
				)
			)
		)
	(symbol "antmicroResistors0402:R_68k_0402"
			(pin_numbers
				(hide yes)
			)
			(pin_names
				(hide yes)
			)
			(exclude_from_sim no)
			(in_bom yes)
			(on_board yes)
			(property "Reference" "R"
				(at 20.32 -5.08 0)
				(effects
					(font
						(size 1.27 1.27)
						(thickness 0.15)
					)
					(justify left bottom)
				)
			)
			(property "Value" "R_68k_0402"
				(at 20.32 -12.7 0)
				(effects
					(font
						(size 1.27 1.27)
						(thickness 0.15)
					)
					(justify left bottom)
					(hide yes)
				)
			)
			(property "Footprint" "antmicro-footprints:R_0402_1005Metric"
				(at 20.32 -15.24 0)
				(effects
					(font
						(size 1.27 1.27)
						(thickness 0.15)
					)
					(justify left bottom)
					(hide yes)
				)
			)
			(property "Datasheet" "https://www.bourns.com/docs/product-datasheets/cr.pdf"
				(at 20.32 -17.78 0)
				(effects
					(font
						(size 1.27 1.27)
						(thickness 0.15)
					)
					(justify left bottom)
					(hide yes)
				)
			)
			(property "Description" "SMD Chip Resistor"
				(at 0 0 0)
				(effects
					(font
						(size 1.27 1.27)
					)
					(hide yes)
				)
			)
			(property "MPN" "CR0402-FX-6802GLF"
				(at 20.32 -20.32 0)
				(effects
					(font
						(size 1.27 1.27)
						(thickness 0.15)
					)
					(justify left bottom)
					(hide yes)
				)
			)
			(property "Manufacturer" "Bourns"
				(at 20.32 -22.86 0)
				(effects
					(font
						(size 1.27 1.27)
						(thickness 0.15)
					)
					(justify left bottom)
					(hide yes)
				)
			)
			(property "License" "Apache-2.0"
				(at 20.32 -25.4 0)
				(effects
					(font
						(size 1.27 1.27)
						(thickness 0.15)
					)
					(justify left bottom)
					(hide yes)
				)
			)
			(property "Author" "Antmicro"
				(at 20.32 -27.94 0)
				(effects
					(font
						(size 1.27 1.27)
						(thickness 0.15)
					)
					(justify left bottom)
					(hide yes)
				)
			)
			(property "Val" "68k"
				(at 20.32 -7.62 0)
				(effects
					(font
						(size 1.27 1.27)
						(thickness 0.15)
					)
					(justify left bottom)
				)
			)
			(property "Tolerance" "1%"
				(at 20.32 -10.16 0)
				(effects
					(font
						(size 1.27 1.27)
					)
					(justify left bottom)
					(hide yes)
				)
			)
			(property "Public" "False"
				(at 20.32 -30.48 0)
				(effects
					(font
						(size 1.27 1.27)
					)
					(justify left bottom)
					(hide yes)
				)
			)
			(property "ki_keywords" "0402, SMT, RESISTOR, PASSIVE"
				(at 0 0 0)
				(effects
					(font
						(size 1.27 1.27)
					)
					(hide yes)
				)
			)
			(symbol "R_68k_0402_0_1"
				(rectangle
					(start 0.635 0.889)
					(end 4.445 -0.889)
					(stroke
						(width 0.254)
						(type default)
					)
					(fill
						(type none)
					)
				)
			)
			(symbol "R_68k_0402_1_1"
				(pin passive line
					(at 0 0 0)
					(length 0.635)
					(name "~"
						(effects
							(font
								(size 1.27 1.27)
							)
						)
					)
					(number "1"
						(effects
							(font
								(size 1.27 1.27)
							)
						)
					)
				)
				(pin passive line
					(at 5.08 0 180)
					(length 0.635)
					(name "~"
						(effects
							(font
								(size 1.27 1.27)
							)
						)
					)
					(number "2"
						(effects
							(font
								(size 1.27 1.27)
							)
						)
					)
				)
			)
		)
	(symbol "antmicroResistors0402:R_75R_0402"
			(pin_numbers
				(hide yes)
			)
			(pin_names
				(hide yes)
			)
			(exclude_from_sim no)
			(in_bom yes)
			(on_board yes)
			(property "Reference" "R"
				(at 20.32 -5.08 0)
				(effects
					(font
						(size 1.27 1.27)
						(thickness 0.15)
					)
					(justify left bottom)
				)
			)
			(property "Value" "R_75R_0402"
				(at 20.32 -12.7 0)
				(effects
					(font
						(size 1.27 1.27)
						(thickness 0.15)
					)
					(justify left bottom)
					(hide yes)
				)
			)
			(property "Footprint" "antmicro-footprints:R_0402_1005Metric"
				(at 20.32 -15.24 0)
				(effects
					(font
						(size 1.27 1.27)
						(thickness 0.15)
					)
					(justify left bottom)
					(hide yes)
				)
			)
			(property "Datasheet" "https://www.bourns.com/docs/product-datasheets/cr.pdf"
				(at 20.32 -17.78 0)
				(effects
					(font
						(size 1.27 1.27)
						(thickness 0.15)
					)
					(justify left bottom)
					(hide yes)
				)
			)
			(property "Description" "SMD Chip Resistor, 75 ohm, ± 1%, 62.5 mW, 0402 [1005 Metric], Thick Film, General Purpose"
				(at 0 0 0)
				(effects
					(font
						(size 1.27 1.27)
					)
					(hide yes)
				)
			)
			(property "MPN" "CR0402-FX-75R0GLF"
				(at 20.32 -20.32 0)
				(effects
					(font
						(size 1.27 1.27)
						(thickness 0.15)
					)
					(justify left bottom)
					(hide yes)
				)
			)
			(property "Manufacturer" "Bourns"
				(at 20.32 -22.86 0)
				(effects
					(font
						(size 1.27 1.27)
						(thickness 0.15)
					)
					(justify left bottom)
					(hide yes)
				)
			)
			(property "License" "Apache-2.0"
				(at 20.32 -25.4 0)
				(effects
					(font
						(size 1.27 1.27)
						(thickness 0.15)
					)
					(justify left bottom)
					(hide yes)
				)
			)
			(property "Author" "Antmicro"
				(at 20.32 -27.94 0)
				(effects
					(font
						(size 1.27 1.27)
						(thickness 0.15)
					)
					(justify left bottom)
					(hide yes)
				)
			)
			(property "Val" "75R"
				(at 20.32 -7.62 0)
				(effects
					(font
						(size 1.27 1.27)
						(thickness 0.15)
					)
					(justify left bottom)
				)
			)
			(property "Tolerance" "1%"
				(at 20.32 -10.16 0)
				(effects
					(font
						(size 1.27 1.27)
					)
					(justify left bottom)
					(hide yes)
				)
			)
			(property "Public" "False"
				(at 20.32 -30.48 0)
				(effects
					(font
						(size 1.27 1.27)
					)
					(justify left bottom)
					(hide yes)
				)
			)
			(property "ki_keywords" "0402, SMT, RESISTOR, PASSIVE"
				(at 0 0 0)
				(effects
					(font
						(size 1.27 1.27)
					)
					(hide yes)
				)
			)
			(symbol "R_75R_0402_0_1"
				(rectangle
					(start 0.635 0.889)
					(end 4.445 -0.889)
					(stroke
						(width 0.254)
						(type default)
					)
					(fill
						(type none)
					)
				)
			)
			(symbol "R_75R_0402_1_1"
				(pin passive line
					(at 0 0 0)
					(length 0.635)
					(name "~"
						(effects
							(font
								(size 1.27 1.27)
							)
						)
					)
					(number "1"
						(effects
							(font
								(size 1.27 1.27)
							)
						)
					)
				)
				(pin passive line
					(at 5.08 0 180)
					(length 0.635)
					(name "~"
						(effects
							(font
								(size 1.27 1.27)
							)
						)
					)
					(number "2"
						(effects
							(font
								(size 1.27 1.27)
							)
						)
					)
				)
			)
		)
	(symbol "antmicroResistors0603:R_0R_22.4A_0603"
			(pin_numbers
				(hide yes)
			)
			(pin_names
				(hide yes)
			)
			(exclude_from_sim no)
			(in_bom yes)
			(on_board yes)
			(property "Reference" "R"
				(at 15.24 -2.54 0)
				(effects
					(font
						(size 1.27 1.27)
						(thickness 0.15)
					)
					(justify left bottom)
				)
			)
			(property "Value" "R_0R_22.4A_0603"
				(at 15.24 -5.08 0)
				(effects
					(font
						(size 1.27 1.27)
						(thickness 0.15)
					)
					(justify left bottom)
				)
			)
			(property "Footprint" "antmicro-footprints:R_0603_1608Metric"
				(at 15.24 -10.16 0)
				(effects
					(font
						(size 1.27 1.27)
						(thickness 0.15)
					)
					(justify left bottom)
					(hide yes)
				)
			)
			(property "Datasheet" "https://fscdn.rohm.com/en/products/databook/datasheet/passive/resistor/chip_resistor/pmr-jpw-e.pdf"
				(at 15.24 -12.7 0)
				(effects
					(font
						(size 1.27 1.27)
						(thickness 0.15)
					)
					(justify left bottom)
					(hide yes)
				)
			)
			(property "Description" "SMD Chip Resistor"
				(at 0 0 0)
				(effects
					(font
						(size 1.27 1.27)
					)
					(hide yes)
				)
			)
			(property "MPN" "PMR03EZPJ000"
				(at 15.24 -15.24 0)
				(effects
					(font
						(size 1.27 1.27)
						(thickness 0.15)
					)
					(justify left bottom)
					(hide yes)
				)
			)
			(property "Manufacturer" "ROHM Semiconductor"
				(at 15.24 -17.78 0)
				(effects
					(font
						(size 1.27 1.27)
						(thickness 0.15)
					)
					(justify left bottom)
					(hide yes)
				)
			)
			(property "Val" "0R"
				(at 15.24 -7.62 0)
				(effects
					(font
						(size 1.27 1.27)
						(thickness 0.15)
					)
					(justify left bottom)
				)
			)
			(property "Max. Curr." "22.4A"
				(at 15.24 -20.32 0)
				(effects
					(font
						(size 1.27 1.27)
						(thickness 0.15)
					)
					(justify left bottom)
				)
			)
			(property "Author" "Antmicro"
				(at 15.24 -22.86 0)
				(effects
					(font
						(size 1.27 1.27)
						(thickness 0.15)
					)
					(justify left bottom)
					(hide yes)
				)
			)
			(property "License" "Apache-2.0"
				(at 15.24 -25.4 0)
				(effects
					(font
						(size 1.27 1.27)
						(thickness 0.15)
					)
					(justify left bottom)
					(hide yes)
				)
			)
			(property "Tolerance" "template_tolerance"
				(at 20.32 -10.16 0)
				(effects
					(font
						(size 1.27 1.27)
					)
					(justify left bottom)
					(hide yes)
				)
			)
			(property "Public" "False"
				(at 20.32 -30.48 0)
				(effects
					(font
						(size 1.27 1.27)
					)
					(justify left bottom)
					(hide yes)
				)
			)
			(property "ki_keywords" "0603, SMT, RESISTOR, PASSIVE"
				(at 0 0 0)
				(effects
					(font
						(size 1.27 1.27)
					)
					(hide yes)
				)
			)
			(symbol "R_0R_22.4A_0603_0_1"
				(rectangle
					(start 0.635 0.889)
					(end 4.445 -0.889)
					(stroke
						(width 0.254)
						(type default)
					)
					(fill
						(type none)
					)
				)
			)
			(symbol "R_0R_22.4A_0603_1_1"
				(pin passive line
					(at 0 0 0)
					(length 0.635)
					(name "~"
						(effects
							(font
								(size 1.27 1.27)
							)
						)
					)
					(number "1"
						(effects
							(font
								(size 1.27 1.27)
							)
						)
					)
				)
				(pin passive line
					(at 5.08 0 180)
					(length 0.635)
					(name "~"
						(effects
							(font
								(size 1.27 1.27)
							)
						)
					)
					(number "2"
						(effects
							(font
								(size 1.27 1.27)
							)
						)
					)
				)
			)
		)
	(symbol "antmicroResistorsmisc:R_0R001_0805"
			(pin_numbers
				(hide yes)
			)
			(pin_names
				(hide yes)
			)
			(exclude_from_sim no)
			(in_bom yes)
			(on_board yes)
			(property "Reference" "R"
				(at 20.32 -5.08 0)
				(effects
					(font
						(size 1.27 1.27)
						(thickness 0.15)
					)
					(justify left bottom)
				)
			)
			(property "Value" "R_0R001_0805"
				(at 20.32 -12.7 0)
				(effects
					(font
						(size 1.27 1.27)
						(thickness 0.15)
					)
					(justify left bottom)
					(hide yes)
				)
			)
			(property "Footprint" "antmicro-footprints:R_0805_2012Metric"
				(at 20.32 -15.24 0)
				(effects
					(font
						(size 1.27 1.27)
						(thickness 0.15)
					)
					(justify left bottom)
					(hide yes)
				)
			)
			(property "Datasheet" "https://www.eaton.com/content/dam/eaton/products/electronic-components/resources/data-sheet/eaton-msma-automotive-smd-current-sense-resistor-metal-strip-data-sheet-elx1179.pdf"
				(at 20.32 -17.78 0)
				(effects
					(font
						(size 1.27 1.27)
						(thickness 0.15)
					)
					(justify left bottom)
					(hide yes)
				)
			)
			(property "Description" "Current Sense Resistors - SMD MSMA, 0805 SIZE, 1/2 Watt, 1 mohm, 50 TCR MnCu Metal AEC-Q"
				(at 0 0 0)
				(effects
					(font
						(size 1.27 1.27)
					)
					(hide yes)
				)
			)
			(property "MPN" "MSMA0805R0010FSM"
				(at 20.32 -20.32 0)
				(effects
					(font
						(size 1.27 1.27)
						(thickness 0.15)
					)
					(justify left bottom)
					(hide yes)
				)
			)
			(property "Manufacturer" "Eaton"
				(at 20.32 -22.86 0)
				(effects
					(font
						(size 1.27 1.27)
						(thickness 0.15)
					)
					(justify left bottom)
					(hide yes)
				)
			)
			(property "License" "Apache-2.0"
				(at 20.32 -25.4 0)
				(effects
					(font
						(size 1.27 1.27)
						(thickness 0.15)
					)
					(justify left bottom)
					(hide yes)
				)
			)
			(property "Author" "Antmicro"
				(at 20.32 -27.94 0)
				(effects
					(font
						(size 1.27 1.27)
						(thickness 0.15)
					)
					(justify left bottom)
					(hide yes)
				)
			)
			(property "Val" "0R001"
				(at 20.32 -7.62 0)
				(effects
					(font
						(size 1.27 1.27)
						(thickness 0.15)
					)
					(justify left bottom)
				)
			)
			(property "Tolerance" "1%"
				(at 20.32 -10.16 0)
				(effects
					(font
						(size 1.27 1.27)
					)
					(justify left bottom)
					(hide yes)
				)
			)
			(property "Public" "False"
				(at 20.32 -30.48 0)
				(effects
					(font
						(size 1.27 1.27)
					)
					(justify left bottom)
					(hide yes)
				)
			)
			(property "ki_keywords" "0805, SMT, RESISTOR, PASSIVE"
				(at 0 0 0)
				(effects
					(font
						(size 1.27 1.27)
					)
					(hide yes)
				)
			)
			(symbol "R_0R001_0805_0_1"
				(rectangle
					(start 0.635 0.889)
					(end 4.445 -0.889)
					(stroke
						(width 0.254)
						(type default)
					)
					(fill
						(type none)
					)
				)
			)
			(symbol "R_0R001_0805_1_1"
				(pin passive line
					(at 0 0 0)
					(length 0.635)
					(name "~"
						(effects
							(font
								(size 1.27 1.27)
							)
						)
					)
					(number "1"
						(effects
							(font
								(size 1.27 1.27)
							)
						)
					)
				)
				(pin passive line
					(at 5.08 0 180)
					(length 0.635)
					(name "~"
						(effects
							(font
								(size 1.27 1.27)
							)
						)
					)
					(number "2"
						(effects
							(font
								(size 1.27 1.27)
							)
						)
					)
				)
			)
		)
	(symbol "antmicroResistorsmisc:R_0R_0201"
			(pin_numbers
				(hide yes)
			)
			(pin_names
				(hide yes)
			)
			(exclude_from_sim no)
			(in_bom yes)
			(on_board yes)
			(property "Reference" "R"
				(at 20.32 -5.08 0)
				(effects
					(font
						(size 1.27 1.27)
						(thickness 0.15)
					)
					(justify left bottom)
				)
			)
			(property "Value" "R_0R_0201"
				(at 20.32 -12.7 0)
				(effects
					(font
						(size 1.27 1.27)
						(thickness 0.15)
					)
					(justify left bottom)
					(hide yes)
				)
			)
			(property "Footprint" "antmicro-footprints:R_0201"
				(at 20.32 -15.24 0)
				(effects
					(font
						(size 1.27 1.27)
						(thickness 0.15)
					)
					(justify left bottom)
					(hide yes)
				)
			)
			(property "Datasheet" "https://www.bourns.com/docs/product-datasheets/cr.pdf"
				(at 20.32 -17.78 0)
				(effects
					(font
						(size 1.27 1.27)
						(thickness 0.15)
					)
					(justify left bottom)
					(hide yes)
				)
			)
			(property "Description" "SMD Chip Resistor"
				(at 0 0 0)
				(effects
					(font
						(size 1.27 1.27)
					)
					(hide yes)
				)
			)
			(property "MPN" "CR0201-FX-0R00GLF"
				(at 20.32 -20.32 0)
				(effects
					(font
						(size 1.27 1.27)
						(thickness 0.15)
					)
					(justify left bottom)
					(hide yes)
				)
			)
			(property "Manufacturer" "Bourns"
				(at 20.32 -22.86 0)
				(effects
					(font
						(size 1.27 1.27)
						(thickness 0.15)
					)
					(justify left bottom)
					(hide yes)
				)
			)
			(property "License" "Apache-2.0"
				(at 20.32 -25.4 0)
				(effects
					(font
						(size 1.27 1.27)
						(thickness 0.15)
					)
					(justify left bottom)
					(hide yes)
				)
			)
			(property "Author" "Antmicro"
				(at 20.32 -27.94 0)
				(effects
					(font
						(size 1.27 1.27)
						(thickness 0.15)
					)
					(justify left bottom)
					(hide yes)
				)
			)
			(property "Val" "0R"
				(at 20.32 -7.62 0)
				(effects
					(font
						(size 1.27 1.27)
						(thickness 0.15)
					)
					(justify left bottom)
				)
			)
			(property "Tolerance" "1%"
				(at 20.32 -10.16 0)
				(effects
					(font
						(size 1.27 1.27)
					)
					(justify left bottom)
					(hide yes)
				)
			)
			(property "ki_keywords" "0603, SMT, RESISTOR, PASSIVE"
				(at 0 0 0)
				(effects
					(font
						(size 1.27 1.27)
					)
					(hide yes)
				)
			)
			(symbol "R_0R_0201_0_1"
				(rectangle
					(start 0.635 0.889)
					(end 4.445 -0.889)
					(stroke
						(width 0.254)
						(type default)
					)
					(fill
						(type none)
					)
				)
			)
			(symbol "R_0R_0201_1_1"
				(pin passive line
					(at 0 0 0)
					(length 0.635)
					(name "~"
						(effects
							(font
								(size 1.27 1.27)
							)
						)
					)
					(number "1"
						(effects
							(font
								(size 1.27 1.27)
							)
						)
					)
				)
				(pin passive line
					(at 5.08 0 180)
					(length 0.635)
					(name "~"
						(effects
							(font
								(size 1.27 1.27)
							)
						)
					)
					(number "2"
						(effects
							(font
								(size 1.27 1.27)
							)
						)
					)
				)
			)
		)
	(symbol "antmicroShuntsJumpers:Jumper_1x2_P2.54mm"
			(exclude_from_sim no)
			(in_bom yes)
			(on_board yes)
			(property "Reference" "JP"
				(at 7.62 -2.54 0)
				(effects
					(font
						(size 1.27 1.27)
					)
					(justify left bottom)
				)
			)
			(property "Value" "Jumper_1x2_P2.54mm"
				(at 7.62 -5.08 0)
				(effects
					(font
						(size 1.27 1.27)
					)
					(justify left bottom)
				)
			)
			(property "Footprint" "antmicro-footprints:Jumper_1x2_P2.54mm"
				(at 7.62 -10.16 0)
				(effects
					(font
						(size 1.27 1.27)
					)
					(justify left bottom)
					(hide yes)
				)
			)
			(property "Datasheet" "https://www.tme.eu/en/details/jumper-w/pin-headers/ninigi/"
				(at 7.62 -7.62 0)
				(effects
					(font
						(size 1.27 1.27)
					)
					(justify left bottom)
					(hide yes)
				)
			)
			(property "Description" "Jumper"
				(at 0 0 0)
				(effects
					(font
						(size 1.27 1.27)
					)
					(hide yes)
				)
			)
			(property "MPN" "JUMPER-W"
				(at 7.62 -12.7 0)
				(effects
					(font
						(size 1.27 1.27)
					)
					(justify left bottom)
					(hide yes)
				)
			)
			(property "Manufacturer" "Ninigi"
				(at 7.62 -15.24 0)
				(effects
					(font
						(size 1.27 1.27)
					)
					(justify left bottom)
					(hide yes)
				)
			)
			(property "License" "Apache-2.0"
				(at 7.62 -20.32 0)
				(effects
					(font
						(size 1.27 1.27)
					)
					(justify left bottom)
					(hide yes)
				)
			)
			(property "Author" "Antmicro"
				(at 7.62 -17.78 0)
				(effects
					(font
						(size 1.27 1.27)
					)
					(justify left bottom)
					(hide yes)
				)
			)
			(property "ki_keywords" "JUMPER"
				(at 0 0 0)
				(effects
					(font
						(size 1.27 1.27)
					)
					(hide yes)
				)
			)
			(symbol "Jumper_1x2_P2.54mm_1_1"
				(rectangle
					(start 0 0)
					(end 2.54 -5.08)
					(stroke
						(width 0.254)
						(type default)
					)
					(fill
						(type background)
					)
				)
			)
		)
	(symbol "antmicroTVSDiodes:ESD204DQAR"
			(exclude_from_sim no)
			(in_bom yes)
			(on_board yes)
			(property "Reference" "D"
				(at 24.13 0 0)
				(effects
					(font
						(size 1.27 1.27)
						(thickness 0.15)
					)
					(justify left bottom)
				)
			)
			(property "Value" "ESD204DQAR"
				(at 24.13 -5.08 0)
				(effects
					(font
						(size 1.27 1.27)
						(thickness 0.15)
					)
					(justify left bottom)
					(hide yes)
				)
			)
			(property "Footprint" "antmicro-footprints:USON-10_2.5x1mm_P0.5mm"
				(at 24.13 -7.62 0)
				(effects
					(font
						(size 1.27 1.27)
						(thickness 0.15)
					)
					(justify left bottom)
					(hide yes)
				)
			)
			(property "Datasheet" "https://www.ti.com/lit/ds/symlink/esd204.pdf?ts=1706004844383&ref_url=https%253A%252F%252Fwww.ti.com%252Finterface%252Fdiodes%252Fesd-protection-diodes%252Fproducts.html"
				(at 24.13 -10.16 0)
				(effects
					(font
						(size 1.27 1.27)
						(thickness 0.15)
					)
					(justify left bottom)
					(hide yes)
				)
			)
			(property "Description" "TVS diode array, 30 kV, USON-10, 3.6 V, 0.55 pF"
				(at 0 0 0)
				(effects
					(font
						(size 1.27 1.27)
					)
					(hide yes)
				)
			)
			(property "MPN" "ESD204DQAR"
				(at 24.13 -2.54 0)
				(effects
					(font
						(size 1.27 1.27)
						(thickness 0.15)
					)
					(justify left bottom)
				)
			)
			(property "Manufacturer" "Texas Instruments"
				(at 24.13 -12.7 0)
				(effects
					(font
						(size 1.27 1.27)
						(thickness 0.15)
					)
					(justify left bottom)
					(hide yes)
				)
			)
			(property "Author" "Antmicro"
				(at 24.13 -15.24 0)
				(effects
					(font
						(size 1.27 1.27)
						(thickness 0.15)
					)
					(justify left bottom)
					(hide yes)
				)
			)
			(property "License" "Apache-2.0"
				(at 24.13 -17.78 0)
				(effects
					(font
						(size 1.27 1.27)
						(thickness 0.15)
					)
					(justify left bottom)
					(hide yes)
				)
			)
			(property "ki_keywords" "SMT, DIODE, SEMICONDUCTOR, TVS, ESD"
				(at 0 0 0)
				(effects
					(font
						(size 1.27 1.27)
					)
					(hide yes)
				)
			)
			(symbol "ESD204DQAR_1_1"
				(rectangle
					(start 2.54 2.54)
					(end 8.89 -12.7)
					(stroke
						(width 0.254)
						(type default)
					)
					(fill
						(type background)
					)
				)
				(polyline
					(pts
						(xy 2.54 0) (xy 7.62 0)
					)
					(stroke
						(width 0.254)
						(type default)
					)
					(fill
						(type background)
					)
				)
				(polyline
					(pts
						(xy 2.54 -2.54) (xy 7.62 -2.54)
					)
					(stroke
						(width 0.254)
						(type default)
					)
					(fill
						(type background)
					)
				)
				(polyline
					(pts
						(xy 2.54 -5.08) (xy 7.62 -5.08)
					)
					(stroke
						(width 0.254)
						(type default)
					)
					(fill
						(type background)
					)
				)
				(polyline
					(pts
						(xy 2.54 -7.62) (xy 7.62 -7.62)
					)
					(stroke
						(width 0.254)
						(type default)
					)
					(fill
						(type background)
					)
				)
				(polyline
					(pts
						(xy 4.826 -0.635) (xy 5.08 -0.381) (xy 5.08 0.381) (xy 5.334 0.635)
					)
					(stroke
						(width 0.254)
						(type default)
					)
					(fill
						(type background)
					)
				)
				(polyline
					(pts
						(xy 4.826 -3.175) (xy 5.08 -2.921) (xy 5.08 -2.159) (xy 5.334 -1.905)
					)
					(stroke
						(width 0.254)
						(type default)
					)
					(fill
						(type background)
					)
				)
				(polyline
					(pts
						(xy 4.826 -5.715) (xy 5.08 -5.461) (xy 5.08 -4.699) (xy 5.334 -4.445)
					)
					(stroke
						(width 0.254)
						(type default)
					)
					(fill
						(type background)
					)
				)
				(polyline
					(pts
						(xy 4.826 -8.255) (xy 5.08 -8.001) (xy 5.08 -7.239) (xy 5.334 -6.985)
					)
					(stroke
						(width 0.254)
						(type default)
					)
					(fill
						(type background)
					)
				)
				(polyline
					(pts
						(xy 5.08 0) (xy 3.81 -0.635) (xy 3.81 0.635) (xy 5.08 0)
					)
					(stroke
						(width 0.254)
						(type default)
					)
					(fill
						(type background)
					)
				)
				(polyline
					(pts
						(xy 5.08 0) (xy 6.35 -0.635) (xy 6.35 0.635) (xy 5.08 0)
					)
					(stroke
						(width 0.254)
						(type default)
					)
					(fill
						(type background)
					)
				)
				(polyline
					(pts
						(xy 5.08 -2.54) (xy 3.81 -3.175) (xy 3.81 -1.905) (xy 5.08 -2.54)
					)
					(stroke
						(width 0.254)
						(type default)
					)
					(fill
						(type background)
					)
				)
				(polyline
					(pts
						(xy 5.08 -2.54) (xy 6.35 -3.175) (xy 6.35 -1.905) (xy 5.08 -2.54)
					)
					(stroke
						(width 0.254)
						(type default)
					)
					(fill
						(type background)
					)
				)
				(polyline
					(pts
						(xy 5.08 -5.08) (xy 3.81 -5.715) (xy 3.81 -4.445) (xy 5.08 -5.08)
					)
					(stroke
						(width 0.254)
						(type default)
					)
					(fill
						(type background)
					)
				)
				(polyline
					(pts
						(xy 5.08 -5.08) (xy 6.35 -4.445) (xy 6.35 -5.715) (xy 5.08 -5.08)
					)
					(stroke
						(width 0.254)
						(type default)
					)
					(fill
						(type background)
					)
				)
				(polyline
					(pts
						(xy 5.08 -7.62) (xy 3.81 -8.255) (xy 3.81 -6.985) (xy 5.08 -7.62)
					)
					(stroke
						(width 0.254)
						(type default)
					)
					(fill
						(type background)
					)
				)
				(polyline
					(pts
						(xy 6.35 -6.985) (xy 6.35 -8.255) (xy 5.08 -7.62) (xy 6.35 -6.985)
					)
					(stroke
						(width 0.254)
						(type default)
					)
					(fill
						(type background)
					)
				)
				(polyline
					(pts
						(xy 7.62 0) (xy 7.62 -10.16)
					)
					(stroke
						(width 0.254)
						(type default)
					)
					(fill
						(type background)
					)
				)
				(circle
					(center 7.62 -2.54)
					(radius 0.254)
					(stroke
						(width 0.254)
						(type default)
					)
					(fill
						(type background)
					)
				)
				(circle
					(center 7.62 -5.08)
					(radius 0.254)
					(stroke
						(width 0.254)
						(type default)
					)
					(fill
						(type background)
					)
				)
				(circle
					(center 7.62 -5.08)
					(radius 0.254)
					(stroke
						(width 0.254)
						(type default)
					)
					(fill
						(type background)
					)
				)
				(circle
					(center 7.62 -7.62)
					(radius 0.254)
					(stroke
						(width 0.254)
						(type default)
					)
					(fill
						(type background)
					)
				)
				(polyline
					(pts
						(xy 7.62 -10.16) (xy 2.54 -10.16)
					)
					(stroke
						(width 0.254)
						(type default)
					)
					(fill
						(type background)
					)
				)
				(pin passive line
					(at 0 0 0)
					(length 2.54)
					(name "~"
						(effects
							(font
								(size 1.27 1.27)
							)
						)
					)
					(number "1"
						(effects
							(font
								(size 1.27 1.27)
							)
						)
					)
				)
				(pin passive line
					(at 0 0 0)
					(length 2.54)
					(hide yes)
					(name "~"
						(effects
							(font
								(size 1.27 1.27)
							)
						)
					)
					(number "10"
						(effects
							(font
								(size 1.27 1.27)
							)
						)
					)
				)
				(pin passive line
					(at 0 -2.54 0)
					(length 2.54)
					(name "~"
						(effects
							(font
								(size 1.27 1.27)
							)
						)
					)
					(number "2"
						(effects
							(font
								(size 1.27 1.27)
							)
						)
					)
				)
				(pin passive line
					(at 0 -2.54 0)
					(length 2.54)
					(hide yes)
					(name "~"
						(effects
							(font
								(size 1.27 1.27)
							)
						)
					)
					(number "9"
						(effects
							(font
								(size 1.27 1.27)
							)
						)
					)
				)
				(pin passive line
					(at 0 -5.08 0)
					(length 2.54)
					(name "~"
						(effects
							(font
								(size 1.27 1.27)
							)
						)
					)
					(number "4"
						(effects
							(font
								(size 1.27 1.27)
							)
						)
					)
				)
				(pin passive line
					(at 0 -5.08 0)
					(length 2.54)
					(hide yes)
					(name "~"
						(effects
							(font
								(size 1.27 1.27)
							)
						)
					)
					(number "7"
						(effects
							(font
								(size 1.27 1.27)
							)
						)
					)
				)
				(pin passive line
					(at 0 -7.62 0)
					(length 2.54)
					(name "~"
						(effects
							(font
								(size 1.27 1.27)
							)
						)
					)
					(number "5"
						(effects
							(font
								(size 1.27 1.27)
							)
						)
					)
				)
				(pin passive line
					(at 0 -7.62 0)
					(length 2.54)
					(hide yes)
					(name "~"
						(effects
							(font
								(size 1.27 1.27)
							)
						)
					)
					(number "6"
						(effects
							(font
								(size 1.27 1.27)
							)
						)
					)
				)
				(pin power_in line
					(at 0 -10.16 0)
					(length 2.54)
					(name "~"
						(effects
							(font
								(size 1.27 1.27)
							)
						)
					)
					(number "3"
						(effects
							(font
								(size 1.27 1.27)
							)
						)
					)
				)
				(pin passive line
					(at 0 -10.16 0)
					(length 2.54)
					(hide yes)
					(name "~"
						(effects
							(font
								(size 1.27 1.27)
							)
						)
					)
					(number "8"
						(effects
							(font
								(size 1.27 1.27)
							)
						)
					)
				)
			)
		)
	(symbol "antmicroTVSDiodes:PESD5Z5_0F"
			(pin_numbers
				(hide yes)
			)
			(pin_names
				(hide yes)
			)
			(exclude_from_sim no)
			(in_bom yes)
			(on_board yes)
			(property "Reference" "D"
				(at 15.24 0 0)
				(effects
					(font
						(size 1.27 1.27)
						(thickness 0.15)
					)
					(justify left bottom)
				)
			)
			(property "Value" "PESD5Z5_0F"
				(at 15.24 -12.7 0)
				(effects
					(font
						(size 1.27 1.27)
						(thickness 0.15)
					)
					(justify left bottom)
					(hide yes)
				)
			)
			(property "Footprint" "antmicro-footprints:SOD-523"
				(at 15.24 -5.08 0)
				(effects
					(font
						(size 1.27 1.27)
						(thickness 0.15)
					)
					(justify left bottom)
					(hide yes)
				)
			)
			(property "Datasheet" "https://assets.nexperia.com/documents/data-sheet/PESD5Z5_0.pdf"
				(at 15.24 -7.62 0)
				(effects
					(font
						(size 1.27 1.27)
						(thickness 0.15)
					)
					(justify left bottom)
					(hide yes)
				)
			)
			(property "Description" "Unidirectional TVS, 30 kV,  SOD-523, 5 V, 89 pF"
				(at 0 0 0)
				(effects
					(font
						(size 1.27 1.27)
					)
					(hide yes)
				)
			)
			(property "Manufacturer" "Nexperia"
				(at 15.24 -10.16 0)
				(effects
					(font
						(size 1.27 1.27)
						(thickness 0.15)
					)
					(justify left bottom)
					(hide yes)
				)
			)
			(property "MPN" "PESD5Z5.0F"
				(at 15.24 -2.54 0)
				(effects
					(font
						(size 1.27 1.27)
						(thickness 0.15)
					)
					(justify left bottom)
				)
			)
			(property "Author" "Antmicro"
				(at 15.24 -15.24 0)
				(effects
					(font
						(size 1.27 1.27)
						(thickness 0.15)
					)
					(justify left bottom)
					(hide yes)
				)
			)
			(property "Public" "False"
				(at 20.32 -17.78 0)
				(effects
					(font
						(size 1.27 1.27)
					)
					(justify left bottom)
					(hide yes)
				)
			)
			(property "License" "Apache-2.0"
				(at 15.24 -17.78 0)
				(effects
					(font
						(size 1.27 1.27)
						(thickness 0.15)
					)
					(justify left bottom)
					(hide yes)
				)
			)
			(property "ki_keywords" "DIODE, SEMICONDUCTOR, TVS, ESD"
				(at 0 0 0)
				(effects
					(font
						(size 1.27 1.27)
					)
					(hide yes)
				)
			)
			(symbol "PESD5Z5_0F_0_1"
				(polyline
					(pts
						(xy 1.905 0) (xy 0.635 0)
					)
					(stroke
						(width 0)
						(type default)
					)
					(fill
						(type none)
					)
				)
				(polyline
					(pts
						(xy 4.445 0) (xy 3.175 0)
					)
					(stroke
						(width 0)
						(type default)
					)
					(fill
						(type none)
					)
				)
			)
			(symbol "PESD5Z5_0F_1_1"
				(polyline
					(pts
						(xy 1.778 1.016) (xy 1.397 1.016)
					)
					(stroke
						(width 0.254)
						(type default)
					)
					(fill
						(type none)
					)
				)
				(polyline
					(pts
						(xy 1.778 1.016) (xy 1.778 -1.016)
					)
					(stroke
						(width 0.254)
						(type default)
					)
					(fill
						(type none)
					)
				)
				(polyline
					(pts
						(xy 2.159 -1.016) (xy 1.778 -1.016)
					)
					(stroke
						(width 0.254)
						(type default)
					)
					(fill
						(type none)
					)
				)
				(polyline
					(pts
						(xy 3.302 1.016) (xy 3.302 -1.016) (xy 1.778 0) (xy 3.302 1.016)
					)
					(stroke
						(width 0.254)
						(type default)
					)
					(fill
						(type outline)
					)
				)
				(pin passive line
					(at 0 0 0)
					(length 0.635)
					(name "C"
						(effects
							(font
								(size 1.27 1.27)
							)
						)
					)
					(number "1"
						(effects
							(font
								(size 1.27 1.27)
							)
						)
					)
				)
				(pin passive line
					(at 5.08 0 180)
					(length 0.635)
					(name "A"
						(effects
							(font
								(size 1.27 1.27)
							)
						)
					)
					(number "2"
						(effects
							(font
								(size 1.27 1.27)
							)
						)
					)
				)
			)
		)
	(symbol "antmicroTVSDiodes:SMF4L15A"
			(pin_numbers
				(hide yes)
			)
			(pin_names
				(hide yes)
			)
			(exclude_from_sim no)
			(in_bom yes)
			(on_board yes)
			(property "Reference" "D"
				(at 26.67 -5.08 0)
				(effects
					(font
						(size 1.27 1.27)
						(thickness 0.15)
					)
					(justify left bottom)
				)
			)
			(property "Value" "SMF4L15A"
				(at 26.67 -15.24 0)
				(effects
					(font
						(size 1.27 1.27)
						(thickness 0.15)
					)
					(justify left bottom)
					(hide yes)
				)
			)
			(property "Footprint" "antmicro-footprints:SOD-123FL"
				(at 26.67 -10.16 0)
				(effects
					(font
						(size 1.27 1.27)
						(thickness 0.15)
					)
					(justify left bottom)
					(hide yes)
				)
			)
			(property "Datasheet" "https://www.littelfuse.com/media?resourcetype=datasheets&itemid=d2ba8fab-1de3-4176-8530-f36ecb0b8799&filename=smf4l"
				(at 26.67 -12.7 0)
				(effects
					(font
						(size 1.27 1.27)
						(thickness 0.15)
					)
					(justify left bottom)
					(hide yes)
				)
			)
			(property "Description" "Unidirectional TVS, 30 kV,  SOD-123FL, 15 V, 600 pF"
				(at 0 0 0)
				(effects
					(font
						(size 1.27 1.27)
					)
					(hide yes)
				)
			)
			(property "MPN" "SMF4L15A"
				(at 26.67 -7.62 0)
				(effects
					(font
						(size 1.27 1.27)
						(thickness 0.15)
					)
					(justify left bottom)
				)
			)
			(property "Manufacturer" "Littelfuse"
				(at 26.67 -17.78 0)
				(effects
					(font
						(size 1.27 1.27)
						(thickness 0.15)
					)
					(justify left bottom)
					(hide yes)
				)
			)
			(property "Author" "Antmicro"
				(at 26.67 -20.32 0)
				(effects
					(font
						(size 1.27 1.27)
						(thickness 0.15)
					)
					(justify left bottom)
					(hide yes)
				)
			)
			(property "Public" "False"
				(at 20.32 -17.78 0)
				(effects
					(font
						(size 1.27 1.27)
					)
					(justify left bottom)
					(hide yes)
				)
			)
			(property "License" "Apache-2.0"
				(at 26.67 -22.86 0)
				(effects
					(font
						(size 1.27 1.27)
						(thickness 0.15)
					)
					(justify left bottom)
					(hide yes)
				)
			)
			(property "ki_keywords" "DIODE, SEMICONDUCTOR, TVS, ESD"
				(at 0 0 0)
				(effects
					(font
						(size 1.27 1.27)
					)
					(hide yes)
				)
			)
			(symbol "SMF4L15A_0_1"
				(polyline
					(pts
						(xy 1.905 0) (xy 0.635 0)
					)
					(stroke
						(width 0)
						(type default)
					)
					(fill
						(type none)
					)
				)
				(polyline
					(pts
						(xy 4.445 0) (xy 3.175 0)
					)
					(stroke
						(width 0)
						(type default)
					)
					(fill
						(type none)
					)
				)
			)
			(symbol "SMF4L15A_1_1"
				(polyline
					(pts
						(xy 1.778 1.016) (xy 1.397 1.016)
					)
					(stroke
						(width 0.254)
						(type default)
					)
					(fill
						(type none)
					)
				)
				(polyline
					(pts
						(xy 1.778 1.016) (xy 1.778 -1.016)
					)
					(stroke
						(width 0.254)
						(type default)
					)
					(fill
						(type none)
					)
				)
				(polyline
					(pts
						(xy 2.159 -1.016) (xy 1.778 -1.016)
					)
					(stroke
						(width 0.254)
						(type default)
					)
					(fill
						(type none)
					)
				)
				(polyline
					(pts
						(xy 3.302 1.016) (xy 3.302 -1.016) (xy 1.778 0) (xy 3.302 1.016)
					)
					(stroke
						(width 0.254)
						(type default)
					)
					(fill
						(type outline)
					)
				)
				(pin passive line
					(at 0 0 0)
					(length 0.635)
					(name "C"
						(effects
							(font
								(size 1.27 1.27)
							)
						)
					)
					(number "1"
						(effects
							(font
								(size 1.27 1.27)
							)
						)
					)
				)
				(pin passive line
					(at 5.08 0 180)
					(length 0.635)
					(name "A"
						(effects
							(font
								(size 1.27 1.27)
							)
						)
					)
					(number "2"
						(effects
							(font
								(size 1.27 1.27)
							)
						)
					)
				)
			)
		)
	(symbol "antmicroTVSDiodes:TPD2E2U06_SC70"
			(pin_names
				(hide yes)
			)
			(exclude_from_sim no)
			(in_bom yes)
			(on_board yes)
			(property "Reference" "D"
				(at 12.7 2.54 0)
				(effects
					(font
						(size 1.27 1.27)
						(thickness 0.15)
					)
					(justify left bottom)
				)
			)
			(property "Value" "TPD2E2U06_SC70"
				(at 12.7 -2.54 0)
				(effects
					(font
						(size 1.27 1.27)
						(thickness 0.15)
					)
					(justify left bottom)
					(hide yes)
				)
			)
			(property "Footprint" "antmicro-footprints:SC70-3"
				(at 12.7 -5.08 0)
				(effects
					(font
						(size 1.27 1.27)
						(thickness 0.15)
					)
					(justify left bottom)
					(hide yes)
				)
			)
			(property "Datasheet" "https://www.ti.com/lit/ds/symlink/tpd2e2u06.pdf?ts=1706006131823&ref_url=https%253A%252F%252Fwww.ti.com%252Finterface%252Fdiodes%252Fesd-protection-diodes%252Fproducts.html"
				(at 12.7 -7.62 0)
				(effects
					(font
						(size 1.27 1.27)
						(thickness 0.15)
					)
					(justify left bottom)
					(hide yes)
				)
			)
			(property "Description" "TVS diode array, 15 kV, SC70, 5.5V, 1.5 pF"
				(at 0 0 0)
				(effects
					(font
						(size 1.27 1.27)
					)
					(hide yes)
				)
			)
			(property "MPN" "TPD2E2U06DCKR"
				(at 12.7 0 0)
				(effects
					(font
						(size 1.27 1.27)
						(thickness 0.15)
					)
					(justify left bottom)
				)
			)
			(property "Manufacturer" "Texas Instruments"
				(at 12.7 -10.16 0)
				(effects
					(font
						(size 1.27 1.27)
						(thickness 0.15)
					)
					(justify left bottom)
					(hide yes)
				)
			)
			(property "Author" "Antmicro"
				(at 12.7 -12.7 0)
				(effects
					(font
						(size 1.27 1.27)
						(thickness 0.15)
					)
					(justify left bottom)
					(hide yes)
				)
			)
			(property "License" "Apache-2.0"
				(at 12.7 -15.24 0)
				(effects
					(font
						(size 1.27 1.27)
						(thickness 0.15)
					)
					(justify left bottom)
					(hide yes)
				)
			)
			(property "ki_keywords" "SMT, DIODE, SEMICONDUCTOR, TVS, ESD"
				(at 0 0 0)
				(effects
					(font
						(size 1.27 1.27)
					)
					(hide yes)
				)
			)
			(symbol "TPD2E2U06_SC70_0_1"
				(polyline
					(pts
						(xy 2.54 -5.08) (xy 6.35 -5.08) (xy 6.35 0) (xy 5.08 0)
					)
					(stroke
						(width 0.254)
						(type default)
					)
					(fill
						(type none)
					)
				)
				(polyline
					(pts
						(xy 3.81 0) (xy 2.54 0)
					)
					(stroke
						(width 0.254)
						(type default)
					)
					(fill
						(type none)
					)
				)
				(polyline
					(pts
						(xy 3.81 -2.54) (xy 2.54 -2.54)
					)
					(stroke
						(width 0.254)
						(type default)
					)
					(fill
						(type none)
					)
				)
				(polyline
					(pts
						(xy 5.08 -2.54) (xy 6.35 -2.54)
					)
					(stroke
						(width 0.254)
						(type default)
					)
					(fill
						(type none)
					)
				)
			)
			(symbol "TPD2E2U06_SC70_1_1"
				(rectangle
					(start 2.54 2.54)
					(end 7.62 -7.62)
					(stroke
						(width 0.254)
						(type default)
					)
					(fill
						(type background)
					)
				)
				(polyline
					(pts
						(xy 3.81 -0.635) (xy 3.81 -0.381) (xy 3.81 0.381) (xy 4.064 0.635)
					)
					(stroke
						(width 0.254)
						(type default)
					)
					(fill
						(type background)
					)
				)
				(polyline
					(pts
						(xy 3.81 -3.175) (xy 3.81 -2.921) (xy 3.81 -2.159) (xy 4.064 -1.905)
					)
					(stroke
						(width 0.254)
						(type default)
					)
					(fill
						(type background)
					)
				)
				(polyline
					(pts
						(xy 5.08 -0.635) (xy 5.08 0.635) (xy 3.81 0) (xy 5.08 -0.635)
					)
					(stroke
						(width 0.254)
						(type default)
					)
					(fill
						(type outline)
					)
				)
				(polyline
					(pts
						(xy 5.08 -3.175) (xy 5.08 -1.905) (xy 3.81 -2.54) (xy 5.08 -3.175)
					)
					(stroke
						(width 0.254)
						(type default)
					)
					(fill
						(type outline)
					)
				)
				(circle
					(center 6.35 -2.54)
					(radius 0.127)
					(stroke
						(width 0.254)
						(type default)
					)
					(fill
						(type background)
					)
				)
				(pin passive line
					(at 0 0 0)
					(length 2.54)
					(name "1"
						(effects
							(font
								(size 1.27 1.27)
							)
						)
					)
					(number "1"
						(effects
							(font
								(size 1.27 1.27)
							)
						)
					)
				)
				(pin passive line
					(at 0 -2.54 0)
					(length 2.54)
					(name "2"
						(effects
							(font
								(size 1.27 1.27)
							)
						)
					)
					(number "2"
						(effects
							(font
								(size 1.27 1.27)
							)
						)
					)
				)
				(pin passive line
					(at 0 -5.08 0)
					(length 2.54)
					(name "3"
						(effects
							(font
								(size 1.27 1.27)
							)
						)
					)
					(number "3"
						(effects
							(font
								(size 1.27 1.27)
							)
						)
					)
				)
			)
		)
	(symbol "antmicroTemperatureSensorsAnalogandDigitalOutput:ADT7476AARQZ"
			(exclude_from_sim no)
			(in_bom yes)
			(on_board yes)
			(property "Reference" "U"
				(at 48.26 -2.54 0)
				(effects
					(font
						(size 1.27 1.27)
						(thickness 0.15)
					)
					(justify left bottom)
				)
			)
			(property "Value" "ADT7476AARQZ"
				(at 48.26 -7.62 0)
				(effects
					(font
						(size 1.27 1.27)
						(thickness 0.15)
					)
					(justify left bottom)
					(hide yes)
				)
			)
			(property "Footprint" "antmicro-footprints:QSOP-24_8.65x6mm_P0.635mm"
				(at 48.26 -10.16 0)
				(effects
					(font
						(size 1.27 1.27)
						(thickness 0.15)
					)
					(justify left bottom)
					(hide yes)
				)
			)
			(property "Datasheet" "https://www.onsemi.com/pdf/datasheet/adt7476a-d.pdf"
				(at 48.26 -12.7 0)
				(effects
					(font
						(size 1.27 1.27)
						(thickness 0.15)
					)
					(justify left bottom)
					(hide yes)
				)
			)
			(property "Description" "Remote Thermal Monitor, Fan Controller and Voltage Monitor"
				(at 0 0 0)
				(effects
					(font
						(size 1.27 1.27)
					)
					(hide yes)
				)
			)
			(property "MPN" "ADT7476AARQZ"
				(at 48.26 -5.08 0)
				(effects
					(font
						(size 1.27 1.27)
						(thickness 0.15)
					)
					(justify left bottom)
				)
			)
			(property "Manufacturer" "Onsemi"
				(at 48.26 -15.24 0)
				(effects
					(font
						(size 1.27 1.27)
						(thickness 0.15)
					)
					(justify left bottom)
					(hide yes)
				)
			)
			(property "Author" "Antmicro"
				(at 48.26 -17.78 0)
				(effects
					(font
						(size 1.27 1.27)
						(thickness 0.15)
					)
					(justify left bottom)
					(hide yes)
				)
			)
			(property "License" "Apache-2.0"
				(at 48.26 -20.32 0)
				(effects
					(font
						(size 1.27 1.27)
						(thickness 0.15)
					)
					(justify left bottom)
					(hide yes)
				)
			)
			(property "ki_keywords" "IC, PMIC, SMT, MONITOR, CONTROLLER"
				(at 0 0 0)
				(effects
					(font
						(size 1.27 1.27)
					)
					(hide yes)
				)
			)
			(symbol "ADT7476AARQZ_1_1"
				(rectangle
					(start 2.54 2.54)
					(end 30.48 -50.8)
					(stroke
						(width 0.254)
						(type default)
					)
					(fill
						(type background)
					)
				)
				(pin power_in line
					(at 0 0 0)
					(length 2.54)
					(name "VCC"
						(effects
							(font
								(size 1.27 1.27)
							)
						)
					)
					(number "4"
						(effects
							(font
								(size 1.27 1.27)
							)
						)
					)
				)
				(pin passive line
					(at 0 -5.08 0)
					(length 2.54)
					(name "+2.5V_{IN}"
						(effects
							(font
								(size 1.27 1.27)
							)
						)
					)
					(number "22"
						(effects
							(font
								(size 1.27 1.27)
							)
						)
					)
				)
				(pin passive line
					(at 0 -7.62 0)
					(length 2.54)
					(name "+12V_{IN}"
						(effects
							(font
								(size 1.27 1.27)
							)
						)
					)
					(number "21"
						(effects
							(font
								(size 1.27 1.27)
							)
						)
					)
				)
				(pin passive line
					(at 0 -10.16 0)
					(length 2.54)
					(name "+5V_{IN}"
						(effects
							(font
								(size 1.27 1.27)
							)
						)
					)
					(number "20"
						(effects
							(font
								(size 1.27 1.27)
							)
						)
					)
				)
				(pin passive line
					(at 0 -12.7 0)
					(length 2.54)
					(name "V_{CCP}"
						(effects
							(font
								(size 1.27 1.27)
							)
						)
					)
					(number "23"
						(effects
							(font
								(size 1.27 1.27)
							)
						)
					)
				)
				(pin open_collector line
					(at 0 -22.86 0)
					(length 2.54)
					(name "SDA"
						(effects
							(font
								(size 1.27 1.27)
							)
						)
					)
					(number "1"
						(effects
							(font
								(size 1.27 1.27)
							)
						)
					)
				)
				(pin open_collector line
					(at 0 -25.4 0)
					(length 2.54)
					(name "SCL"
						(effects
							(font
								(size 1.27 1.27)
							)
						)
					)
					(number "2"
						(effects
							(font
								(size 1.27 1.27)
							)
						)
					)
				)
				(pin power_in line
					(at 0 -48.26 0)
					(length 2.54)
					(name "GND"
						(effects
							(font
								(size 1.27 1.27)
							)
						)
					)
					(number "3"
						(effects
							(font
								(size 1.27 1.27)
							)
						)
					)
				)
				(pin input line
					(at 33.02 0 180)
					(length 2.54)
					(name "TACH4"
						(effects
							(font
								(size 1.27 1.27)
							)
						)
					)
					(number "14"
						(effects
							(font
								(size 1.27 1.27)
							)
						)
					)
					(alternate "GPIO6" passive line)
					(alternate "~{ADDR_{SEL}}" passive line)
				)
				(pin input line
					(at 33.02 -2.54 180)
					(length 2.54)
					(name "TACH3"
						(effects
							(font
								(size 1.27 1.27)
							)
						)
					)
					(number "9"
						(effects
							(font
								(size 1.27 1.27)
							)
						)
					)
				)
				(pin input line
					(at 33.02 -5.08 180)
					(length 2.54)
					(name "TACH2"
						(effects
							(font
								(size 1.27 1.27)
							)
						)
					)
					(number "12"
						(effects
							(font
								(size 1.27 1.27)
							)
						)
					)
				)
				(pin input line
					(at 33.02 -7.62 180)
					(length 2.54)
					(name "TACH1"
						(effects
							(font
								(size 1.27 1.27)
							)
						)
					)
					(number "11"
						(effects
							(font
								(size 1.27 1.27)
							)
						)
					)
				)
				(pin input line
					(at 33.02 -12.7 180)
					(length 2.54)
					(name "PWM3"
						(effects
							(font
								(size 1.27 1.27)
							)
						)
					)
					(number "13"
						(effects
							(font
								(size 1.27 1.27)
							)
						)
					)
					(alternate "~{ADDREN}" passive line)
				)
				(pin open_collector line
					(at 33.02 -15.24 180)
					(length 2.54)
					(name "PWM2"
						(effects
							(font
								(size 1.27 1.27)
							)
						)
					)
					(number "10"
						(effects
							(font
								(size 1.27 1.27)
							)
						)
					)
					(alternate "~{SMB_{ALERT}}" passive line)
				)
				(pin open_collector line
					(at 33.02 -17.78 180)
					(length 2.54)
					(name "PWM1"
						(effects
							(font
								(size 1.27 1.27)
							)
						)
					)
					(number "24"
						(effects
							(font
								(size 1.27 1.27)
							)
						)
					)
					(alternate "XTO" passive line)
				)
				(pin open_collector line
					(at 33.02 -22.86 180)
					(length 2.54)
					(name "GPIO4"
						(effects
							(font
								(size 1.27 1.27)
							)
						)
					)
					(number "19"
						(effects
							(font
								(size 1.27 1.27)
							)
						)
					)
				)
				(pin open_collector line
					(at 33.02 -25.4 180)
					(length 2.54)
					(name "GPIO3"
						(effects
							(font
								(size 1.27 1.27)
							)
						)
					)
					(number "8"
						(effects
							(font
								(size 1.27 1.27)
							)
						)
					)
				)
				(pin open_collector line
					(at 33.02 -27.94 180)
					(length 2.54)
					(name "GPIO2"
						(effects
							(font
								(size 1.27 1.27)
							)
						)
					)
					(number "7"
						(effects
							(font
								(size 1.27 1.27)
							)
						)
					)
				)
				(pin open_collector line
					(at 33.02 -30.48 180)
					(length 2.54)
					(name "GPIO1"
						(effects
							(font
								(size 1.27 1.27)
							)
						)
					)
					(number "6"
						(effects
							(font
								(size 1.27 1.27)
							)
						)
					)
				)
				(pin open_collector line
					(at 33.02 -33.02 180)
					(length 2.54)
					(name "GPIO0"
						(effects
							(font
								(size 1.27 1.27)
							)
						)
					)
					(number "5"
						(effects
							(font
								(size 1.27 1.27)
							)
						)
					)
				)
				(pin passive line
					(at 33.02 -38.1 180)
					(length 2.54)
					(name "D2+"
						(effects
							(font
								(size 1.27 1.27)
							)
						)
					)
					(number "16"
						(effects
							(font
								(size 1.27 1.27)
							)
						)
					)
				)
				(pin passive line
					(at 33.02 -40.64 180)
					(length 2.54)
					(name "D2-"
						(effects
							(font
								(size 1.27 1.27)
							)
						)
					)
					(number "15"
						(effects
							(font
								(size 1.27 1.27)
							)
						)
					)
				)
				(pin passive line
					(at 33.02 -45.72 180)
					(length 2.54)
					(name "D1+"
						(effects
							(font
								(size 1.27 1.27)
							)
						)
					)
					(number "18"
						(effects
							(font
								(size 1.27 1.27)
							)
						)
					)
				)
				(pin passive line
					(at 33.02 -48.26 180)
					(length 2.54)
					(name "D1-"
						(effects
							(font
								(size 1.27 1.27)
							)
						)
					)
					(number "17"
						(effects
							(font
								(size 1.27 1.27)
							)
						)
					)
				)
			)
		)
	(symbol "antmicroTestPoints:TP_0.75mm_SMD"
			(pin_names
				(hide yes)
			)
			(exclude_from_sim no)
			(in_bom no)
			(on_board yes)
			(property "Reference" "TP"
				(at 10.16 -1.27 0)
				(effects
					(font
						(size 1.27 1.27)
						(thickness 0.15)
					)
					(justify left bottom)
				)
			)
			(property "Value" "TP_0.75mm_SMD"
				(at 10.16 -3.81 0)
				(effects
					(font
						(size 1.27 1.27)
						(thickness 0.15)
					)
					(justify left bottom)
					(hide yes)
				)
			)
			(property "Footprint" "antmicro-footprints:TP_SMD_0.75mm"
				(at 10.16 -6.35 0)
				(effects
					(font
						(size 1.27 1.27)
						(thickness 0.15)
					)
					(justify left bottom)
					(hide yes)
				)
			)
			(property "Datasheet" ""
				(at 17.78 -12.7 0)
				(effects
					(font
						(size 1.27 1.27)
						(thickness 0.15)
					)
					(justify left bottom)
					(hide yes)
				)
			)
			(property "Description" "SMT test point"
				(at 0 0 0)
				(effects
					(font
						(size 1.27 1.27)
					)
					(hide yes)
				)
			)
			(property "MPN" ""
				(at 10.795 -11.43 0)
				(effects
					(font
						(size 1.27 1.27)
						(thickness 0.15)
					)
					(justify left bottom)
					(hide yes)
				)
			)
			(property "Manufacturer" ""
				(at 10.795 -6.35 0)
				(effects
					(font
						(size 1.27 1.27)
						(thickness 0.15)
					)
					(justify left bottom)
					(hide yes)
				)
			)
			(property "Author" "Antmicro"
				(at 10.16 -8.89 0)
				(effects
					(font
						(size 1.27 1.27)
						(thickness 0.15)
					)
					(justify left bottom)
					(hide yes)
				)
			)
			(property "License" "Apache-2.0"
				(at 10.16 -11.43 0)
				(effects
					(font
						(size 1.27 1.27)
						(thickness 0.15)
					)
					(justify left bottom)
					(hide yes)
				)
			)
			(property "Public" "False"
				(at 10.16 -13.97 0)
				(effects
					(font
						(size 1.27 1.27)
					)
					(justify left bottom)
					(hide yes)
				)
			)
			(property "ki_keywords" "TESTPOINT"
				(at 0 0 0)
				(effects
					(font
						(size 1.27 1.27)
					)
					(hide yes)
				)
			)
			(symbol "TP_0.75mm_SMD_1_1"
				(circle
					(center 3.175 0)
					(radius 0.635)
					(stroke
						(width 0.254)
						(type default)
					)
					(fill
						(type none)
					)
				)
				(pin passive line
					(at 0 0 0)
					(length 2.54)
					(name "1"
						(effects
							(font
								(size 1.27 1.27)
							)
						)
					)
					(number "1"
						(effects
							(font
								(size 1.27 1.27)
							)
						)
					)
				)
			)
		)
	(symbol "antmicroTransistorsBipolarSingle:MMBT3904LT1G"
			(pin_names
				(offset 0)
				(hide yes)
			)
			(exclude_from_sim no)
			(in_bom yes)
			(on_board yes)
			(property "Reference" "Q"
				(at 15.24 -5.08 0)
				(effects
					(font
						(size 1.27 1.27)
						(thickness 0.15)
					)
					(justify left bottom)
				)
			)
			(property "Value" "MMBT3904LT1G"
				(at 15.24 -10.16 0)
				(effects
					(font
						(size 1.27 1.27)
						(thickness 0.15)
					)
					(justify left bottom)
					(hide yes)
				)
			)
			(property "Footprint" "antmicro-footprints:SOT-23-3"
				(at 15.24 -12.7 0)
				(effects
					(font
						(size 1.27 1.27)
						(thickness 0.15)
					)
					(justify left bottom)
					(hide yes)
				)
			)
			(property "Datasheet" "https://eu.mouser.com/datasheet/2/308/1/MMBT3904LT1_D-2316262.pdf"
				(at 15.24 -15.24 0)
				(effects
					(font
						(size 1.27 1.27)
						(thickness 0.15)
					)
					(justify left bottom)
					(hide yes)
				)
			)
			(property "Description" "Bipolar Transistors - BJT NPN GENERAL PURPOSE"
				(at 0 0 0)
				(effects
					(font
						(size 1.27 1.27)
					)
					(hide yes)
				)
			)
			(property "MPN" "MMBT3904LT1G"
				(at 15.24 -7.62 0)
				(effects
					(font
						(size 1.27 1.27)
						(thickness 0.15)
					)
					(justify left bottom)
				)
			)
			(property "Manufacturer" "Onsemi"
				(at 15.24 -17.78 0)
				(effects
					(font
						(size 1.27 1.27)
						(thickness 0.15)
					)
					(justify left bottom)
					(hide yes)
				)
			)
			(property "Author" "Antmicro"
				(at 15.24 -20.32 0)
				(effects
					(font
						(size 1.27 1.27)
						(thickness 0.15)
					)
					(justify left bottom)
					(hide yes)
				)
			)
			(property "License" "Apache-2.0"
				(at 15.24 -22.86 0)
				(effects
					(font
						(size 1.27 1.27)
						(thickness 0.15)
					)
					(justify left bottom)
					(hide yes)
				)
			)
			(property "Public" "False"
				(at 22.86 -20.32 0)
				(effects
					(font
						(size 1.27 1.27)
					)
					(justify left bottom)
					(hide yes)
				)
			)
			(property "ki_keywords" "SMT, TRANSISTOR, SEMICONDUCTOR, BIPOLAR"
				(at 0 0 0)
				(effects
					(font
						(size 1.27 1.27)
					)
					(hide yes)
				)
			)
			(property "ki_fp_filters" "SOT?323*"
				(at 0 0 0)
				(effects
					(font
						(size 1.27 1.27)
					)
					(hide yes)
				)
			)
			(symbol "MMBT3904LT1G_0_1"
				(polyline
					(pts
						(xy 2.54 0) (xy 4.445 0)
					)
					(stroke
						(width 0)
						(type default)
					)
					(fill
						(type none)
					)
				)
				(polyline
					(pts
						(xy 4.445 1.905) (xy 4.445 -1.905) (xy 4.445 -1.905)
					)
					(stroke
						(width 0.508)
						(type default)
					)
					(fill
						(type none)
					)
				)
				(polyline
					(pts
						(xy 4.445 0.635) (xy 6.35 2.54)
					)
					(stroke
						(width 0)
						(type default)
					)
					(fill
						(type none)
					)
				)
				(polyline
					(pts
						(xy 4.445 -0.635) (xy 6.35 -2.54) (xy 6.35 -2.54)
					)
					(stroke
						(width 0)
						(type default)
					)
					(fill
						(type none)
					)
				)
				(circle
					(center 5.08 0)
					(radius 2.8194)
					(stroke
						(width 0.254)
						(type default)
					)
					(fill
						(type background)
					)
				)
				(polyline
					(pts
						(xy 5.08 -1.778) (xy 5.588 -1.27) (xy 6.096 -2.286) (xy 5.08 -1.778) (xy 5.08 -1.778)
					)
					(stroke
						(width 0)
						(type default)
					)
					(fill
						(type outline)
					)
				)
			)
			(symbol "MMBT3904LT1G_1_1"
				(pin input line
					(at 0 0 0)
					(length 2.54)
					(name "B"
						(effects
							(font
								(size 1.27 1.27)
							)
						)
					)
					(number "1"
						(effects
							(font
								(size 1.27 1.27)
							)
						)
					)
				)
				(pin passive line
					(at 6.35 5.08 270)
					(length 2.54)
					(name "C"
						(effects
							(font
								(size 1.27 1.27)
							)
						)
					)
					(number "3"
						(effects
							(font
								(size 1.27 1.27)
							)
						)
					)
				)
				(pin passive line
					(at 6.35 -5.08 90)
					(length 2.54)
					(name "E"
						(effects
							(font
								(size 1.27 1.27)
							)
						)
					)
					(number "2"
						(effects
							(font
								(size 1.27 1.27)
							)
						)
					)
				)
			)
		)
	(symbol "antmicroTransistorsFETsMOSFETsSingle:BSS138-7-F"
			(pin_names
				(offset 0)
			)
			(exclude_from_sim no)
			(in_bom yes)
			(on_board yes)
			(property "Reference" "Q"
				(at 22.86 -2.54 0)
				(effects
					(font
						(size 1.27 1.27)
						(thickness 0.15)
					)
					(justify left bottom)
				)
			)
			(property "Value" "BSS138-7-F"
				(at 22.86 -5.08 0)
				(effects
					(font
						(size 1.27 1.27)
						(thickness 0.15)
					)
					(justify left bottom)
					(hide yes)
				)
			)
			(property "Footprint" "antmicro-footprints:SOT-23-3"
				(at 22.86 -7.62 0)
				(effects
					(font
						(size 1.27 1.27)
						(thickness 0.15)
					)
					(justify left bottom)
					(hide yes)
				)
			)
			(property "Datasheet" "https://www.diodes.com/assets/Datasheets/ds30144.pdf"
				(at 22.86 -10.16 0)
				(effects
					(font
						(size 1.27 1.27)
						(thickness 0.15)
					)
					(justify left bottom)
					(hide yes)
				)
			)
			(property "Description" "Power MOSFET, N Channel, 50 V, 200 mA, 1.4 ohm, SOT-23, Surface Mount"
				(at 0 0 0)
				(effects
					(font
						(size 1.27 1.27)
					)
					(hide yes)
				)
			)
			(property "MPN" "BSS138-7-F"
				(at 22.86 -12.7 0)
				(effects
					(font
						(size 1.27 1.27)
						(thickness 0.15)
					)
					(justify left bottom)
				)
			)
			(property "Manufacturer" "Diodes Incorporated"
				(at 22.86 -15.24 0)
				(effects
					(font
						(size 1.27 1.27)
						(thickness 0.15)
					)
					(justify left bottom)
					(hide yes)
				)
			)
			(property "Author" "Antmicro"
				(at 22.86 -17.78 0)
				(effects
					(font
						(size 1.27 1.27)
						(thickness 0.15)
					)
					(justify left bottom)
					(hide yes)
				)
			)
			(property "License" "Apache-2.0"
				(at 22.86 -20.32 0)
				(effects
					(font
						(size 1.27 1.27)
						(thickness 0.15)
					)
					(justify left bottom)
					(hide yes)
				)
			)
			(property "ki_keywords" "SMT, MOSFET, SEMICONDUCTOR"
				(at 0 0 0)
				(effects
					(font
						(size 1.27 1.27)
					)
					(hide yes)
				)
			)
			(symbol "BSS138-7-F_1_1"
				(polyline
					(pts
						(xy 2.54 0) (xy 4.572 0) (xy 4.572 3.937)
					)
					(stroke
						(width 0.254)
						(type default)
					)
					(fill
						(type none)
					)
				)
				(polyline
					(pts
						(xy 5.08 4.445) (xy 5.08 3.429)
					)
					(stroke
						(width 0.254)
						(type default)
					)
					(fill
						(type background)
					)
				)
				(polyline
					(pts
						(xy 5.08 2.54) (xy 5.08 3.048)
					)
					(stroke
						(width 0.254)
						(type default)
					)
					(fill
						(type background)
					)
				)
				(polyline
					(pts
						(xy 5.08 2.54) (xy 5.08 2.032)
					)
					(stroke
						(width 0.254)
						(type default)
					)
					(fill
						(type background)
					)
				)
				(polyline
					(pts
						(xy 5.08 2.54) (xy 5.842 3.048) (xy 5.842 2.032) (xy 5.08 2.54)
					)
					(stroke
						(width 0.254)
						(type default)
					)
					(fill
						(type outline)
					)
				)
				(polyline
					(pts
						(xy 5.08 1.143) (xy 5.08 1.651)
					)
					(stroke
						(width 0.254)
						(type default)
					)
					(fill
						(type background)
					)
				)
				(polyline
					(pts
						(xy 5.08 1.143) (xy 5.08 0.635)
					)
					(stroke
						(width 0.254)
						(type default)
					)
					(fill
						(type background)
					)
				)
				(circle
					(center 6.35 2.54)
					(radius 3.302)
					(stroke
						(width 0.254)
						(type default)
					)
					(fill
						(type background)
					)
				)
				(polyline
					(pts
						(xy 7.493 0.635) (xy 8.636 0.635) (xy 8.636 3.937) (xy 8.636 4.445) (xy 7.493 4.445)
					)
					(stroke
						(width 0.254)
						(type default)
					)
					(fill
						(type background)
					)
				)
				(polyline
					(pts
						(xy 7.62 6.35) (xy 7.62 3.937) (xy 5.08 3.937)
					)
					(stroke
						(width 0.254)
						(type default)
					)
					(fill
						(type none)
					)
				)
				(circle
					(center 7.62 4.445)
					(radius 0.127)
					(stroke
						(width 0.254)
						(type default)
					)
					(fill
						(type background)
					)
				)
				(polyline
					(pts
						(xy 7.62 1.143) (xy 5.08 1.143)
					)
					(stroke
						(width 0.254)
						(type default)
					)
					(fill
						(type background)
					)
				)
				(circle
					(center 7.62 1.143)
					(radius 0.127)
					(stroke
						(width 0.254)
						(type default)
					)
					(fill
						(type background)
					)
				)
				(circle
					(center 7.62 0.635)
					(radius 0.127)
					(stroke
						(width 0.254)
						(type default)
					)
					(fill
						(type background)
					)
				)
				(polyline
					(pts
						(xy 7.62 -1.27) (xy 7.62 2.54) (xy 5.08 2.54)
					)
					(stroke
						(width 0.254)
						(type default)
					)
					(fill
						(type none)
					)
				)
				(polyline
					(pts
						(xy 8.636 3.048) (xy 8.128 2.286) (xy 9.144 2.286) (xy 8.636 3.048)
					)
					(stroke
						(width 0.254)
						(type default)
					)
					(fill
						(type outline)
					)
				)
				(polyline
					(pts
						(xy 9.144 3.048) (xy 8.128 3.048)
					)
					(stroke
						(width 0.254)
						(type default)
					)
					(fill
						(type background)
					)
				)
				(pin bidirectional line
					(at 0 0 0)
					(length 2.54)
					(name "G"
						(effects
							(font
								(size 1.27 1.27)
							)
						)
					)
					(number "1"
						(effects
							(font
								(size 1.27 1.27)
							)
						)
					)
				)
				(pin bidirectional line
					(at 7.62 8.89 270)
					(length 2.54)
					(name "D"
						(effects
							(font
								(size 1.27 1.27)
							)
						)
					)
					(number "3"
						(effects
							(font
								(size 1.27 1.27)
							)
						)
					)
				)
				(pin bidirectional line
					(at 7.62 -3.81 90)
					(length 2.54)
					(name "S"
						(effects
							(font
								(size 1.27 1.27)
							)
						)
					)
					(number "2"
						(effects
							(font
								(size 1.27 1.27)
							)
						)
					)
				)
			)
		)
	(symbol "antmicroTransistorsFETsMOSFETsSingle:BSS84AKW"
			(pin_names
				(offset 0)
			)
			(exclude_from_sim no)
			(in_bom yes)
			(on_board yes)
			(property "Reference" "Q"
				(at 22.86 -2.54 0)
				(effects
					(font
						(size 1.27 1.27)
						(thickness 0.15)
					)
					(justify left bottom)
				)
			)
			(property "Value" "BSS84AKW"
				(at 22.86 -7.62 0)
				(effects
					(font
						(size 1.27 1.27)
						(thickness 0.15)
					)
					(justify left bottom)
					(hide yes)
				)
			)
			(property "Footprint" "antmicro-footprints:SOT-323"
				(at 22.86 -10.16 0)
				(effects
					(font
						(size 1.27 1.27)
						(thickness 0.15)
					)
					(justify left bottom)
					(hide yes)
				)
			)
			(property "Datasheet" "https://assets.nexperia.com/documents/data-sheet/BSS84AKW.pdf"
				(at 22.86 -12.7 0)
				(effects
					(font
						(size 1.27 1.27)
						(thickness 0.15)
					)
					(justify left bottom)
					(hide yes)
				)
			)
			(property "Description" "Power MOSFET, P Channel, 50 V, 150 mA, 4.5 ohm, SOT-323, Surface Mount"
				(at 0 0 0)
				(effects
					(font
						(size 1.27 1.27)
					)
					(hide yes)
				)
			)
			(property "MPN" "BSS84AKW,115"
				(at 22.86 -5.08 0)
				(effects
					(font
						(size 1.27 1.27)
						(thickness 0.15)
					)
					(justify left bottom)
				)
			)
			(property "Manufacturer" "Nexperia"
				(at 22.86 -15.24 0)
				(effects
					(font
						(size 1.27 1.27)
						(thickness 0.15)
					)
					(justify left bottom)
					(hide yes)
				)
			)
			(property "Author" "Antmicro"
				(at 22.86 -17.78 0)
				(effects
					(font
						(size 1.27 1.27)
						(thickness 0.15)
					)
					(justify left bottom)
					(hide yes)
				)
			)
			(property "License" "Apache-2.0"
				(at 22.86 -20.32 0)
				(effects
					(font
						(size 1.27 1.27)
						(thickness 0.15)
					)
					(justify left bottom)
					(hide yes)
				)
			)
			(property "ki_keywords" "SMT, TRANSISTOR, SEMICONDUCTOR, MOSFET, PMOS"
				(at 0 0 0)
				(effects
					(font
						(size 1.27 1.27)
					)
					(hide yes)
				)
			)
			(symbol "BSS84AKW_1_1"
				(polyline
					(pts
						(xy 2.54 0) (xy 4.572 0) (xy 4.572 3.937)
					)
					(stroke
						(width 0.254)
						(type default)
					)
					(fill
						(type none)
					)
				)
				(polyline
					(pts
						(xy 5.08 4.445) (xy 5.08 3.429)
					)
					(stroke
						(width 0.254)
						(type default)
					)
					(fill
						(type background)
					)
				)
				(polyline
					(pts
						(xy 5.08 2.54) (xy 5.08 3.048)
					)
					(stroke
						(width 0.254)
						(type default)
					)
					(fill
						(type background)
					)
				)
				(polyline
					(pts
						(xy 5.08 2.54) (xy 5.08 2.032)
					)
					(stroke
						(width 0.254)
						(type default)
					)
					(fill
						(type background)
					)
				)
				(polyline
					(pts
						(xy 5.08 1.143) (xy 5.08 1.651)
					)
					(stroke
						(width 0.254)
						(type default)
					)
					(fill
						(type background)
					)
				)
				(polyline
					(pts
						(xy 5.08 1.143) (xy 5.08 0.635)
					)
					(stroke
						(width 0.254)
						(type default)
					)
					(fill
						(type background)
					)
				)
				(circle
					(center 6.35 2.54)
					(radius 3.302)
					(stroke
						(width 0.254)
						(type default)
					)
					(fill
						(type background)
					)
				)
				(polyline
					(pts
						(xy 7.239 2.54) (xy 6.477 3.048) (xy 6.477 2.032) (xy 7.239 2.54)
					)
					(stroke
						(width 0.254)
						(type default)
					)
					(fill
						(type outline)
					)
				)
				(polyline
					(pts
						(xy 7.493 0.635) (xy 8.636 0.635) (xy 8.636 3.937) (xy 8.636 4.445) (xy 7.493 4.445)
					)
					(stroke
						(width 0.254)
						(type default)
					)
					(fill
						(type background)
					)
				)
				(polyline
					(pts
						(xy 7.62 6.35) (xy 7.62 3.937) (xy 5.08 3.937)
					)
					(stroke
						(width 0.254)
						(type default)
					)
					(fill
						(type none)
					)
				)
				(circle
					(center 7.62 4.445)
					(radius 0.127)
					(stroke
						(width 0.254)
						(type default)
					)
					(fill
						(type background)
					)
				)
				(polyline
					(pts
						(xy 7.62 1.143) (xy 5.08 1.143)
					)
					(stroke
						(width 0.254)
						(type default)
					)
					(fill
						(type background)
					)
				)
				(circle
					(center 7.62 1.143)
					(radius 0.127)
					(stroke
						(width 0.254)
						(type default)
					)
					(fill
						(type background)
					)
				)
				(circle
					(center 7.62 0.635)
					(radius 0.127)
					(stroke
						(width 0.254)
						(type default)
					)
					(fill
						(type background)
					)
				)
				(polyline
					(pts
						(xy 7.62 -1.27) (xy 7.62 2.54) (xy 5.08 2.54)
					)
					(stroke
						(width 0.254)
						(type default)
					)
					(fill
						(type none)
					)
				)
				(polyline
					(pts
						(xy 8.636 2.286) (xy 9.144 3.048) (xy 8.128 3.048) (xy 8.636 2.286)
					)
					(stroke
						(width 0.254)
						(type default)
					)
					(fill
						(type outline)
					)
				)
				(polyline
					(pts
						(xy 9.144 2.3368) (xy 8.128 2.3368)
					)
					(stroke
						(width 0.254)
						(type default)
					)
					(fill
						(type background)
					)
				)
				(pin bidirectional line
					(at 0 0 0)
					(length 2.54)
					(name "G"
						(effects
							(font
								(size 1.27 1.27)
							)
						)
					)
					(number "1"
						(effects
							(font
								(size 1.27 1.27)
							)
						)
					)
				)
				(pin bidirectional line
					(at 7.62 8.89 270)
					(length 2.54)
					(name "D"
						(effects
							(font
								(size 1.27 1.27)
							)
						)
					)
					(number "3"
						(effects
							(font
								(size 1.27 1.27)
							)
						)
					)
				)
				(pin bidirectional line
					(at 7.62 -3.81 90)
					(length 2.54)
					(name "S"
						(effects
							(font
								(size 1.27 1.27)
							)
						)
					)
					(number "2"
						(effects
							(font
								(size 1.27 1.27)
							)
						)
					)
				)
			)
		)
	(symbol "antmicroTransistorsFETsMOSFETsSingle:SI7613DN-T1-GE3"
			(pin_names
				(offset 0)
			)
			(exclude_from_sim no)
			(in_bom yes)
			(on_board yes)
			(property "Reference" "Q"
				(at 15.24 5.08 0)
				(effects
					(font
						(size 1.27 1.27)
						(thickness 0.15)
					)
					(justify left bottom)
				)
			)
			(property "Value" "SI7613DN-T1-GE3"
				(at 15.24 2.54 0)
				(effects
					(font
						(size 1.27 1.27)
						(thickness 0.15)
					)
					(justify left bottom)
					(hide yes)
				)
			)
			(property "Footprint" "antmicro-footprints:Vishay_PowerPAK_1212-8_Single"
				(at 15.24 1.27 0)
				(effects
					(font
						(size 1.27 1.27)
						(thickness 0.15)
					)
					(justify left bottom)
					(hide yes)
				)
			)
			(property "Datasheet" "https://www.vishay.com/docs/64809/si7613dn.pdf"
				(at 15.24 -1.27 0)
				(effects
					(font
						(size 1.27 1.27)
						(thickness 0.15)
					)
					(justify left bottom)
					(hide yes)
				)
			)
			(property "Description" "Power MOSFET, P Channel, 20 V, 35 A, 0.0072 ohm, PowerPAK 1212, Surface Mount"
				(at 0 0 0)
				(effects
					(font
						(size 1.27 1.27)
					)
					(hide yes)
				)
			)
			(property "MPN" "SI7613DN-T1-GE3"
				(at 15.24 -5.08 0)
				(effects
					(font
						(size 1.27 1.27)
						(thickness 0.15)
					)
					(justify left bottom)
				)
			)
			(property "Manufacturer" "Vishay"
				(at 15.24 -7.62 0)
				(effects
					(font
						(size 1.27 1.27)
						(thickness 0.15)
					)
					(justify left bottom)
					(hide yes)
				)
			)
			(property "Author" "Antmicro"
				(at 15.24 -10.16 0)
				(effects
					(font
						(size 1.27 1.27)
						(thickness 0.15)
					)
					(justify left bottom)
					(hide yes)
				)
			)
			(property "License" "Apache-2.0"
				(at 15.24 -12.7 0)
				(effects
					(font
						(size 1.27 1.27)
						(thickness 0.15)
					)
					(justify left bottom)
					(hide yes)
				)
			)
			(property "ki_keywords" "SMT, TRANSISTOR, SEMICONDUCTOR, MOSFET, PMOS"
				(at 0 0 0)
				(effects
					(font
						(size 1.27 1.27)
					)
					(hide yes)
				)
			)
			(symbol "SI7613DN-T1-GE3_1_1"
				(polyline
					(pts
						(xy 2.54 0) (xy 4.572 0) (xy 4.572 3.937)
					)
					(stroke
						(width 0.254)
						(type default)
					)
					(fill
						(type none)
					)
				)
				(polyline
					(pts
						(xy 5.08 4.445) (xy 5.08 3.429)
					)
					(stroke
						(width 0.254)
						(type default)
					)
					(fill
						(type background)
					)
				)
				(polyline
					(pts
						(xy 5.08 2.54) (xy 5.08 3.048)
					)
					(stroke
						(width 0.254)
						(type default)
					)
					(fill
						(type background)
					)
				)
				(polyline
					(pts
						(xy 5.08 2.54) (xy 5.08 2.032)
					)
					(stroke
						(width 0.254)
						(type default)
					)
					(fill
						(type background)
					)
				)
				(polyline
					(pts
						(xy 5.08 1.143) (xy 5.08 1.651)
					)
					(stroke
						(width 0.254)
						(type default)
					)
					(fill
						(type background)
					)
				)
				(polyline
					(pts
						(xy 5.08 1.143) (xy 5.08 0.635)
					)
					(stroke
						(width 0.254)
						(type default)
					)
					(fill
						(type background)
					)
				)
				(circle
					(center 6.35 2.54)
					(radius 3.302)
					(stroke
						(width 0.254)
						(type default)
					)
					(fill
						(type background)
					)
				)
				(polyline
					(pts
						(xy 7.239 2.54) (xy 6.477 3.048) (xy 6.477 2.032) (xy 7.239 2.54)
					)
					(stroke
						(width 0.254)
						(type default)
					)
					(fill
						(type outline)
					)
				)
				(polyline
					(pts
						(xy 7.493 0.635) (xy 8.636 0.635) (xy 8.636 3.937) (xy 8.636 4.445) (xy 7.493 4.445)
					)
					(stroke
						(width 0.254)
						(type default)
					)
					(fill
						(type background)
					)
				)
				(polyline
					(pts
						(xy 7.62 6.35) (xy 7.62 3.937) (xy 5.08 3.937)
					)
					(stroke
						(width 0.254)
						(type default)
					)
					(fill
						(type none)
					)
				)
				(circle
					(center 7.62 4.445)
					(radius 0.127)
					(stroke
						(width 0.254)
						(type default)
					)
					(fill
						(type background)
					)
				)
				(polyline
					(pts
						(xy 7.62 1.143) (xy 5.08 1.143)
					)
					(stroke
						(width 0.254)
						(type default)
					)
					(fill
						(type background)
					)
				)
				(circle
					(center 7.62 1.143)
					(radius 0.127)
					(stroke
						(width 0.254)
						(type default)
					)
					(fill
						(type background)
					)
				)
				(circle
					(center 7.62 0.635)
					(radius 0.127)
					(stroke
						(width 0.254)
						(type default)
					)
					(fill
						(type background)
					)
				)
				(polyline
					(pts
						(xy 7.62 -1.27) (xy 7.62 2.54) (xy 5.08 2.54)
					)
					(stroke
						(width 0.254)
						(type default)
					)
					(fill
						(type none)
					)
				)
				(polyline
					(pts
						(xy 8.636 2.286) (xy 8.128 3.048) (xy 9.144 3.048) (xy 8.636 2.286)
					)
					(stroke
						(width 0.254)
						(type default)
					)
					(fill
						(type outline)
					)
				)
				(polyline
					(pts
						(xy 9.144 2.2352) (xy 8.128 2.2352)
					)
					(stroke
						(width 0.254)
						(type default)
					)
					(fill
						(type background)
					)
				)
				(pin passive line
					(at 0 0 0)
					(length 2.54)
					(name "G"
						(effects
							(font
								(size 1.27 1.27)
							)
						)
					)
					(number "4"
						(effects
							(font
								(size 1.27 1.27)
							)
						)
					)
				)
				(pin passive line
					(at 7.62 8.89 270)
					(length 2.54)
					(name "D"
						(effects
							(font
								(size 1.27 1.27)
							)
						)
					)
					(number "5"
						(effects
							(font
								(size 1.27 1.27)
							)
						)
					)
				)
				(pin passive line
					(at 7.62 -3.81 90)
					(length 2.54)
					(name "S"
						(effects
							(font
								(size 1.27 1.27)
							)
						)
					)
					(number "1"
						(effects
							(font
								(size 1.27 1.27)
							)
						)
					)
				)
				(pin passive line
					(at 7.62 -3.81 90)
					(length 2.54)
					(hide yes)
					(name "S"
						(effects
							(font
								(size 1.27 1.27)
							)
						)
					)
					(number "2"
						(effects
							(font
								(size 1.27 1.27)
							)
						)
					)
				)
				(pin passive line
					(at 7.62 -3.81 90)
					(length 2.54)
					(hide yes)
					(name "S"
						(effects
							(font
								(size 1.27 1.27)
							)
						)
					)
					(number "3"
						(effects
							(font
								(size 1.27 1.27)
							)
						)
					)
				)
			)
		)
	(symbol "antmicroUSBConnectors:USB-C_Kycon_KUSBX-SL2-CS1N24-B-TR"
			(exclude_from_sim no)
			(in_bom yes)
			(on_board yes)
			(property "Reference" "J"
				(at 43.18 -2.54 0)
				(effects
					(font
						(size 1.27 1.27)
						(thickness 0.15)
					)
					(justify left bottom)
				)
			)
			(property "Value" "USB-C_Kycon_KUSBX-SL2-CS1N24-B-TR"
				(at 43.18 -5.08 0)
				(effects
					(font
						(size 1.27 1.27)
						(thickness 0.15)
					)
					(justify left bottom)
				)
			)
			(property "Footprint" "antmicro-footprints:USB-C_Receptacle_Kycon_KUSBX-SL2-CS1N24-B-TR"
				(at 43.18 -7.62 0)
				(effects
					(font
						(size 1.27 1.27)
						(thickness 0.15)
					)
					(justify left bottom)
					(hide yes)
				)
			)
			(property "Datasheet" "https://www.kycon.com/Pub_Eng_Draw/KUSBX-SL2-CS1N24-B-TR.pdf"
				(at 43.18 -10.16 0)
				(effects
					(font
						(size 1.27 1.27)
						(thickness 0.15)
					)
					(justify left bottom)
					(hide yes)
				)
			)
			(property "Description" "USB-C (USB TYPE-C) USB 3.2 Gen 2 (USB 3.1 Gen 2, Superspeed + (USB 3.1)) USB PD Receptacle Connector 24 Position Surface Mount"
				(at 0 0 0)
				(effects
					(font
						(size 1.27 1.27)
					)
					(hide yes)
				)
			)
			(property "MPN" "KUSBX-SL2-CS1N24-B-TR"
				(at 43.18 -12.7 0)
				(effects
					(font
						(size 1.27 1.27)
						(thickness 0.15)
					)
					(justify left bottom)
					(hide yes)
				)
			)
			(property "Manufacturer" "Kycon"
				(at 43.18 -15.24 0)
				(effects
					(font
						(size 1.27 1.27)
						(thickness 0.15)
					)
					(justify left bottom)
					(hide yes)
				)
			)
			(property "License" "Apache-2.0"
				(at 43.18 -17.78 0)
				(effects
					(font
						(size 1.27 1.27)
						(thickness 0.15)
					)
					(justify left bottom)
					(hide yes)
				)
			)
			(property "Author" "Antmicro"
				(at 43.18 -20.32 0)
				(effects
					(font
						(size 1.27 1.27)
						(thickness 0.15)
					)
					(justify left bottom)
					(hide yes)
				)
			)
			(property "ki_keywords" "USB, CONNECTOR, SMT, HORIZONTAL"
				(at 0 0 0)
				(effects
					(font
						(size 1.27 1.27)
					)
					(hide yes)
				)
			)
			(symbol "USB-C_Kycon_KUSBX-SL2-CS1N24-B-TR_1_1"
				(rectangle
					(start -22.86 -68.58)
					(end -3.81 2.54)
					(stroke
						(width 0.254)
						(type default)
					)
					(fill
						(type background)
					)
				)
				(circle
					(center -20.066 -33.274)
					(radius 0.284)
					(stroke
						(width 0.254)
						(type default)
					)
					(fill
						(type outline)
					)
				)
				(polyline
					(pts
						(xy -19.812 -31.623) (xy -19.177 -30.48) (xy -18.542 -31.623) (xy -19.812 -31.623)
					)
					(stroke
						(width 0.254)
						(type default)
					)
					(fill
						(type outline)
					)
				)
				(polyline
					(pts
						(xy -19.177 -34.798) (xy -18.288 -33.909) (xy -18.288 -33.274)
					)
					(stroke
						(width 0.254)
						(type default)
					)
					(fill
						(type background)
					)
				)
				(polyline
					(pts
						(xy -19.177 -35.179) (xy -20.066 -34.29) (xy -20.066 -33.655)
					)
					(stroke
						(width 0.254)
						(type default)
					)
					(fill
						(type background)
					)
				)
				(polyline
					(pts
						(xy -19.177 -35.941) (xy -19.177 -31.623)
					)
					(stroke
						(width 0.254)
						(type default)
					)
					(fill
						(type background)
					)
				)
				(circle
					(center -19.177 -36.068)
					(radius 0.5236)
					(stroke
						(width 0.254)
						(type default)
					)
					(fill
						(type outline)
					)
				)
				(rectangle
					(start -18.669 -33.274)
					(end -17.907 -32.512)
					(stroke
						(width 0.254)
						(type default)
					)
					(fill
						(type outline)
					)
				)
				(polyline
					(pts
						(xy -16.51 -36.83) (xy -16.51 -29.21)
					)
					(stroke
						(width 0.254)
						(type default)
					)
					(fill
						(type background)
					)
				)
				(rectangle
					(start -15.24 -36.83)
					(end -13.97 -29.21)
					(stroke
						(width 0.254)
						(type default)
					)
					(fill
						(type outline)
					)
				)
				(arc
					(start -15.24 -29.21)
					(mid -14.605 -28.5777)
					(end -13.97 -29.21)
					(stroke
						(width 0.254)
						(type default)
					)
					(fill
						(type outline)
					)
				)
				(arc
					(start -15.24 -29.21)
					(mid -14.605 -28.5777)
					(end -13.97 -29.21)
					(stroke
						(width 0.254)
						(type default)
					)
					(fill
						(type background)
					)
				)
				(arc
					(start -16.51 -29.21)
					(mid -14.605 -27.3133)
					(end -12.7 -29.21)
					(stroke
						(width 0.254)
						(type default)
					)
					(fill
						(type background)
					)
				)
				(arc
					(start -12.7 -36.83)
					(mid -14.605 -38.7267)
					(end -16.51 -36.83)
					(stroke
						(width 0.254)
						(type default)
					)
					(fill
						(type background)
					)
				)
				(arc
					(start -13.97 -36.83)
					(mid -14.605 -37.4623)
					(end -15.24 -36.83)
					(stroke
						(width 0.254)
						(type default)
					)
					(fill
						(type outline)
					)
				)
				(arc
					(start -13.97 -36.83)
					(mid -14.605 -37.4623)
					(end -15.24 -36.83)
					(stroke
						(width 0.254)
						(type default)
					)
					(fill
						(type background)
					)
				)
				(polyline
					(pts
						(xy -12.7 -29.21) (xy -12.7 -36.83)
					)
					(stroke
						(width 0.254)
						(type default)
					)
					(fill
						(type background)
					)
				)
				(pin passive line
					(at 0 0 180)
					(length 3.81)
					(name "VBUS"
						(effects
							(font
								(size 1.27 1.27)
							)
						)
					)
					(number "A4"
						(effects
							(font
								(size 1.27 1.27)
							)
						)
					)
				)
				(pin passive line
					(at 0 0 180)
					(length 3.81)
					(hide yes)
					(name "VBUS"
						(effects
							(font
								(size 1.27 1.27)
							)
						)
					)
					(number "A9"
						(effects
							(font
								(size 1.27 1.27)
							)
						)
					)
				)
				(pin passive line
					(at 0 0 180)
					(length 3.81)
					(hide yes)
					(name "VBUS"
						(effects
							(font
								(size 1.27 1.27)
							)
						)
					)
					(number "B4"
						(effects
							(font
								(size 1.27 1.27)
							)
						)
					)
				)
				(pin passive line
					(at 0 0 180)
					(length 3.81)
					(hide yes)
					(name "VBUS"
						(effects
							(font
								(size 1.27 1.27)
							)
						)
					)
					(number "B9"
						(effects
							(font
								(size 1.27 1.27)
							)
						)
					)
				)
				(pin bidirectional line
					(at 0 -5.08 180)
					(length 3.81)
					(name "CC_{1}"
						(effects
							(font
								(size 1.27 1.27)
							)
						)
					)
					(number "A5"
						(effects
							(font
								(size 1.27 1.27)
							)
						)
					)
				)
				(pin bidirectional line
					(at 0 -7.62 180)
					(length 3.81)
					(name "CC_{2}"
						(effects
							(font
								(size 1.27 1.27)
							)
						)
					)
					(number "B5"
						(effects
							(font
								(size 1.27 1.27)
							)
						)
					)
				)
				(pin bidirectional line
					(at 0 -12.7 180)
					(length 3.81)
					(name "D_{A}+"
						(effects
							(font
								(size 1.27 1.27)
							)
						)
					)
					(number "A6"
						(effects
							(font
								(size 1.27 1.27)
							)
						)
					)
				)
				(pin bidirectional line
					(at 0 -15.24 180)
					(length 3.81)
					(name "D_{A}-"
						(effects
							(font
								(size 1.27 1.27)
							)
						)
					)
					(number "A7"
						(effects
							(font
								(size 1.27 1.27)
							)
						)
					)
				)
				(pin bidirectional line
					(at 0 -17.78 180)
					(length 3.81)
					(name "D_{B}+"
						(effects
							(font
								(size 1.27 1.27)
							)
						)
					)
					(number "B6"
						(effects
							(font
								(size 1.27 1.27)
							)
						)
					)
				)
				(pin bidirectional line
					(at 0 -20.32 180)
					(length 3.81)
					(name "D_{B}-"
						(effects
							(font
								(size 1.27 1.27)
							)
						)
					)
					(number "B7"
						(effects
							(font
								(size 1.27 1.27)
							)
						)
					)
				)
				(pin bidirectional line
					(at 0 -25.4 180)
					(length 3.81)
					(name "RX_{1}+"
						(effects
							(font
								(size 1.27 1.27)
							)
						)
					)
					(number "B11"
						(effects
							(font
								(size 1.27 1.27)
							)
						)
					)
				)
				(pin bidirectional line
					(at 0 -27.94 180)
					(length 3.81)
					(name "RX_{1}-"
						(effects
							(font
								(size 1.27 1.27)
							)
						)
					)
					(number "B10"
						(effects
							(font
								(size 1.27 1.27)
							)
						)
					)
				)
				(pin bidirectional line
					(at 0 -33.02 180)
					(length 3.81)
					(name "TX_{1}+"
						(effects
							(font
								(size 1.27 1.27)
							)
						)
					)
					(number "A2"
						(effects
							(font
								(size 1.27 1.27)
							)
						)
					)
				)
				(pin bidirectional line
					(at 0 -35.56 180)
					(length 3.81)
					(name "TX_{1}-"
						(effects
							(font
								(size 1.27 1.27)
							)
						)
					)
					(number "A3"
						(effects
							(font
								(size 1.27 1.27)
							)
						)
					)
				)
				(pin bidirectional line
					(at 0 -40.64 180)
					(length 3.81)
					(name "RX_{2}+"
						(effects
							(font
								(size 1.27 1.27)
							)
						)
					)
					(number "A11"
						(effects
							(font
								(size 1.27 1.27)
							)
						)
					)
				)
				(pin bidirectional line
					(at 0 -43.18 180)
					(length 3.81)
					(name "RX_{2}-"
						(effects
							(font
								(size 1.27 1.27)
							)
						)
					)
					(number "A10"
						(effects
							(font
								(size 1.27 1.27)
							)
						)
					)
				)
				(pin bidirectional line
					(at 0 -48.26 180)
					(length 3.81)
					(name "TX_{2}+"
						(effects
							(font
								(size 1.27 1.27)
							)
						)
					)
					(number "B2"
						(effects
							(font
								(size 1.27 1.27)
							)
						)
					)
				)
				(pin bidirectional line
					(at 0 -50.8 180)
					(length 3.81)
					(name "TX_{2}-"
						(effects
							(font
								(size 1.27 1.27)
							)
						)
					)
					(number "B3"
						(effects
							(font
								(size 1.27 1.27)
							)
						)
					)
				)
				(pin bidirectional line
					(at 0 -55.88 180)
					(length 3.81)
					(name "SBU_{1}"
						(effects
							(font
								(size 1.27 1.27)
							)
						)
					)
					(number "A8"
						(effects
							(font
								(size 1.27 1.27)
							)
						)
					)
				)
				(pin bidirectional line
					(at 0 -58.42 180)
					(length 3.81)
					(name "SBU_{2}"
						(effects
							(font
								(size 1.27 1.27)
							)
						)
					)
					(number "B8"
						(effects
							(font
								(size 1.27 1.27)
							)
						)
					)
				)
				(pin power_in line
					(at 0 -63.5 180)
					(length 3.81)
					(name "GND"
						(effects
							(font
								(size 1.27 1.27)
							)
						)
					)
					(number "A1"
						(effects
							(font
								(size 1.27 1.27)
							)
						)
					)
				)
				(pin passive line
					(at 0 -63.5 180)
					(length 3.81)
					(hide yes)
					(name "GND"
						(effects
							(font
								(size 1.27 1.27)
							)
						)
					)
					(number "A12"
						(effects
							(font
								(size 1.27 1.27)
							)
						)
					)
				)
				(pin passive line
					(at 0 -63.5 180)
					(length 3.81)
					(hide yes)
					(name "GND"
						(effects
							(font
								(size 1.27 1.27)
							)
						)
					)
					(number "B1"
						(effects
							(font
								(size 1.27 1.27)
							)
						)
					)
				)
				(pin passive line
					(at 0 -63.5 180)
					(length 3.81)
					(hide yes)
					(name "GND"
						(effects
							(font
								(size 1.27 1.27)
							)
						)
					)
					(number "B12"
						(effects
							(font
								(size 1.27 1.27)
							)
						)
					)
				)
				(pin passive line
					(at 0 -66.04 180)
					(length 3.81)
					(name "SH"
						(effects
							(font
								(size 1.27 1.27)
							)
						)
					)
					(number "SH"
						(effects
							(font
								(size 1.27 1.27)
							)
						)
					)
				)
			)
		)
	(symbol "antmicroWire2BoardConnectors:Bel-Fuse_SFP+_2x20_SS-79100-010"
			(exclude_from_sim no)
			(in_bom yes)
			(on_board yes)
			(property "Reference" "J"
				(at 41.91 -2.54 0)
				(effects
					(font
						(size 1.27 1.27)
						(thickness 0.15)
					)
					(justify left bottom)
				)
			)
			(property "Value" "Bel-Fuse_SFP+_2x20_SS-79100-010"
				(at 41.91 -10.16 0)
				(effects
					(font
						(size 1.27 1.27)
						(thickness 0.15)
					)
					(justify left bottom)
					(hide yes)
				)
			)
			(property "Footprint" "antmicro-footprints:Conn_Bel-Fuse_SFP+_2x20_SS-79100-010"
				(at 41.91 -12.7 0)
				(effects
					(font
						(size 1.27 1.27)
						(thickness 0.15)
					)
					(justify left bottom)
					(hide yes)
				)
			)
			(property "Datasheet" "https://www.belfuse.com/resources/datasheets/stewartconnector/ds-STW-SFP-cages.pdf"
				(at 41.91 -15.24 0)
				(effects
					(font
						(size 1.27 1.27)
						(thickness 0.15)
					)
					(justify left bottom)
					(hide yes)
				)
			)
			(property "Description" "40 Position SFP+ Receptacle with Cage, Ganged (2x1) Connector Press-Fit Through Hole, Right Angle"
				(at 0 0 0)
				(effects
					(font
						(size 1.27 1.27)
					)
					(hide yes)
				)
			)
			(property "MPN" "SS-79100-010"
				(at 41.91 -5.08 0)
				(effects
					(font
						(size 1.27 1.27)
						(thickness 0.15)
					)
					(justify left bottom)
				)
			)
			(property "Manufacturer" "Bel Fuse"
				(at 41.91 -7.62 0)
				(effects
					(font
						(size 1.27 1.27)
						(thickness 0.15)
					)
					(justify left bottom)
					(hide yes)
				)
			)
			(property "Author" "Antmicro"
				(at 41.91 -17.78 0)
				(effects
					(font
						(size 1.27 1.27)
						(thickness 0.15)
					)
					(justify left bottom)
					(hide yes)
				)
			)
			(property "License" "Apache-2.0"
				(at 41.91 -20.32 0)
				(effects
					(font
						(size 1.27 1.27)
						(thickness 0.15)
					)
					(justify left bottom)
					(hide yes)
				)
			)
			(property "ki_locked" ""
				(at 0 0 0)
				(effects
					(font
						(size 1.27 1.27)
					)
				)
			)
			(property "ki_keywords" "THT, CONNECTOR"
				(at 0 0 0)
				(effects
					(font
						(size 1.27 1.27)
					)
					(hide yes)
				)
			)
			(symbol "Bel-Fuse_SFP+_2x20_SS-79100-010_1_1"
				(rectangle
					(start 3.81 2.54)
					(end 24.13 -45.72)
					(stroke
						(width 0.254)
						(type default)
					)
					(fill
						(type background)
					)
				)
				(text "SFP+\n"
					(at 17.78 0 0)
					(effects
						(font
							(size 1.27 1.27)
							(thickness 0.15)
						)
						(justify left bottom)
					)
				)
				(pin power_in line
					(at 0 0 0)
					(length 3.81)
					(name "V_{CC}(R)"
						(effects
							(font
								(size 1.27 1.27)
							)
						)
					)
					(number "T15"
						(effects
							(font
								(size 1.27 1.27)
							)
						)
					)
				)
				(pin power_in line
					(at 0 -2.54 0)
					(length 3.81)
					(name "V_{CC}(T)"
						(effects
							(font
								(size 1.27 1.27)
							)
						)
					)
					(number "T16"
						(effects
							(font
								(size 1.27 1.27)
							)
						)
					)
				)
				(pin bidirectional line
					(at 0 -7.62 0)
					(length 3.81)
					(name "SDA"
						(effects
							(font
								(size 1.27 1.27)
							)
						)
					)
					(number "T4"
						(effects
							(font
								(size 1.27 1.27)
							)
						)
					)
				)
				(pin bidirectional line
					(at 0 -10.16 0)
					(length 3.81)
					(name "SCL"
						(effects
							(font
								(size 1.27 1.27)
							)
						)
					)
					(number "T5"
						(effects
							(font
								(size 1.27 1.27)
							)
						)
					)
				)
				(pin passive line
					(at 0 -15.24 0)
					(length 3.81)
					(name "MOD_{ABS}"
						(effects
							(font
								(size 1.27 1.27)
							)
						)
					)
					(number "T6"
						(effects
							(font
								(size 1.27 1.27)
							)
						)
					)
				)
				(pin open_collector line
					(at 0 -17.78 0)
					(length 3.81)
					(name "RX_{LOS}"
						(effects
							(font
								(size 1.27 1.27)
							)
						)
					)
					(number "T8"
						(effects
							(font
								(size 1.27 1.27)
							)
						)
					)
				)
				(pin open_collector line
					(at 0 -20.32 0)
					(length 3.81)
					(name "TX_{FAULT}"
						(effects
							(font
								(size 1.27 1.27)
							)
						)
					)
					(number "T2"
						(effects
							(font
								(size 1.27 1.27)
							)
						)
					)
				)
				(pin input line
					(at 0 -22.86 0)
					(length 3.81)
					(name "TX_{DISABLE}"
						(effects
							(font
								(size 1.27 1.27)
							)
						)
					)
					(number "T3"
						(effects
							(font
								(size 1.27 1.27)
							)
						)
					)
				)
				(pin input line
					(at 0 -25.4 0)
					(length 3.81)
					(name "RS1"
						(effects
							(font
								(size 1.27 1.27)
							)
						)
					)
					(number "T9"
						(effects
							(font
								(size 1.27 1.27)
							)
						)
					)
				)
				(pin input line
					(at 0 -27.94 0)
					(length 3.81)
					(name "RS0"
						(effects
							(font
								(size 1.27 1.27)
							)
						)
					)
					(number "T7"
						(effects
							(font
								(size 1.27 1.27)
							)
						)
					)
				)
				(pin input line
					(at 0 -33.02 0)
					(length 3.81)
					(name "TD+"
						(effects
							(font
								(size 1.27 1.27)
							)
						)
					)
					(number "T18"
						(effects
							(font
								(size 1.27 1.27)
							)
						)
					)
				)
				(pin input line
					(at 0 -35.56 0)
					(length 3.81)
					(name "TD-"
						(effects
							(font
								(size 1.27 1.27)
							)
						)
					)
					(number "T19"
						(effects
							(font
								(size 1.27 1.27)
							)
						)
					)
				)
				(pin output line
					(at 0 -40.64 0)
					(length 3.81)
					(name "RD+"
						(effects
							(font
								(size 1.27 1.27)
							)
						)
					)
					(number "T13"
						(effects
							(font
								(size 1.27 1.27)
							)
						)
					)
				)
				(pin output line
					(at 0 -43.18 0)
					(length 3.81)
					(name "RD-"
						(effects
							(font
								(size 1.27 1.27)
							)
						)
					)
					(number "T12"
						(effects
							(font
								(size 1.27 1.27)
							)
						)
					)
				)
				(pin passive line
					(at 27.94 -38.1 180)
					(length 3.81)
					(name "SH"
						(effects
							(font
								(size 1.27 1.27)
							)
						)
					)
					(number "SH"
						(effects
							(font
								(size 1.27 1.27)
							)
						)
					)
				)
				(pin passive line
					(at 27.94 -40.64 180)
					(length 3.81)
					(name "V_{EE}(T)"
						(effects
							(font
								(size 1.27 1.27)
							)
						)
					)
					(number "T1"
						(effects
							(font
								(size 1.27 1.27)
							)
						)
					)
				)
				(pin passive line
					(at 27.94 -40.64 180)
					(length 3.81)
					(hide yes)
					(name "V_{EE}(T)"
						(effects
							(font
								(size 1.27 1.27)
							)
						)
					)
					(number "T17"
						(effects
							(font
								(size 1.27 1.27)
							)
						)
					)
				)
				(pin passive line
					(at 27.94 -40.64 180)
					(length 3.81)
					(hide yes)
					(name "V_{EE}(T)"
						(effects
							(font
								(size 1.27 1.27)
							)
						)
					)
					(number "T20"
						(effects
							(font
								(size 1.27 1.27)
							)
						)
					)
				)
				(pin passive line
					(at 27.94 -43.18 180)
					(length 3.81)
					(name "V_{EE}(R)"
						(effects
							(font
								(size 1.27 1.27)
							)
						)
					)
					(number "T10"
						(effects
							(font
								(size 1.27 1.27)
							)
						)
					)
				)
				(pin passive line
					(at 27.94 -43.18 180)
					(length 3.81)
					(hide yes)
					(name "V_{EE}(R)"
						(effects
							(font
								(size 1.27 1.27)
							)
						)
					)
					(number "T11"
						(effects
							(font
								(size 1.27 1.27)
							)
						)
					)
				)
				(pin passive line
					(at 27.94 -43.18 180)
					(length 3.81)
					(hide yes)
					(name "V_{EE}(R)"
						(effects
							(font
								(size 1.27 1.27)
							)
						)
					)
					(number "T14"
						(effects
							(font
								(size 1.27 1.27)
							)
						)
					)
				)
			)
			(symbol "Bel-Fuse_SFP+_2x20_SS-79100-010_2_1"
				(rectangle
					(start 3.81 2.54)
					(end 24.13 -45.72)
					(stroke
						(width 0.254)
						(type default)
					)
					(fill
						(type background)
					)
				)
				(text "SFP+\n"
					(at 17.78 0 0)
					(effects
						(font
							(size 1.27 1.27)
							(thickness 0.15)
						)
						(justify left bottom)
					)
				)
				(pin power_in line
					(at 0 0 0)
					(length 3.81)
					(name "V_{CC}(R)"
						(effects
							(font
								(size 1.27 1.27)
							)
						)
					)
					(number "L15"
						(effects
							(font
								(size 1.27 1.27)
							)
						)
					)
				)
				(pin power_in line
					(at 0 -2.54 0)
					(length 3.81)
					(name "V_{CC}(T)"
						(effects
							(font
								(size 1.27 1.27)
							)
						)
					)
					(number "L16"
						(effects
							(font
								(size 1.27 1.27)
							)
						)
					)
				)
				(pin bidirectional line
					(at 0 -7.62 0)
					(length 3.81)
					(name "SDA"
						(effects
							(font
								(size 1.27 1.27)
							)
						)
					)
					(number "L4"
						(effects
							(font
								(size 1.27 1.27)
							)
						)
					)
				)
				(pin bidirectional line
					(at 0 -10.16 0)
					(length 3.81)
					(name "SCL"
						(effects
							(font
								(size 1.27 1.27)
							)
						)
					)
					(number "L5"
						(effects
							(font
								(size 1.27 1.27)
							)
						)
					)
				)
				(pin passive line
					(at 0 -15.24 0)
					(length 3.81)
					(name "MOD_{ABS}"
						(effects
							(font
								(size 1.27 1.27)
							)
						)
					)
					(number "L6"
						(effects
							(font
								(size 1.27 1.27)
							)
						)
					)
				)
				(pin open_collector line
					(at 0 -17.78 0)
					(length 3.81)
					(name "RX_{LOS}"
						(effects
							(font
								(size 1.27 1.27)
							)
						)
					)
					(number "L8"
						(effects
							(font
								(size 1.27 1.27)
							)
						)
					)
				)
				(pin open_collector line
					(at 0 -20.32 0)
					(length 3.81)
					(name "TX_{FAULT}"
						(effects
							(font
								(size 1.27 1.27)
							)
						)
					)
					(number "L2"
						(effects
							(font
								(size 1.27 1.27)
							)
						)
					)
				)
				(pin input line
					(at 0 -22.86 0)
					(length 3.81)
					(name "TX_{DISABLE}"
						(effects
							(font
								(size 1.27 1.27)
							)
						)
					)
					(number "L3"
						(effects
							(font
								(size 1.27 1.27)
							)
						)
					)
				)
				(pin input line
					(at 0 -25.4 0)
					(length 3.81)
					(name "RS1"
						(effects
							(font
								(size 1.27 1.27)
							)
						)
					)
					(number "L9"
						(effects
							(font
								(size 1.27 1.27)
							)
						)
					)
				)
				(pin input line
					(at 0 -27.94 0)
					(length 3.81)
					(name "RS0"
						(effects
							(font
								(size 1.27 1.27)
							)
						)
					)
					(number "L7"
						(effects
							(font
								(size 1.27 1.27)
							)
						)
					)
				)
				(pin input line
					(at 0 -33.02 0)
					(length 3.81)
					(name "TD+"
						(effects
							(font
								(size 1.27 1.27)
							)
						)
					)
					(number "L18"
						(effects
							(font
								(size 1.27 1.27)
							)
						)
					)
				)
				(pin input line
					(at 0 -35.56 0)
					(length 3.81)
					(name "TD-"
						(effects
							(font
								(size 1.27 1.27)
							)
						)
					)
					(number "L19"
						(effects
							(font
								(size 1.27 1.27)
							)
						)
					)
				)
				(pin output line
					(at 0 -40.64 0)
					(length 3.81)
					(name "RD+"
						(effects
							(font
								(size 1.27 1.27)
							)
						)
					)
					(number "L13"
						(effects
							(font
								(size 1.27 1.27)
							)
						)
					)
				)
				(pin output line
					(at 0 -43.18 0)
					(length 3.81)
					(name "RD-"
						(effects
							(font
								(size 1.27 1.27)
							)
						)
					)
					(number "L12"
						(effects
							(font
								(size 1.27 1.27)
							)
						)
					)
				)
				(pin passive line
					(at 27.94 -40.64 180)
					(length 3.81)
					(name "V_{EE}(R)"
						(effects
							(font
								(size 1.27 1.27)
							)
						)
					)
					(number "L10"
						(effects
							(font
								(size 1.27 1.27)
							)
						)
					)
				)
				(pin passive line
					(at 27.94 -40.64 180)
					(length 3.81)
					(hide yes)
					(name "V_{EE}(R)"
						(effects
							(font
								(size 1.27 1.27)
							)
						)
					)
					(number "L11"
						(effects
							(font
								(size 1.27 1.27)
							)
						)
					)
				)
				(pin passive line
					(at 27.94 -40.64 180)
					(length 3.81)
					(hide yes)
					(name "V_{EE}(R)"
						(effects
							(font
								(size 1.27 1.27)
							)
						)
					)
					(number "L14"
						(effects
							(font
								(size 1.27 1.27)
							)
						)
					)
				)
				(pin passive line
					(at 27.94 -43.18 180)
					(length 3.81)
					(name "V_{EE}(T)"
						(effects
							(font
								(size 1.27 1.27)
							)
						)
					)
					(number "L1"
						(effects
							(font
								(size 1.27 1.27)
							)
						)
					)
				)
				(pin passive line
					(at 27.94 -43.18 180)
					(length 3.81)
					(hide yes)
					(name "V_{EE}(T)"
						(effects
							(font
								(size 1.27 1.27)
							)
						)
					)
					(number "L17"
						(effects
							(font
								(size 1.27 1.27)
							)
						)
					)
				)
				(pin passive line
					(at 27.94 -43.18 180)
					(length 3.81)
					(hide yes)
					(name "V_{EE}(T)"
						(effects
							(font
								(size 1.27 1.27)
							)
						)
					)
					(number "L20"
						(effects
							(font
								(size 1.27 1.27)
							)
						)
					)
				)
			)
		)
	(symbol "antmicroWire2BoardConnectors:Molex_KK_1x4_0470531000"
			(exclude_from_sim no)
			(in_bom yes)
			(on_board yes)
			(property "Reference" "J"
				(at 20.32 -5.08 0)
				(effects
					(font
						(size 1.27 1.27)
						(thickness 0.15)
					)
					(justify left bottom)
				)
			)
			(property "Value" "Molex_KK_1x4_0470531000"
				(at 20.32 -10.16 0)
				(effects
					(font
						(size 1.27 1.27)
						(thickness 0.15)
					)
					(justify left bottom)
					(hide yes)
				)
			)
			(property "Footprint" "antmicro-footprints:Conn_Molex_KK_1x4_0470531000"
				(at 20.32 -12.7 0)
				(effects
					(font
						(size 1.27 1.27)
						(thickness 0.15)
					)
					(justify left bottom)
					(hide yes)
				)
			)
			(property "Datasheet" "https://tools.molex.com/pdm_docs/sd/470531000_sd.pdf"
				(at 20.32 -15.24 0)
				(effects
					(font
						(size 1.27 1.27)
						(thickness 0.15)
					)
					(justify left bottom)
					(hide yes)
				)
			)
			(property "Description" "Connector Header, THT,  4x1"
				(at 0 0 0)
				(effects
					(font
						(size 1.27 1.27)
					)
					(hide yes)
				)
			)
			(property "MPN" "0470531000"
				(at 20.32 -7.62 0)
				(effects
					(font
						(size 1.27 1.27)
						(thickness 0.15)
					)
					(justify left bottom)
				)
			)
			(property "Manufacturer" "Molex"
				(at 20.32 -17.78 0)
				(effects
					(font
						(size 1.27 1.27)
						(thickness 0.15)
					)
					(justify left bottom)
					(hide yes)
				)
			)
			(property "Author" "Antmicro"
				(at 20.32 -20.32 0)
				(effects
					(font
						(size 1.27 1.27)
						(thickness 0.15)
					)
					(justify left bottom)
					(hide yes)
				)
			)
			(property "License" "Apache-2.0"
				(at 20.32 -22.86 0)
				(effects
					(font
						(size 1.27 1.27)
						(thickness 0.15)
					)
					(justify left bottom)
					(hide yes)
				)
			)
			(property "ki_keywords" "CONNECTOR, HEADER, WIRE-BOARD, THT"
				(at 0 0 0)
				(effects
					(font
						(size 1.27 1.27)
					)
					(hide yes)
				)
			)
			(symbol "Molex_KK_1x4_0470531000_1_1"
				(rectangle
					(start 2.54 0.127)
					(end 3.81 -0.127)
					(stroke
						(width 0.254)
						(type default)
					)
					(fill
						(type background)
					)
				)
				(rectangle
					(start 2.54 -2.413)
					(end 3.81 -2.667)
					(stroke
						(width 0.254)
						(type default)
					)
					(fill
						(type background)
					)
				)
				(rectangle
					(start 2.54 -4.953)
					(end 3.81 -5.207)
					(stroke
						(width 0.254)
						(type default)
					)
					(fill
						(type background)
					)
				)
				(rectangle
					(start 2.54 -7.493)
					(end 3.81 -7.747)
					(stroke
						(width 0.254)
						(type default)
					)
					(fill
						(type background)
					)
				)
				(rectangle
					(start 5.08 -8.89)
					(end 2.54 1.27)
					(stroke
						(width 0.254)
						(type default)
					)
					(fill
						(type background)
					)
				)
				(pin passive line
					(at 0 0 0)
					(length 2.54)
					(name "~"
						(effects
							(font
								(size 1.27 1.27)
							)
						)
					)
					(number "1"
						(effects
							(font
								(size 1.27 1.27)
							)
						)
					)
				)
				(pin passive line
					(at 0 -2.54 0)
					(length 2.54)
					(name "~"
						(effects
							(font
								(size 1.27 1.27)
							)
						)
					)
					(number "2"
						(effects
							(font
								(size 1.27 1.27)
							)
						)
					)
				)
				(pin passive line
					(at 0 -5.08 0)
					(length 2.54)
					(name "~"
						(effects
							(font
								(size 1.27 1.27)
							)
						)
					)
					(number "3"
						(effects
							(font
								(size 1.27 1.27)
							)
						)
					)
				)
				(pin passive line
					(at 0 -7.62 0)
					(length 2.54)
					(name "~"
						(effects
							(font
								(size 1.27 1.27)
							)
						)
					)
					(number "4"
						(effects
							(font
								(size 1.27 1.27)
							)
						)
					)
				)
			)
		)
	(symbol "antmicroWire2BoardConnectors:Molex_Nano-Fit_1x2_105309-1202"
			(exclude_from_sim no)
			(in_bom yes)
			(on_board yes)
			(property "Reference" "J"
				(at 20.32 -2.54 0)
				(effects
					(font
						(size 1.27 1.27)
						(thickness 0.15)
					)
					(justify left bottom)
				)
			)
			(property "Value" "Molex_Nano-Fit_1x2_105309-1202"
				(at 20.32 -7.62 0)
				(effects
					(font
						(size 1.27 1.27)
						(thickness 0.15)
					)
					(justify left bottom)
					(hide yes)
				)
			)
			(property "Footprint" "antmicro-footprints:Conn_Molex_Nano-Fit_1x2_105309-1202"
				(at 20.32 -10.16 0)
				(effects
					(font
						(size 1.27 1.27)
						(thickness 0.15)
					)
					(justify left bottom)
					(hide yes)
				)
			)
			(property "Datasheet" "https://tools.molex.com/pdm_docs/sd/1053091202_sd.pdf"
				(at 20.32 -12.7 0)
				(effects
					(font
						(size 1.27 1.27)
						(thickness 0.15)
					)
					(justify left bottom)
					(hide yes)
				)
			)
			(property "Description" "Pin Header, Power, 2.5 mm, 1 Rows, 2 Contacts, Through Hole Straight, Nano-Fit"
				(at 20.32 -22.86 0)
				(effects
					(font
						(size 1.27 1.27)
					)
					(justify left bottom)
					(hide yes)
				)
			)
			(property "Manufacturer" "Molex"
				(at 20.32 -15.24 0)
				(effects
					(font
						(size 1.27 1.27)
						(thickness 0.15)
					)
					(justify left bottom)
					(hide yes)
				)
			)
			(property "MPN" "105309-1202"
				(at 20.32 -5.08 0)
				(effects
					(font
						(size 1.27 1.27)
						(thickness 0.15)
					)
					(justify left bottom)
				)
			)
			(property "Author" "Antmicro"
				(at 20.32 -17.78 0)
				(effects
					(font
						(size 1.27 1.27)
						(thickness 0.15)
					)
					(justify left bottom)
					(hide yes)
				)
			)
			(property "License" "Apache-2.0"
				(at 20.32 -20.32 0)
				(effects
					(font
						(size 1.27 1.27)
						(thickness 0.15)
					)
					(justify left bottom)
					(hide yes)
				)
			)
			(property "ki_keywords" "CONNECTOR, HEADER, THT, WIRE-BOARD"
				(at 0 0 0)
				(effects
					(font
						(size 1.27 1.27)
					)
					(hide yes)
				)
			)
			(symbol "Molex_Nano-Fit_1x2_105309-1202_1_1"
				(rectangle
					(start 2.54 2.54)
					(end 6.35 -5.08)
					(stroke
						(width 0.254)
						(type default)
					)
					(fill
						(type background)
					)
				)
				(rectangle
					(start 3.81 -0.635)
					(end 5.08 0.635)
					(stroke
						(width 0.254)
						(type default)
					)
					(fill
						(type background)
					)
				)
				(rectangle
					(start 3.81 -3.175)
					(end 5.08 -1.905)
					(stroke
						(width 0.254)
						(type default)
					)
					(fill
						(type background)
					)
				)
				(pin input line
					(at 0 0 0)
					(length 2.54)
					(name "~"
						(effects
							(font
								(size 1.27 1.27)
							)
						)
					)
					(number "1"
						(effects
							(font
								(size 1.27 1.27)
							)
						)
					)
				)
				(pin input line
					(at 0 -2.54 0)
					(length 2.54)
					(name "~"
						(effects
							(font
								(size 1.27 1.27)
							)
						)
					)
					(number "2"
						(effects
							(font
								(size 1.27 1.27)
							)
						)
					)
				)
			)
		)
	(symbol "antmicropower:+12V"
			(power)
			(pin_names
				(offset 0)
			)
			(exclude_from_sim no)
			(in_bom yes)
			(on_board yes)
			(property "Reference" "#PWR"
				(at 0 -3.81 0)
				(effects
					(font
						(size 1.27 1.27)
					)
					(hide yes)
				)
			)
			(property "Value" "+12V"
				(at 0 3.556 0)
				(effects
					(font
						(size 1.27 1.27)
					)
				)
			)
			(property "Footprint" ""
				(at 0 0 0)
				(effects
					(font
						(size 1.27 1.27)
					)
					(hide yes)
				)
			)
			(property "Datasheet" ""
				(at 0 0 0)
				(effects
					(font
						(size 1.27 1.27)
					)
					(hide yes)
				)
			)
			(property "Description" ""
				(at 0 0 0)
				(effects
					(font
						(size 1.27 1.27)
					)
					(hide yes)
				)
			)
			(symbol "+12V_0_1"
				(polyline
					(pts
						(xy -0.762 1.27) (xy 0 2.54)
					)
					(stroke
						(width 0)
						(type default)
					)
					(fill
						(type none)
					)
				)
				(polyline
					(pts
						(xy 0 2.54) (xy 0.762 1.27)
					)
					(stroke
						(width 0)
						(type default)
					)
					(fill
						(type none)
					)
				)
				(polyline
					(pts
						(xy 0 0) (xy 0 2.54)
					)
					(stroke
						(width 0)
						(type default)
					)
					(fill
						(type none)
					)
				)
			)
			(symbol "+12V_1_1"
				(pin power_in line
					(at 0 0 90)
					(length 0)
					(hide yes)
					(name "+12V"
						(effects
							(font
								(size 1.27 1.27)
							)
						)
					)
					(number "1"
						(effects
							(font
								(size 1.27 1.27)
							)
						)
					)
				)
			)
		)
	(symbol "antmicropower:+12V_AON"
			(power)
			(pin_names
				(offset 0)
			)
			(exclude_from_sim no)
			(in_bom yes)
			(on_board yes)
			(property "Reference" "#PWR"
				(at 0 -3.81 0)
				(effects
					(font
						(size 1.27 1.27)
					)
					(hide yes)
				)
			)
			(property "Value" "+12V_AON"
				(at 0 3.556 0)
				(effects
					(font
						(size 1.27 1.27)
					)
				)
			)
			(property "Footprint" ""
				(at 0 0 0)
				(effects
					(font
						(size 1.27 1.27)
					)
					(hide yes)
				)
			)
			(property "Datasheet" ""
				(at 0 0 0)
				(effects
					(font
						(size 1.27 1.27)
					)
					(hide yes)
				)
			)
			(property "Description" ""
				(at 0 0 0)
				(effects
					(font
						(size 1.27 1.27)
					)
					(hide yes)
				)
			)
			(symbol "+12V_AON_0_1"
				(polyline
					(pts
						(xy -0.762 1.27) (xy 0 2.54)
					)
					(stroke
						(width 0)
						(type default)
					)
					(fill
						(type none)
					)
				)
				(polyline
					(pts
						(xy 0 2.54) (xy 0.762 1.27)
					)
					(stroke
						(width 0)
						(type default)
					)
					(fill
						(type none)
					)
				)
				(polyline
					(pts
						(xy 0 0) (xy 0 2.54)
					)
					(stroke
						(width 0)
						(type default)
					)
					(fill
						(type none)
					)
				)
			)
			(symbol "+12V_AON_1_1"
				(pin power_in line
					(at 0 0 90)
					(length 0)
					(hide yes)
					(name "+12V_AON"
						(effects
							(font
								(size 1.27 1.27)
							)
						)
					)
					(number "1"
						(effects
							(font
								(size 1.27 1.27)
							)
						)
					)
				)
			)
		)
	(symbol "antmicropower:+1V0"
			(power)
			(pin_names
				(offset 0)
			)
			(exclude_from_sim no)
			(in_bom yes)
			(on_board yes)
			(property "Reference" "#PWR"
				(at 0 -3.81 0)
				(effects
					(font
						(size 1.27 1.27)
					)
					(hide yes)
				)
			)
			(property "Value" "+1V0"
				(at 0 3.556 0)
				(effects
					(font
						(size 1.27 1.27)
					)
				)
			)
			(property "Footprint" ""
				(at 0 0 0)
				(effects
					(font
						(size 1.27 1.27)
					)
					(hide yes)
				)
			)
			(property "Datasheet" ""
				(at 0 0 0)
				(effects
					(font
						(size 1.27 1.27)
					)
					(hide yes)
				)
			)
			(property "Description" ""
				(at 0 0 0)
				(effects
					(font
						(size 1.27 1.27)
					)
					(hide yes)
				)
			)
			(symbol "+1V0_0_1"
				(polyline
					(pts
						(xy -0.762 1.27) (xy 0 2.54)
					)
					(stroke
						(width 0)
						(type default)
					)
					(fill
						(type none)
					)
				)
				(polyline
					(pts
						(xy 0 2.54) (xy 0.762 1.27)
					)
					(stroke
						(width 0)
						(type default)
					)
					(fill
						(type none)
					)
				)
				(polyline
					(pts
						(xy 0 0) (xy 0 2.54)
					)
					(stroke
						(width 0)
						(type default)
					)
					(fill
						(type none)
					)
				)
			)
			(symbol "+1V0_1_1"
				(pin power_in line
					(at 0 0 90)
					(length 0)
					(hide yes)
					(name "+1V0"
						(effects
							(font
								(size 1.27 1.27)
							)
						)
					)
					(number "1"
						(effects
							(font
								(size 1.27 1.27)
							)
						)
					)
				)
			)
		)
	(symbol "antmicropower:+1V8"
			(power)
			(pin_numbers
				(hide yes)
			)
			(pin_names
				(hide yes)
			)
			(exclude_from_sim no)
			(in_bom yes)
			(on_board yes)
			(property "Reference" "#PWR"
				(at 15.24 -2.54 0)
				(effects
					(font
						(size 1.27 1.27)
						(thickness 0.15)
					)
					(justify left bottom)
					(hide yes)
				)
			)
			(property "Value" "+1V8"
				(at -3.175 2.54 0)
				(effects
					(font
						(size 1.27 1.27)
						(thickness 0.15)
					)
					(justify left bottom)
				)
			)
			(property "Footprint" ""
				(at 15.24 -7.62 0)
				(effects
					(font
						(size 1.27 1.27)
						(thickness 0.15)
					)
					(justify left bottom)
					(hide yes)
				)
			)
			(property "Datasheet" ""
				(at 15.24 -10.16 0)
				(effects
					(font
						(size 1.27 1.27)
						(thickness 0.15)
					)
					(justify left bottom)
					(hide yes)
				)
			)
			(property "Description" ""
				(at 0 0 0)
				(effects
					(font
						(size 1.27 1.27)
					)
					(hide yes)
				)
			)
			(property "Author" "Antmicro"
				(at 15.24 -5.08 0)
				(effects
					(font
						(size 1.27 1.27)
						(thickness 0.15)
					)
					(justify left bottom)
					(hide yes)
				)
			)
			(property "License" "Apache-2.0"
				(at 15.24 -7.62 0)
				(effects
					(font
						(size 1.27 1.27)
						(thickness 0.15)
					)
					(justify left bottom)
					(hide yes)
				)
			)
			(symbol "+1V8_1_1"
				(polyline
					(pts
						(xy -0.762 1.27) (xy 0 2.54)
					)
					(stroke
						(width 0)
						(type default)
					)
					(fill
						(type background)
					)
				)
				(polyline
					(pts
						(xy 0 2.54) (xy 0.762 1.27)
					)
					(stroke
						(width 0)
						(type default)
					)
					(fill
						(type background)
					)
				)
				(polyline
					(pts
						(xy 0 0) (xy 0 2.54)
					)
					(stroke
						(width 0)
						(type default)
					)
					(fill
						(type background)
					)
				)
				(pin power_in line
					(at 0 0 90)
					(length 0)
					(hide yes)
					(name "+1V8"
						(effects
							(font
								(size 1.27 1.27)
							)
						)
					)
					(number "1"
						(effects
							(font
								(size 1.27 1.27)
							)
						)
					)
				)
			)
		)
	(symbol "antmicropower:+3V3"
			(power)
			(pin_numbers
				(hide yes)
			)
			(pin_names
				(hide yes)
			)
			(exclude_from_sim no)
			(in_bom yes)
			(on_board yes)
			(property "Reference" "#PWR"
				(at 15.24 0 0)
				(effects
					(font
						(size 1.27 1.27)
						(thickness 0.15)
					)
					(justify left bottom)
					(hide yes)
				)
			)
			(property "Value" "+3V3"
				(at -3.175 2.54 0)
				(effects
					(font
						(size 1.27 1.27)
						(thickness 0.15)
					)
					(justify left bottom)
				)
			)
			(property "Footprint" ""
				(at 15.24 -7.62 0)
				(effects
					(font
						(size 1.27 1.27)
						(thickness 0.15)
					)
					(justify left bottom)
					(hide yes)
				)
			)
			(property "Datasheet" ""
				(at 15.24 -10.16 0)
				(effects
					(font
						(size 1.27 1.27)
						(thickness 0.15)
					)
					(justify left bottom)
					(hide yes)
				)
			)
			(property "Description" ""
				(at 0 0 0)
				(effects
					(font
						(size 1.27 1.27)
					)
					(hide yes)
				)
			)
			(property "Author" "Antmicro"
				(at 15.24 -2.54 0)
				(effects
					(font
						(size 1.27 1.27)
						(thickness 0.15)
					)
					(justify left bottom)
					(hide yes)
				)
			)
			(property "License" "Apache-2.0"
				(at 15.24 -5.08 0)
				(effects
					(font
						(size 1.27 1.27)
						(thickness 0.15)
					)
					(justify left bottom)
					(hide yes)
				)
			)
			(symbol "+3V3_0_1"
				(polyline
					(pts
						(xy 0 2.54) (xy -0.762 1.27)
					)
					(stroke
						(width 0)
						(type default)
					)
					(fill
						(type none)
					)
				)
				(polyline
					(pts
						(xy 0 2.54) (xy 0.762 1.27)
					)
					(stroke
						(width 0)
						(type default)
					)
					(fill
						(type none)
					)
				)
				(polyline
					(pts
						(xy 0 0) (xy 0 2.54)
					)
					(stroke
						(width 0)
						(type default)
					)
					(fill
						(type none)
					)
				)
			)
			(symbol "+3V3_1_1"
				(pin power_in line
					(at 0 0 90)
					(length 0)
					(hide yes)
					(name "+3V3"
						(effects
							(font
								(size 1.27 1.27)
							)
						)
					)
					(number "1"
						(effects
							(font
								(size 1.27 1.27)
							)
						)
					)
				)
			)
		)
	(symbol "antmicropower:+3V3_AON"
			(power)
			(pin_names
				(offset 0)
			)
			(exclude_from_sim no)
			(in_bom yes)
			(on_board yes)
			(property "Reference" "#PWR"
				(at 0 -3.81 0)
				(effects
					(font
						(size 1.27 1.27)
					)
					(hide yes)
				)
			)
			(property "Value" "+3V3_AON"
				(at 0 3.556 0)
				(effects
					(font
						(size 1.27 1.27)
					)
				)
			)
			(property "Footprint" ""
				(at 0 0 0)
				(effects
					(font
						(size 1.27 1.27)
					)
					(hide yes)
				)
			)
			(property "Datasheet" ""
				(at 0 0 0)
				(effects
					(font
						(size 1.27 1.27)
					)
					(hide yes)
				)
			)
			(property "Description" ""
				(at 0 0 0)
				(effects
					(font
						(size 1.27 1.27)
					)
					(hide yes)
				)
			)
			(symbol "+3V3_AON_0_1"
				(polyline
					(pts
						(xy -0.762 1.27) (xy 0 2.54)
					)
					(stroke
						(width 0)
						(type default)
					)
					(fill
						(type none)
					)
				)
				(polyline
					(pts
						(xy 0 2.54) (xy 0.762 1.27)
					)
					(stroke
						(width 0)
						(type default)
					)
					(fill
						(type none)
					)
				)
				(polyline
					(pts
						(xy 0 0) (xy 0 2.54)
					)
					(stroke
						(width 0)
						(type default)
					)
					(fill
						(type none)
					)
				)
			)
			(symbol "+3V3_AON_1_1"
				(pin power_in line
					(at 0 0 90)
					(length 0)
					(hide yes)
					(name "+3V3_AON"
						(effects
							(font
								(size 1.27 1.27)
							)
						)
					)
					(number "1"
						(effects
							(font
								(size 1.27 1.27)
							)
						)
					)
				)
			)
		)
	(symbol "antmicropower:+5V"
			(power)
			(pin_numbers
				(hide yes)
			)
			(pin_names
				(hide yes)
			)
			(exclude_from_sim no)
			(in_bom yes)
			(on_board yes)
			(property "Reference" "#PWR"
				(at 15.24 -2.54 0)
				(effects
					(font
						(size 1.27 1.27)
						(thickness 0.15)
					)
					(justify left bottom)
					(hide yes)
				)
			)
			(property "Value" "+5V"
				(at 15.24 -5.08 0)
				(effects
					(font
						(size 1.27 1.27)
						(thickness 0.15)
					)
					(justify left bottom)
				)
			)
			(property "Footprint" ""
				(at 15.24 -7.62 0)
				(effects
					(font
						(size 1.27 1.27)
						(thickness 0.15)
					)
					(justify left bottom)
					(hide yes)
				)
			)
			(property "Datasheet" ""
				(at 15.24 -10.16 0)
				(effects
					(font
						(size 1.27 1.27)
						(thickness 0.15)
					)
					(justify left bottom)
					(hide yes)
				)
			)
			(property "Description" ""
				(at 0 0 0)
				(effects
					(font
						(size 1.27 1.27)
					)
					(hide yes)
				)
			)
			(property "Author" "Antmicro"
				(at 15.24 -7.62 0)
				(effects
					(font
						(size 1.27 1.27)
						(thickness 0.15)
					)
					(justify left bottom)
					(hide yes)
				)
			)
			(property "License" "Apache-2.0"
				(at 15.24 -10.16 0)
				(effects
					(font
						(size 1.27 1.27)
						(thickness 0.15)
					)
					(justify left bottom)
					(hide yes)
				)
			)
			(symbol "+5V_1_1"
				(polyline
					(pts
						(xy -0.762 1.27) (xy 0 2.54)
					)
					(stroke
						(width 0)
						(type default)
					)
					(fill
						(type background)
					)
				)
				(polyline
					(pts
						(xy 0 2.54) (xy 0.762 1.27)
					)
					(stroke
						(width 0)
						(type default)
					)
					(fill
						(type background)
					)
				)
				(polyline
					(pts
						(xy 0 0) (xy 0 2.54)
					)
					(stroke
						(width 0)
						(type default)
					)
					(fill
						(type background)
					)
				)
				(pin power_in line
					(at 0 0 90)
					(length 0)
					(name "+5V"
						(effects
							(font
								(size 1.27 1.27)
							)
						)
					)
					(number "1"
						(effects
							(font
								(size 1.27 1.27)
							)
						)
					)
				)
			)
		)
	(symbol "antmicropower:+5V_AON"
			(power)
			(pin_names
				(offset 0)
			)
			(exclude_from_sim no)
			(in_bom yes)
			(on_board yes)
			(property "Reference" "#PWR"
				(at 0 -3.81 0)
				(effects
					(font
						(size 1.27 1.27)
					)
					(hide yes)
				)
			)
			(property "Value" "+5V_AON"
				(at 0 3.556 0)
				(effects
					(font
						(size 1.27 1.27)
					)
				)
			)
			(property "Footprint" ""
				(at 0 0 0)
				(effects
					(font
						(size 1.27 1.27)
					)
					(hide yes)
				)
			)
			(property "Datasheet" ""
				(at 0 0 0)
				(effects
					(font
						(size 1.27 1.27)
					)
					(hide yes)
				)
			)
			(property "Description" ""
				(at 0 0 0)
				(effects
					(font
						(size 1.27 1.27)
					)
					(hide yes)
				)
			)
			(symbol "+5V_AON_0_1"
				(polyline
					(pts
						(xy -0.762 1.27) (xy 0 2.54)
					)
					(stroke
						(width 0)
						(type default)
					)
					(fill
						(type none)
					)
				)
				(polyline
					(pts
						(xy 0 2.54) (xy 0.762 1.27)
					)
					(stroke
						(width 0)
						(type default)
					)
					(fill
						(type none)
					)
				)
				(polyline
					(pts
						(xy 0 0) (xy 0 2.54)
					)
					(stroke
						(width 0)
						(type default)
					)
					(fill
						(type none)
					)
				)
			)
			(symbol "+5V_AON_1_1"
				(pin power_in line
					(at 0 0 90)
					(length 0)
					(hide yes)
					(name "+5V_AON"
						(effects
							(font
								(size 1.27 1.27)
							)
						)
					)
					(number "1"
						(effects
							(font
								(size 1.27 1.27)
							)
						)
					)
				)
			)
		)
	(symbol "antmicropower:GND"
			(power)
			(pin_numbers
				(hide yes)
			)
			(pin_names
				(hide yes)
			)
			(exclude_from_sim no)
			(in_bom yes)
			(on_board yes)
			(property "Reference" "#PWR"
				(at 8.89 -2.54 0)
				(effects
					(font
						(size 1.27 1.27)
						(thickness 0.15)
					)
					(justify left bottom)
					(hide yes)
				)
			)
			(property "Value" "GND"
				(at 8.89 -5.08 0)
				(effects
					(font
						(size 1.27 1.27)
						(thickness 0.15)
					)
					(justify left bottom)
				)
			)
			(property "Footprint" ""
				(at 8.89 -7.62 0)
				(effects
					(font
						(size 1.27 1.27)
						(thickness 0.15)
					)
					(justify left bottom)
					(hide yes)
				)
			)
			(property "Datasheet" ""
				(at 8.89 -12.7 0)
				(effects
					(font
						(size 1.27 1.27)
						(thickness 0.15)
					)
					(justify left bottom)
					(hide yes)
				)
			)
			(property "Description" ""
				(at 0 0 0)
				(effects
					(font
						(size 1.27 1.27)
					)
					(hide yes)
				)
			)
			(property "Author" "Antmicro"
				(at 8.89 -7.62 0)
				(effects
					(font
						(size 1.27 1.27)
						(thickness 0.15)
					)
					(justify left bottom)
					(hide yes)
				)
			)
			(property "License" "Apache-2.0"
				(at 8.89 -10.16 0)
				(effects
					(font
						(size 1.27 1.27)
						(thickness 0.15)
					)
					(justify left bottom)
					(hide yes)
				)
			)
			(symbol "GND_1_1"
				(polyline
					(pts
						(xy 0 0) (xy 0 -1.27) (xy 1.27 -1.27) (xy 0 -2.54) (xy -1.27 -1.27) (xy 0 -1.27)
					)
					(stroke
						(width 0)
						(type default)
					)
					(fill
						(type none)
					)
				)
				(pin power_in line
					(at 0 0 270)
					(length 0)
					(name "GND"
						(effects
							(font
								(size 1.27 1.27)
							)
						)
					)
					(number "1"
						(effects
							(font
								(size 1.27 1.27)
							)
						)
					)
				)
			)
		)
	(symbol "antmicropower:PWR_FLAG"
			(power)
			(pin_numbers
				(hide yes)
			)
			(pin_names
				(offset 0)
				(hide yes)
			)
			(exclude_from_sim no)
			(in_bom yes)
			(on_board yes)
			(property "Reference" "#FLG"
				(at 0 1.905 0)
				(effects
					(font
						(size 1.27 1.27)
					)
					(hide yes)
				)
			)
			(property "Value" "PWR_FLAG"
				(at 0 3.81 0)
				(effects
					(font
						(size 1.27 1.27)
					)
				)
			)
			(property "Footprint" ""
				(at 0 0 0)
				(effects
					(font
						(size 1.27 1.27)
					)
					(hide yes)
				)
			)
			(property "Datasheet" ""
				(at 0 0 0)
				(effects
					(font
						(size 1.27 1.27)
					)
					(hide yes)
				)
			)
			(property "Description" ""
				(at 0 0 0)
				(effects
					(font
						(size 1.27 1.27)
					)
					(hide yes)
				)
			)
			(symbol "PWR_FLAG_0_0"
				(pin power_out line
					(at 0 0 90)
					(length 0)
					(name "pwr"
						(effects
							(font
								(size 1.27 1.27)
							)
						)
					)
					(number "1"
						(effects
							(font
								(size 1.27 1.27)
							)
						)
					)
				)
			)
			(symbol "PWR_FLAG_0_1"
				(polyline
					(pts
						(xy 0 0) (xy 0 1.27) (xy -1.016 1.905) (xy 0 2.54) (xy 1.016 1.905) (xy 0 1.27)
					)
					(stroke
						(width 0)
						(type default)
					)
					(fill
						(type none)
					)
				)
			)
		)
	(symbol "antmicropower:VCC"
			(power)
			(pin_names
				(offset 0)
			)
			(exclude_from_sim no)
			(in_bom yes)
			(on_board yes)
			(property "Reference" "#PWR"
				(at 0 -3.81 0)
				(effects
					(font
						(size 1.27 1.27)
					)
					(hide yes)
				)
			)
			(property "Value" "VCC"
				(at 0 3.81 0)
				(effects
					(font
						(size 1.27 1.27)
					)
				)
			)
			(property "Footprint" ""
				(at 0 0 0)
				(effects
					(font
						(size 1.27 1.27)
					)
					(hide yes)
				)
			)
			(property "Datasheet" ""
				(at 0 0 0)
				(effects
					(font
						(size 1.27 1.27)
					)
					(hide yes)
				)
			)
			(property "Description" ""
				(at 0 0 0)
				(effects
					(font
						(size 1.27 1.27)
					)
					(hide yes)
				)
			)
			(symbol "VCC_0_1"
				(polyline
					(pts
						(xy -0.762 1.27) (xy 0 2.54)
					)
					(stroke
						(width 0)
						(type default)
					)
					(fill
						(type none)
					)
				)
				(polyline
					(pts
						(xy 0 2.54) (xy 0.762 1.27)
					)
					(stroke
						(width 0)
						(type default)
					)
					(fill
						(type none)
					)
				)
				(polyline
					(pts
						(xy 0 0) (xy 0 2.54)
					)
					(stroke
						(width 0)
						(type default)
					)
					(fill
						(type none)
					)
				)
			)
			(symbol "VCC_1_1"
				(pin power_in line
					(at 0 0 90)
					(length 0)
					(hide yes)
					(name "VCC"
						(effects
							(font
								(size 1.27 1.27)
							)
						)
					)
					(number "1"
						(effects
							(font
								(size 1.27 1.27)
							)
						)
					)
				)
			)
		)
)
